G04 ================== begin FILE IDENTIFICATION RECORD ==================*
G04 Layout Name:  D:/<user>/Wistron_project/16342-2/gbr/16342-2.brd*
G04 Film Name:    16342-2_X_Y*
G04 File Format:  Gerber RS274X*
G04 File Origin:  Cadence Allegro 16.5-S056*
G04 Origin Date:  Mon Aug 07 11:24:03 2017*
G04 *
G04 Layer:  BOARD GEOMETRY/PANEL_DRAWING*
G04 *
G04 Offset:    (0.00 0.00)*
G04 Mirror:    No*
G04 Mode:      Positive*
G04 Rotation:  0*
G04 FullContactRelief:  No*
G04 UndefLineWidth:     6.00*
G04 ================== end FILE IDENTIFICATION RECORD ====================*
%FSLAX35Y35*MOIN*%
%IR0*IPPOS*OFA0.00000B0.00000*MIA0B0*SFA1.00000B1.00000*%
%ADD10C,.006*%
G75*
%LPD*%
G75*
G54D10*
G01X-1914847Y-609933D02*
X-1914136Y-611069D01*
X-1913284Y-611826D01*
X-1912290Y-612205D01*
X-1911154Y-611826D01*
X-1910302Y-611069D01*
X-1909449Y-609933D01*
X-1909165Y-608418D01*
Y-600843D01*
G01X-1913710Y-384961D02*
X-1910302D01*
G01X-1912006D02*
Y-396323D01*
G01X-1913710D02*
X-1910302D01*
G01X-1914989Y-180631D02*
Y-169269D01*
G01X-1909023D02*
Y-180631D01*
G01Y-174950D02*
X-1914989D01*
G01X-1911154Y40932D02*
X-1908313D01*
Y37523D01*
X-1909165Y36387D01*
X-1910160Y35630D01*
X-1911580Y35251D01*
X-1913000Y35630D01*
X-1913994Y36387D01*
X-1914847Y37523D01*
X-1915415Y38849D01*
X-1915699Y40364D01*
Y41689D01*
X-1915415Y42825D01*
X-1914847Y44151D01*
X-1913994Y45287D01*
X-1913142Y46045D01*
X-1912006Y46613D01*
X-1911012D01*
X-1909876Y46234D01*
X-1909023Y45477D01*
G01X-1915083Y251323D02*
Y262685D01*
X-1909685D01*
G01X-1911674Y257193D02*
X-1915083D01*
G01X-1909165Y467394D02*
X-1914847D01*
Y478756D01*
X-1909165D01*
G01X-1911438Y473264D02*
X-1914847D01*
G01X-1915131Y683086D02*
Y694448D01*
X-1912290D01*
X-1911154Y693880D01*
X-1910302Y693122D01*
X-1909591Y691986D01*
X-1909023Y690660D01*
X-1908881Y688767D01*
X-1909023Y686873D01*
X-1909591Y685548D01*
X-1910302Y684411D01*
X-1911154Y683654D01*
X-1912290Y683086D01*
X-1915131D01*
G01X-1908881Y909573D02*
X-1909734Y910141D01*
X-1910728Y910520D01*
X-1911864D01*
X-1913142Y909952D01*
X-1914136Y909005D01*
X-1914847Y907869D01*
X-1915415Y905975D01*
X-1915557Y904271D01*
X-1915273Y902567D01*
X-1914847Y901430D01*
X-1913994Y900294D01*
X-1913000Y899537D01*
X-1912006Y899158D01*
X-1911012D01*
X-1910018Y899537D01*
X-1909165Y900105D01*
X-1908455Y900862D01*
G01X-1910870Y1120910D02*
X-1910302Y1121478D01*
X-1909876Y1122424D01*
X-1909591Y1123750D01*
X-1909876Y1124886D01*
X-1910444Y1125644D01*
X-1911438Y1126212D01*
X-1915273D01*
Y1114850D01*
X-1910586D01*
X-1909591Y1115607D01*
X-1909023Y1116744D01*
X-1908739Y1118069D01*
X-1909023Y1119395D01*
X-1909876Y1120531D01*
X-1910870Y1120910D01*
X-1915273D01*
G01X-1915557Y1330732D02*
X-1912006Y1342094D01*
X-1908455Y1330732D01*
G01X-1909734Y1334709D02*
X-1914279D01*
G01X-1785128Y-729615D02*
Y-718253D01*
X-1786832Y-720525D01*
G01Y-729615D02*
X-1783424D01*
G01X-1778761Y1094118D02*
X-1779844Y1095562D01*
X-1780385Y1097005D01*
Y1102779D01*
X-1779844Y1104223D01*
X-1778761Y1105666D01*
G01X-1772049Y1097005D02*
Y1105666D01*
X-1767069Y1097005D01*
Y1105666D01*
G01X-1760898Y1097005D02*
X-1761764Y1097149D01*
X-1762522Y1097727D01*
X-1763172Y1098593D01*
X-1763605Y1099603D01*
X-1763821Y1100758D01*
Y1101913D01*
X-1763605Y1103068D01*
X-1763172Y1104078D01*
X-1762522Y1104944D01*
X-1761764Y1105522D01*
X-1760898Y1105666D01*
X-1760032Y1105522D01*
X-1759274Y1104944D01*
X-1758624Y1104078D01*
X-1758191Y1103068D01*
X-1757975Y1101913D01*
Y1100758D01*
X-1758191Y1099603D01*
X-1758624Y1098593D01*
X-1759274Y1097727D01*
X-1760032Y1097149D01*
X-1760898Y1097005D01*
G01X-1743576Y1105666D02*
Y1097005D01*
G01X-1746066Y1105666D02*
X-1741086D01*
G01X-1737080Y1097005D02*
Y1105666D01*
X-1734374D01*
X-1733508Y1105233D01*
X-1732966Y1104656D01*
X-1732750Y1103501D01*
X-1732966Y1102346D01*
X-1733616Y1101624D01*
X-1734374Y1101191D01*
X-1737080D01*
G01X-1734374D02*
X-1732750Y1097005D01*
G01X-1728961D02*
X-1726254Y1105666D01*
X-1723547Y1097005D01*
G01X-1724522Y1100036D02*
X-1727986D01*
G01X-1715211Y1104944D02*
X-1715861Y1105377D01*
X-1716619Y1105666D01*
X-1717485D01*
X-1718459Y1105233D01*
X-1719217Y1104511D01*
X-1719758Y1103645D01*
X-1720192Y1102202D01*
X-1720300Y1100902D01*
X-1720083Y1099603D01*
X-1719758Y1098737D01*
X-1719109Y1097871D01*
X-1718351Y1097294D01*
X-1717593Y1097005D01*
X-1716835D01*
X-1716077Y1097294D01*
X-1715428Y1097727D01*
X-1714886Y1098304D01*
G01X-1706767Y1097005D02*
X-1711097D01*
Y1105666D01*
X-1706767D01*
G01X-1708499Y1101480D02*
X-1711097D01*
G01X-1694317Y1097005D02*
X-1691610Y1105666D01*
X-1688903Y1097005D01*
G01X-1689878Y1100036D02*
X-1693342D01*
G01X-1682949Y1105666D02*
Y1097005D01*
G01X-1685439Y1105666D02*
X-1680459D01*
G01X-1668334Y1097005D02*
X-1665627Y1105666D01*
X-1662920Y1097005D01*
G01X-1663895Y1100036D02*
X-1667359D01*
G01X-1659131Y1105666D02*
Y1097005D01*
X-1654801D01*
G01X-1650470Y1105666D02*
Y1097005D01*
X-1646140D01*
G01X-1633148Y1105666D02*
Y1097005D01*
X-1628818D01*
G01X-1625029D02*
X-1622322Y1105666D01*
X-1619615Y1097005D01*
G01X-1620590Y1100036D02*
X-1624054D01*
G01X-1613661Y1097005D02*
Y1100902D01*
X-1615826Y1105666D01*
G01X-1611496D02*
X-1613661Y1100902D01*
G01X-1602835Y1097005D02*
X-1607165D01*
Y1105666D01*
X-1602835D01*
G01X-1604567Y1101480D02*
X-1607165D01*
G01X-1598504Y1097005D02*
Y1105666D01*
X-1595798D01*
X-1594932Y1105233D01*
X-1594390Y1104656D01*
X-1594174Y1103501D01*
X-1594390Y1102346D01*
X-1595040Y1101624D01*
X-1595798Y1101191D01*
X-1598504D01*
G01X-1595798D02*
X-1594174Y1097005D01*
G01X-1589952Y1098160D02*
X-1589085Y1097438D01*
X-1588111Y1097005D01*
X-1587245D01*
X-1586379Y1097438D01*
X-1585729Y1098160D01*
X-1585404Y1099170D01*
X-1585621Y1100181D01*
X-1586162Y1101047D01*
X-1587137Y1101624D01*
X-1588436Y1101913D01*
X-1589194Y1102490D01*
X-1589519Y1103501D01*
X-1589302Y1104511D01*
X-1588761Y1105233D01*
X-1588003Y1105666D01*
X-1587245D01*
X-1586487Y1105377D01*
X-1585837Y1104656D01*
G01X-1568191Y1097005D02*
X-1572521D01*
Y1105666D01*
X-1568191D01*
G01X-1569923Y1101480D02*
X-1572521D01*
G01X-1563969Y1097005D02*
X-1559421Y1105666D01*
G01X-1563969D02*
X-1559421Y1097005D01*
G01X-1550652Y1104944D02*
X-1551302Y1105377D01*
X-1552060Y1105666D01*
X-1552926D01*
X-1553900Y1105233D01*
X-1554658Y1104511D01*
X-1555199Y1103645D01*
X-1555633Y1102202D01*
X-1555741Y1100902D01*
X-1555524Y1099603D01*
X-1555199Y1098737D01*
X-1554550Y1097871D01*
X-1553792Y1097294D01*
X-1553034Y1097005D01*
X-1552276D01*
X-1551518Y1097294D01*
X-1550869Y1097727D01*
X-1550327Y1098304D01*
G01X-1542208Y1097005D02*
X-1546538D01*
Y1105666D01*
X-1542208D01*
G01X-1543940Y1101480D02*
X-1546538D01*
G01X-1537877Y1097005D02*
Y1105666D01*
X-1535279D01*
X-1534413Y1105233D01*
X-1533763Y1104223D01*
X-1533547Y1103068D01*
X-1533763Y1101913D01*
X-1534305Y1101047D01*
X-1535279Y1100614D01*
X-1537877D01*
G01X-1527051Y1105666D02*
Y1097005D01*
G01X-1529541Y1105666D02*
X-1524561D01*
G01X-1509079Y1101335D02*
X-1506914D01*
Y1098737D01*
X-1507564Y1097871D01*
X-1508322Y1097294D01*
X-1509404Y1097005D01*
X-1510487Y1097294D01*
X-1511245Y1097871D01*
X-1511894Y1098737D01*
X-1512328Y1099748D01*
X-1512544Y1100902D01*
Y1101913D01*
X-1512328Y1102779D01*
X-1511894Y1103790D01*
X-1511245Y1104656D01*
X-1510595Y1105233D01*
X-1509729Y1105666D01*
X-1508971D01*
X-1508105Y1105377D01*
X-1507455Y1104800D01*
G01X-1503558Y1097005D02*
Y1105666D01*
X-1498578Y1097005D01*
Y1105666D01*
G01X-1494789Y1097005D02*
Y1105666D01*
X-1492624D01*
X-1491757Y1105233D01*
X-1491108Y1104656D01*
X-1490566Y1103790D01*
X-1490133Y1102779D01*
X-1490025Y1101335D01*
X-1490133Y1099892D01*
X-1490566Y1098881D01*
X-1491108Y1098015D01*
X-1491757Y1097438D01*
X-1492624Y1097005D01*
X-1494789D01*
G01X-1483205Y1094118D02*
X-1482122Y1095562D01*
X-1481581Y1097005D01*
Y1102779D01*
X-1482122Y1104223D01*
X-1483205Y1105666D01*
G01X-1782780Y1097005D02*
X-1782563Y1098881D01*
X-1782238Y1100469D01*
X-1781805Y1101913D01*
X-1781264Y1103501D01*
X-1780398Y1105666D01*
X-1784728D01*
G01X-1773902Y1096716D02*
X-1774119Y1096861D01*
Y1097149D01*
X-1773902Y1097294D01*
X-1773685Y1097149D01*
Y1096861D01*
X-1773902Y1096716D01*
G01X-1767623Y1098304D02*
X-1766973Y1097582D01*
X-1766215Y1097149D01*
X-1765241Y1097005D01*
X-1764267Y1097294D01*
X-1763509Y1097871D01*
X-1762967Y1098881D01*
X-1762859Y1100036D01*
X-1763076Y1101191D01*
X-1763617Y1101913D01*
X-1764375Y1102490D01*
X-1765133Y1102635D01*
X-1765891Y1102490D01*
X-1766865Y1101913D01*
X-1766540Y1105666D01*
X-1763617D01*
G01X-1756580D02*
X-1757446Y1105377D01*
X-1758096Y1104656D01*
X-1758529Y1103790D01*
X-1758854Y1102635D01*
X-1758962Y1101335D01*
X-1758854Y1100036D01*
X-1758529Y1098881D01*
X-1758096Y1098015D01*
X-1757446Y1097294D01*
X-1756580Y1097005D01*
X-1755714Y1097294D01*
X-1755064Y1098015D01*
X-1754631Y1098881D01*
X-1754306Y1100036D01*
X-1754198Y1101335D01*
X-1754306Y1102635D01*
X-1754631Y1103790D01*
X-1755064Y1104656D01*
X-1755714Y1105377D01*
X-1756580Y1105666D01*
G01X-1789603Y1097005D02*
Y1102779D01*
G01Y1101335D02*
X-1789169Y1102057D01*
X-1788520Y1102635D01*
X-1787654Y1102779D01*
X-1786896Y1102635D01*
X-1786246Y1102057D01*
X-1785921Y1101047D01*
Y1097005D01*
G01X-1785128Y1448141D02*
Y1459503D01*
X-1786832Y1457231D01*
G01Y1448141D02*
X-1783424D01*
G01X-1668634Y-518509D02*
X-1669500Y-518798D01*
X-1670150Y-519519D01*
X-1670583Y-520385D01*
X-1670908Y-521540D01*
X-1671016Y-522840D01*
X-1670908Y-524139D01*
X-1670583Y-525294D01*
X-1670150Y-526160D01*
X-1669500Y-526881D01*
X-1668634Y-527170D01*
X-1667768Y-526881D01*
X-1667118Y-526160D01*
X-1666685Y-525294D01*
X-1666360Y-524139D01*
X-1666252Y-522840D01*
X-1666360Y-521540D01*
X-1666685Y-520385D01*
X-1667118Y-519519D01*
X-1667768Y-518798D01*
X-1668634Y-518509D01*
G01X-1659973Y-527459D02*
X-1660190Y-527314D01*
Y-527026D01*
X-1659973Y-526881D01*
X-1659756Y-527026D01*
Y-527314D01*
X-1659973Y-527459D01*
G01X-1651312Y-518509D02*
X-1652178Y-518798D01*
X-1652828Y-519519D01*
X-1653261Y-520385D01*
X-1653586Y-521540D01*
X-1653694Y-522840D01*
X-1653586Y-524139D01*
X-1653261Y-525294D01*
X-1652828Y-526160D01*
X-1652178Y-526881D01*
X-1651312Y-527170D01*
X-1650446Y-526881D01*
X-1649796Y-526160D01*
X-1649363Y-525294D01*
X-1649038Y-524139D01*
X-1648930Y-522840D01*
X-1649038Y-521540D01*
X-1649363Y-520385D01*
X-1649796Y-519519D01*
X-1650446Y-518798D01*
X-1651312Y-518509D01*
G01X-1642651D02*
X-1643517Y-518798D01*
X-1644167Y-519519D01*
X-1644600Y-520385D01*
X-1644925Y-521540D01*
X-1645033Y-522840D01*
X-1644925Y-524139D01*
X-1644600Y-525294D01*
X-1644167Y-526160D01*
X-1643517Y-526881D01*
X-1642651Y-527170D01*
X-1641785Y-526881D01*
X-1641135Y-526160D01*
X-1640702Y-525294D01*
X-1640377Y-524139D01*
X-1640269Y-522840D01*
X-1640377Y-521540D01*
X-1640702Y-520385D01*
X-1641135Y-519519D01*
X-1641785Y-518798D01*
X-1642651Y-518509D01*
G01X-1656322Y581178D02*
X-1655672Y582043D01*
X-1654915Y582477D01*
X-1654048Y582621D01*
X-1652966Y582332D01*
X-1652208Y581611D01*
X-1651991Y580745D01*
X-1652100Y579878D01*
X-1652533Y579157D01*
X-1654698Y577713D01*
X-1655672Y576703D01*
X-1656322Y575259D01*
X-1656539Y573960D01*
X-1651991D01*
G01X-1647986Y575259D02*
X-1647336Y574537D01*
X-1646578Y574104D01*
X-1645604Y573960D01*
X-1644630Y574249D01*
X-1643872Y574826D01*
X-1643330Y575836D01*
X-1643222Y576991D01*
X-1643439Y578146D01*
X-1643980Y578868D01*
X-1644738Y579445D01*
X-1645496Y579590D01*
X-1646254Y579445D01*
X-1647228Y578868D01*
X-1646903Y582621D01*
X-1643980D01*
G01X-1636943Y573671D02*
X-1637160Y573816D01*
Y574104D01*
X-1636943Y574249D01*
X-1636726Y574104D01*
Y573816D01*
X-1636943Y573671D01*
G01X-1628282Y582621D02*
X-1629148Y582332D01*
X-1629798Y581611D01*
X-1630231Y580745D01*
X-1630556Y579590D01*
X-1630664Y578290D01*
X-1630556Y576991D01*
X-1630231Y575836D01*
X-1629798Y574970D01*
X-1629148Y574249D01*
X-1628282Y573960D01*
X-1627416Y574249D01*
X-1626766Y574970D01*
X-1626333Y575836D01*
X-1626008Y576991D01*
X-1625900Y578290D01*
X-1626008Y579590D01*
X-1626333Y580745D01*
X-1626766Y581611D01*
X-1627416Y582332D01*
X-1628282Y582621D01*
G01X-1619621D02*
X-1620487Y582332D01*
X-1621137Y581611D01*
X-1621570Y580745D01*
X-1621895Y579590D01*
X-1622003Y578290D01*
X-1621895Y576991D01*
X-1621570Y575836D01*
X-1621137Y574970D01*
X-1620487Y574249D01*
X-1619621Y573960D01*
X-1618755Y574249D01*
X-1618105Y574970D01*
X-1617672Y575836D01*
X-1617347Y576991D01*
X-1617239Y578290D01*
X-1617347Y579590D01*
X-1617672Y580745D01*
X-1618105Y581611D01*
X-1618755Y582332D01*
X-1619621Y582621D01*
G01X-1656322Y717530D02*
X-1655564Y718540D01*
X-1654915Y719118D01*
X-1654048Y719406D01*
X-1653291Y719118D01*
X-1652749Y718540D01*
X-1652316Y717674D01*
X-1652208Y716664D01*
X-1652316Y715797D01*
X-1652749Y714931D01*
X-1653399Y714210D01*
X-1654157Y713921D01*
X-1655023Y714210D01*
X-1655781Y715076D01*
X-1656214Y716375D01*
X-1656322Y717818D01*
X-1656106Y719695D01*
X-1655781Y720706D01*
X-1655239Y721716D01*
X-1654482Y722438D01*
X-1653724Y722582D01*
X-1652966Y722293D01*
X-1652424Y721572D01*
G01X-1645604Y722582D02*
X-1646470Y722293D01*
X-1647120Y721572D01*
X-1647553Y720706D01*
X-1647878Y719551D01*
X-1647986Y718251D01*
X-1647878Y716952D01*
X-1647553Y715797D01*
X-1647120Y714931D01*
X-1646470Y714210D01*
X-1645604Y713921D01*
X-1644738Y714210D01*
X-1644088Y714931D01*
X-1643655Y715797D01*
X-1643330Y716952D01*
X-1643222Y718251D01*
X-1643330Y719551D01*
X-1643655Y720706D01*
X-1644088Y721572D01*
X-1644738Y722293D01*
X-1645604Y722582D01*
G01X-1636943Y713632D02*
X-1637160Y713777D01*
Y714065D01*
X-1636943Y714210D01*
X-1636726Y714065D01*
Y713777D01*
X-1636943Y713632D01*
G01X-1630664Y715220D02*
X-1630014Y714498D01*
X-1629256Y714065D01*
X-1628282Y713921D01*
X-1627308Y714210D01*
X-1626550Y714787D01*
X-1626008Y715797D01*
X-1625900Y716952D01*
X-1626117Y718107D01*
X-1626658Y718829D01*
X-1627416Y719406D01*
X-1628174Y719551D01*
X-1628932Y719406D01*
X-1629906Y718829D01*
X-1629581Y722582D01*
X-1626658D01*
G01X-1622003Y715220D02*
X-1621353Y714498D01*
X-1620595Y714065D01*
X-1619621Y713921D01*
X-1618647Y714210D01*
X-1617889Y714787D01*
X-1617347Y715797D01*
X-1617239Y716952D01*
X-1617456Y718107D01*
X-1617997Y718829D01*
X-1618755Y719406D01*
X-1619513Y719551D01*
X-1620271Y719406D01*
X-1621245Y718829D01*
X-1620920Y722582D01*
X-1617997D01*
G01X-1662926Y889117D02*
Y897778D01*
X-1664225Y896046D01*
G01Y889117D02*
X-1661627D01*
G01X-1654265Y897778D02*
X-1655131Y897489D01*
X-1655781Y896768D01*
X-1656214Y895902D01*
X-1656539Y894747D01*
X-1656647Y893447D01*
X-1656539Y892148D01*
X-1656214Y890993D01*
X-1655781Y890127D01*
X-1655131Y889406D01*
X-1654265Y889117D01*
X-1653399Y889406D01*
X-1652749Y890127D01*
X-1652316Y890993D01*
X-1651991Y892148D01*
X-1651883Y893447D01*
X-1651991Y894747D01*
X-1652316Y895902D01*
X-1652749Y896768D01*
X-1653399Y897489D01*
X-1654265Y897778D01*
G01X-1647986Y890416D02*
X-1647336Y889694D01*
X-1646578Y889261D01*
X-1645604Y889117D01*
X-1644630Y889406D01*
X-1643872Y889983D01*
X-1643330Y890993D01*
X-1643222Y892148D01*
X-1643439Y893303D01*
X-1643980Y894025D01*
X-1644738Y894602D01*
X-1645496Y894747D01*
X-1646254Y894602D01*
X-1647228Y894025D01*
X-1646903Y897778D01*
X-1643980D01*
G01X-1636943Y888828D02*
X-1637160Y888973D01*
Y889261D01*
X-1636943Y889406D01*
X-1636726Y889261D01*
Y888973D01*
X-1636943Y888828D01*
G01X-1628282Y897778D02*
X-1629148Y897489D01*
X-1629798Y896768D01*
X-1630231Y895902D01*
X-1630556Y894747D01*
X-1630664Y893447D01*
X-1630556Y892148D01*
X-1630231Y890993D01*
X-1629798Y890127D01*
X-1629148Y889406D01*
X-1628282Y889117D01*
X-1627416Y889406D01*
X-1626766Y890127D01*
X-1626333Y890993D01*
X-1626008Y892148D01*
X-1625900Y893447D01*
X-1626008Y894747D01*
X-1626333Y895902D01*
X-1626766Y896768D01*
X-1627416Y897489D01*
X-1628282Y897778D01*
G01X-1622003Y890416D02*
X-1621353Y889694D01*
X-1620595Y889261D01*
X-1619621Y889117D01*
X-1618647Y889406D01*
X-1617889Y889983D01*
X-1617347Y890993D01*
X-1617239Y892148D01*
X-1617456Y893303D01*
X-1617997Y894025D01*
X-1618755Y894602D01*
X-1619513Y894747D01*
X-1620271Y894602D01*
X-1621245Y894025D01*
X-1620920Y897778D01*
X-1617997D01*
G01X-1662926Y947976D02*
Y956637D01*
X-1664225Y954905D01*
G01Y947976D02*
X-1661627D01*
G01X-1656322Y955194D02*
X-1655672Y956059D01*
X-1654915Y956493D01*
X-1654048Y956637D01*
X-1652966Y956348D01*
X-1652208Y955627D01*
X-1651991Y954761D01*
X-1652100Y953894D01*
X-1652533Y953173D01*
X-1654698Y951729D01*
X-1655672Y950719D01*
X-1656322Y949275D01*
X-1656539Y947976D01*
X-1651991D01*
G01X-1645604Y956637D02*
X-1646470Y956348D01*
X-1647120Y955627D01*
X-1647553Y954761D01*
X-1647878Y953606D01*
X-1647986Y952306D01*
X-1647878Y951007D01*
X-1647553Y949852D01*
X-1647120Y948986D01*
X-1646470Y948265D01*
X-1645604Y947976D01*
X-1644738Y948265D01*
X-1644088Y948986D01*
X-1643655Y949852D01*
X-1643330Y951007D01*
X-1643222Y952306D01*
X-1643330Y953606D01*
X-1643655Y954761D01*
X-1644088Y955627D01*
X-1644738Y956348D01*
X-1645604Y956637D01*
G01X-1636943Y947687D02*
X-1637160Y947832D01*
Y948120D01*
X-1636943Y948265D01*
X-1636726Y948120D01*
Y947832D01*
X-1636943Y947687D01*
G01X-1628282Y956637D02*
X-1629148Y956348D01*
X-1629798Y955627D01*
X-1630231Y954761D01*
X-1630556Y953606D01*
X-1630664Y952306D01*
X-1630556Y951007D01*
X-1630231Y949852D01*
X-1629798Y948986D01*
X-1629148Y948265D01*
X-1628282Y947976D01*
X-1627416Y948265D01*
X-1626766Y948986D01*
X-1626333Y949852D01*
X-1626008Y951007D01*
X-1625900Y952306D01*
X-1626008Y953606D01*
X-1626333Y954761D01*
X-1626766Y955627D01*
X-1627416Y956348D01*
X-1628282Y956637D01*
G01X-1619621D02*
X-1620487Y956348D01*
X-1621137Y955627D01*
X-1621570Y954761D01*
X-1621895Y953606D01*
X-1622003Y952306D01*
X-1621895Y951007D01*
X-1621570Y949852D01*
X-1621137Y948986D01*
X-1620487Y948265D01*
X-1619621Y947976D01*
X-1618755Y948265D01*
X-1618105Y948986D01*
X-1617672Y949852D01*
X-1617347Y951007D01*
X-1617239Y952306D01*
X-1617347Y953606D01*
X-1617672Y954761D01*
X-1618105Y955627D01*
X-1618755Y956348D01*
X-1619621Y956637D01*
G01X-1674423Y1282321D02*
X-1675506Y1283765D01*
X-1676047Y1285208D01*
Y1290982D01*
X-1675506Y1292426D01*
X-1674423Y1293869D01*
G01X-1667386Y1285208D02*
Y1293869D01*
X-1664788D01*
X-1663922Y1293436D01*
X-1663272Y1292426D01*
X-1663056Y1291271D01*
X-1663272Y1290116D01*
X-1663814Y1289250D01*
X-1664788Y1288817D01*
X-1667386D01*
G01X-1656560Y1293869D02*
Y1285208D01*
G01X-1659050Y1293869D02*
X-1654070D01*
G01X-1650173Y1285208D02*
Y1293869D01*
G01X-1645625D02*
Y1285208D01*
G01Y1289538D02*
X-1650173D01*
G01X-1638697Y1282321D02*
X-1637614Y1283765D01*
X-1637073Y1285208D01*
Y1290982D01*
X-1637614Y1292426D01*
X-1638697Y1293869D01*
G01X-1702898Y1285208D02*
Y1293869D01*
X-1706904Y1287662D01*
X-1701490D01*
G01X-1695536Y1284919D02*
X-1695753Y1285064D01*
Y1285352D01*
X-1695536Y1285497D01*
X-1695319Y1285352D01*
Y1285064D01*
X-1695536Y1284919D01*
G01X-1686875Y1293869D02*
X-1687741Y1293580D01*
X-1688391Y1292859D01*
X-1688824Y1291993D01*
X-1689149Y1290838D01*
X-1689257Y1289538D01*
X-1689149Y1288239D01*
X-1688824Y1287084D01*
X-1688391Y1286218D01*
X-1687741Y1285497D01*
X-1686875Y1285208D01*
X-1686009Y1285497D01*
X-1685359Y1286218D01*
X-1684926Y1287084D01*
X-1684601Y1288239D01*
X-1684493Y1289538D01*
X-1684601Y1290838D01*
X-1684926Y1291993D01*
X-1685359Y1292859D01*
X-1686009Y1293580D01*
X-1686875Y1293869D01*
G01X-1678214D02*
X-1679080Y1293580D01*
X-1679730Y1292859D01*
X-1680163Y1291993D01*
X-1680488Y1290838D01*
X-1680596Y1289538D01*
X-1680488Y1288239D01*
X-1680163Y1287084D01*
X-1679730Y1286218D01*
X-1679080Y1285497D01*
X-1678214Y1285208D01*
X-1677348Y1285497D01*
X-1676698Y1286218D01*
X-1676265Y1287084D01*
X-1675940Y1288239D01*
X-1675832Y1289538D01*
X-1675940Y1290838D01*
X-1676265Y1291993D01*
X-1676698Y1292859D01*
X-1677348Y1293580D01*
X-1678214Y1293869D01*
G01X-1711237Y1285208D02*
Y1290982D01*
G01Y1289538D02*
X-1710803Y1290260D01*
X-1710154Y1290838D01*
X-1709288Y1290982D01*
X-1708530Y1290838D01*
X-1707880Y1290260D01*
X-1707555Y1289250D01*
Y1285208D01*
G01X-1662926Y1215692D02*
Y1224353D01*
X-1664225Y1222621D01*
G01Y1215692D02*
X-1661627D01*
G01X-1654265D02*
X-1653507Y1215836D01*
X-1652641Y1216269D01*
X-1652100Y1216991D01*
X-1651883Y1218002D01*
X-1652100Y1219012D01*
X-1652749Y1219878D01*
X-1653724Y1220311D01*
X-1654806D01*
X-1655456Y1220600D01*
X-1655997Y1221322D01*
X-1656214Y1222332D01*
X-1655889Y1223343D01*
X-1655131Y1224064D01*
X-1654265Y1224353D01*
X-1653399Y1224064D01*
X-1652641Y1223343D01*
X-1652316Y1222332D01*
X-1652533Y1221322D01*
X-1653074Y1220600D01*
X-1653724Y1220311D01*
X-1654806D01*
X-1655781Y1219878D01*
X-1656430Y1219012D01*
X-1656647Y1218002D01*
X-1656430Y1216991D01*
X-1655889Y1216269D01*
X-1655023Y1215836D01*
X-1654265Y1215692D01*
G01X-1645604D02*
X-1644846Y1215836D01*
X-1643980Y1216269D01*
X-1643439Y1216991D01*
X-1643222Y1218002D01*
X-1643439Y1219012D01*
X-1644088Y1219878D01*
X-1645063Y1220311D01*
X-1646145D01*
X-1646795Y1220600D01*
X-1647336Y1221322D01*
X-1647553Y1222332D01*
X-1647228Y1223343D01*
X-1646470Y1224064D01*
X-1645604Y1224353D01*
X-1644738Y1224064D01*
X-1643980Y1223343D01*
X-1643655Y1222332D01*
X-1643872Y1221322D01*
X-1644413Y1220600D01*
X-1645063Y1220311D01*
X-1646145D01*
X-1647120Y1219878D01*
X-1647769Y1219012D01*
X-1647986Y1218002D01*
X-1647769Y1216991D01*
X-1647228Y1216269D01*
X-1646362Y1215836D01*
X-1645604Y1215692D01*
G01X-1636943Y1215403D02*
X-1637160Y1215548D01*
Y1215836D01*
X-1636943Y1215981D01*
X-1636726Y1215836D01*
Y1215548D01*
X-1636943Y1215403D01*
G01X-1628282Y1224353D02*
X-1629148Y1224064D01*
X-1629798Y1223343D01*
X-1630231Y1222477D01*
X-1630556Y1221322D01*
X-1630664Y1220022D01*
X-1630556Y1218723D01*
X-1630231Y1217568D01*
X-1629798Y1216702D01*
X-1629148Y1215981D01*
X-1628282Y1215692D01*
X-1627416Y1215981D01*
X-1626766Y1216702D01*
X-1626333Y1217568D01*
X-1626008Y1218723D01*
X-1625900Y1220022D01*
X-1626008Y1221322D01*
X-1626333Y1222477D01*
X-1626766Y1223343D01*
X-1627416Y1224064D01*
X-1628282Y1224353D01*
G01X-1619621D02*
X-1620487Y1224064D01*
X-1621137Y1223343D01*
X-1621570Y1222477D01*
X-1621895Y1221322D01*
X-1622003Y1220022D01*
X-1621895Y1218723D01*
X-1621570Y1217568D01*
X-1621137Y1216702D01*
X-1620487Y1215981D01*
X-1619621Y1215692D01*
X-1618755Y1215981D01*
X-1618105Y1216702D01*
X-1617672Y1217568D01*
X-1617347Y1218723D01*
X-1617239Y1220022D01*
X-1617347Y1221322D01*
X-1617672Y1222477D01*
X-1618105Y1223343D01*
X-1618755Y1224064D01*
X-1619621Y1224353D01*
G01X-1677436Y1217424D02*
X-1676786Y1216414D01*
X-1675920Y1215836D01*
X-1674946Y1215692D01*
X-1674080Y1215836D01*
X-1673213Y1216558D01*
X-1672672Y1217424D01*
X-1672564Y1218290D01*
X-1672780Y1219301D01*
X-1673538Y1220022D01*
X-1674296Y1220311D01*
X-1675271D01*
G01X-1674296D02*
X-1673647Y1220744D01*
X-1673105Y1221466D01*
X-1672889Y1222332D01*
X-1673105Y1223198D01*
X-1673647Y1223920D01*
X-1674621Y1224353D01*
X-1675595Y1224209D01*
X-1676570Y1223631D01*
G01X-1667800Y1218579D02*
X-1664986D01*
G01X-1662926Y1239314D02*
Y1247975D01*
X-1664225Y1246243D01*
G01Y1239314D02*
X-1661627D01*
G01X-1656106Y1240324D02*
X-1655348Y1239603D01*
X-1654482Y1239314D01*
X-1653615Y1239603D01*
X-1652858Y1240469D01*
X-1652316Y1241768D01*
X-1652100Y1243067D01*
Y1244655D01*
X-1652316Y1245954D01*
X-1652858Y1247109D01*
X-1653507Y1247686D01*
X-1654265Y1247975D01*
X-1655131Y1247686D01*
X-1655781Y1247109D01*
X-1656214Y1246243D01*
X-1656430Y1245088D01*
X-1656214Y1244078D01*
X-1655672Y1243067D01*
X-1655023Y1242490D01*
X-1654265Y1242345D01*
X-1653399Y1242634D01*
X-1652749Y1243356D01*
X-1652100Y1244655D01*
G01X-1644305Y1239314D02*
Y1247975D01*
X-1648311Y1241768D01*
X-1642897D01*
G01X-1636943Y1239025D02*
X-1637160Y1239170D01*
Y1239458D01*
X-1636943Y1239603D01*
X-1636726Y1239458D01*
Y1239170D01*
X-1636943Y1239025D01*
G01X-1628282Y1247975D02*
X-1629148Y1247686D01*
X-1629798Y1246965D01*
X-1630231Y1246099D01*
X-1630556Y1244944D01*
X-1630664Y1243644D01*
X-1630556Y1242345D01*
X-1630231Y1241190D01*
X-1629798Y1240324D01*
X-1629148Y1239603D01*
X-1628282Y1239314D01*
X-1627416Y1239603D01*
X-1626766Y1240324D01*
X-1626333Y1241190D01*
X-1626008Y1242345D01*
X-1625900Y1243644D01*
X-1626008Y1244944D01*
X-1626333Y1246099D01*
X-1626766Y1246965D01*
X-1627416Y1247686D01*
X-1628282Y1247975D01*
G01X-1619621D02*
X-1620487Y1247686D01*
X-1621137Y1246965D01*
X-1621570Y1246099D01*
X-1621895Y1244944D01*
X-1622003Y1243644D01*
X-1621895Y1242345D01*
X-1621570Y1241190D01*
X-1621137Y1240324D01*
X-1620487Y1239603D01*
X-1619621Y1239314D01*
X-1618755Y1239603D01*
X-1618105Y1240324D01*
X-1617672Y1241190D01*
X-1617347Y1242345D01*
X-1617239Y1243644D01*
X-1617347Y1244944D01*
X-1617672Y1246099D01*
X-1618105Y1246965D01*
X-1618755Y1247686D01*
X-1619621Y1247975D01*
G01X-1610859Y-597937D02*
X-1610570Y-598803D01*
X-1609849Y-599453D01*
X-1608983Y-599886D01*
X-1607828Y-600211D01*
X-1606528Y-600319D01*
X-1605229Y-600211D01*
X-1604074Y-599886D01*
X-1603208Y-599453D01*
X-1602487Y-598803D01*
X-1602198Y-597937D01*
X-1602487Y-597071D01*
X-1603208Y-596421D01*
X-1604074Y-595988D01*
X-1605229Y-595663D01*
X-1606528Y-595555D01*
X-1607828Y-595663D01*
X-1608983Y-595988D01*
X-1609849Y-596421D01*
X-1610570Y-597071D01*
X-1610859Y-597937D01*
G01X-1601909Y-589276D02*
X-1602054Y-589493D01*
X-1602342D01*
X-1602487Y-589276D01*
X-1602342Y-589059D01*
X-1602054D01*
X-1601909Y-589276D01*
G01X-1610859Y-580615D02*
X-1610570Y-581481D01*
X-1609849Y-582131D01*
X-1608983Y-582564D01*
X-1607828Y-582889D01*
X-1606528Y-582997D01*
X-1605229Y-582889D01*
X-1604074Y-582564D01*
X-1603208Y-582131D01*
X-1602487Y-581481D01*
X-1602198Y-580615D01*
X-1602487Y-579749D01*
X-1603208Y-579099D01*
X-1604074Y-578666D01*
X-1605229Y-578341D01*
X-1606528Y-578233D01*
X-1607828Y-578341D01*
X-1608983Y-578666D01*
X-1609849Y-579099D01*
X-1610570Y-579749D01*
X-1610859Y-580615D01*
G01Y-571954D02*
X-1610570Y-572820D01*
X-1609849Y-573470D01*
X-1608983Y-573903D01*
X-1607828Y-574228D01*
X-1606528Y-574336D01*
X-1605229Y-574228D01*
X-1604074Y-573903D01*
X-1603208Y-573470D01*
X-1602487Y-572820D01*
X-1602198Y-571954D01*
X-1602487Y-571088D01*
X-1603208Y-570438D01*
X-1604074Y-570005D01*
X-1605229Y-569680D01*
X-1606528Y-569572D01*
X-1607828Y-569680D01*
X-1608983Y-570005D01*
X-1609849Y-570438D01*
X-1610570Y-571088D01*
X-1610859Y-571954D01*
G01X-1608979Y398548D02*
X-1608690Y397682D01*
X-1607969Y397032D01*
X-1607103Y396599D01*
X-1605948Y396274D01*
X-1604648Y396166D01*
X-1603349Y396274D01*
X-1602194Y396599D01*
X-1601328Y397032D01*
X-1600607Y397682D01*
X-1600318Y398548D01*
X-1600607Y399414D01*
X-1601328Y400064D01*
X-1602194Y400497D01*
X-1603349Y400822D01*
X-1604648Y400930D01*
X-1605948Y400822D01*
X-1607103Y400497D01*
X-1607969Y400064D01*
X-1608690Y399414D01*
X-1608979Y398548D01*
G01X-1600029Y407209D02*
X-1600174Y406992D01*
X-1600462D01*
X-1600607Y407209D01*
X-1600462Y407426D01*
X-1600174D01*
X-1600029Y407209D01*
G01X-1608979Y415870D02*
X-1608690Y415004D01*
X-1607969Y414354D01*
X-1607103Y413921D01*
X-1605948Y413596D01*
X-1604648Y413488D01*
X-1603349Y413596D01*
X-1602194Y413921D01*
X-1601328Y414354D01*
X-1600607Y415004D01*
X-1600318Y415870D01*
X-1600607Y416736D01*
X-1601328Y417386D01*
X-1602194Y417819D01*
X-1603349Y418144D01*
X-1604648Y418252D01*
X-1605948Y418144D01*
X-1607103Y417819D01*
X-1607969Y417386D01*
X-1608690Y416736D01*
X-1608979Y415870D01*
G01Y424531D02*
X-1608690Y423665D01*
X-1607969Y423015D01*
X-1607103Y422582D01*
X-1605948Y422257D01*
X-1604648Y422149D01*
X-1603349Y422257D01*
X-1602194Y422582D01*
X-1601328Y423015D01*
X-1600607Y423665D01*
X-1600318Y424531D01*
X-1600607Y425397D01*
X-1601328Y426047D01*
X-1602194Y426480D01*
X-1603349Y426805D01*
X-1604648Y426913D01*
X-1605948Y426805D01*
X-1607103Y426480D01*
X-1607969Y426047D01*
X-1608690Y425397D01*
X-1608979Y424531D01*
G01X-1645604Y484196D02*
X-1646470Y483907D01*
X-1647120Y483186D01*
X-1647553Y482320D01*
X-1647878Y481165D01*
X-1647986Y479865D01*
X-1647878Y478566D01*
X-1647553Y477411D01*
X-1647120Y476545D01*
X-1646470Y475824D01*
X-1645604Y475535D01*
X-1644738Y475824D01*
X-1644088Y476545D01*
X-1643655Y477411D01*
X-1643330Y478566D01*
X-1643222Y479865D01*
X-1643330Y481165D01*
X-1643655Y482320D01*
X-1644088Y483186D01*
X-1644738Y483907D01*
X-1645604Y484196D01*
G01X-1636943Y475246D02*
X-1637160Y475391D01*
Y475679D01*
X-1636943Y475824D01*
X-1636726Y475679D01*
Y475391D01*
X-1636943Y475246D01*
G01X-1628282Y484196D02*
X-1629148Y483907D01*
X-1629798Y483186D01*
X-1630231Y482320D01*
X-1630556Y481165D01*
X-1630664Y479865D01*
X-1630556Y478566D01*
X-1630231Y477411D01*
X-1629798Y476545D01*
X-1629148Y475824D01*
X-1628282Y475535D01*
X-1627416Y475824D01*
X-1626766Y476545D01*
X-1626333Y477411D01*
X-1626008Y478566D01*
X-1625900Y479865D01*
X-1626008Y481165D01*
X-1626333Y482320D01*
X-1626766Y483186D01*
X-1627416Y483907D01*
X-1628282Y484196D01*
G01X-1619621D02*
X-1620487Y483907D01*
X-1621137Y483186D01*
X-1621570Y482320D01*
X-1621895Y481165D01*
X-1622003Y479865D01*
X-1621895Y478566D01*
X-1621570Y477411D01*
X-1621137Y476545D01*
X-1620487Y475824D01*
X-1619621Y475535D01*
X-1618755Y475824D01*
X-1618105Y476545D01*
X-1617672Y477411D01*
X-1617347Y478566D01*
X-1617239Y479865D01*
X-1617347Y481165D01*
X-1617672Y482320D01*
X-1618105Y483186D01*
X-1618755Y483907D01*
X-1619621Y484196D01*
G01X-1570051Y-720147D02*
X-1569198Y-719011D01*
X-1568204Y-718442D01*
X-1567068Y-718253D01*
X-1565648Y-718632D01*
X-1564653Y-719579D01*
X-1564369Y-720715D01*
X-1564511Y-721851D01*
X-1565080Y-722798D01*
X-1567920Y-724691D01*
X-1569198Y-726017D01*
X-1570051Y-727911D01*
X-1570335Y-729615D01*
X-1564369D01*
G01X-1542592Y227616D02*
X-1536321Y235942D01*
X-1539856Y237674D01*
X-1542592Y227616D01*
G01X-1517378Y387830D02*
X-1518243Y388480D01*
X-1518677Y389237D01*
X-1518821Y390104D01*
X-1518532Y391186D01*
X-1517811Y391944D01*
X-1516945Y392161D01*
X-1516078Y392052D01*
X-1515357Y391619D01*
X-1513913Y389454D01*
X-1512903Y388480D01*
X-1511459Y387830D01*
X-1510160Y387613D01*
Y392161D01*
G01X-1517378Y396491D02*
X-1518243Y397141D01*
X-1518677Y397898D01*
X-1518821Y398765D01*
X-1518532Y399847D01*
X-1517811Y400605D01*
X-1516945Y400822D01*
X-1516078Y400713D01*
X-1515357Y400280D01*
X-1513913Y398115D01*
X-1512903Y397141D01*
X-1511459Y396491D01*
X-1510160Y396274D01*
Y400822D01*
G01X-1509871Y407209D02*
X-1510016Y406992D01*
X-1510304D01*
X-1510449Y407209D01*
X-1510304Y407426D01*
X-1510016D01*
X-1509871Y407209D01*
G01X-1511170Y414029D02*
X-1510449Y414787D01*
X-1510160Y415653D01*
X-1510449Y416520D01*
X-1511315Y417277D01*
X-1512614Y417819D01*
X-1513913Y418035D01*
X-1515501D01*
X-1516800Y417819D01*
X-1517955Y417277D01*
X-1518532Y416628D01*
X-1518821Y415870D01*
X-1518532Y415004D01*
X-1517955Y414354D01*
X-1517089Y413921D01*
X-1515934Y413705D01*
X-1514924Y413921D01*
X-1513913Y414463D01*
X-1513336Y415112D01*
X-1513191Y415870D01*
X-1513480Y416736D01*
X-1514202Y417386D01*
X-1515501Y418035D01*
G01X-1518821Y424531D02*
X-1518532Y423665D01*
X-1517811Y423015D01*
X-1516945Y422582D01*
X-1515790Y422257D01*
X-1514490Y422149D01*
X-1513191Y422257D01*
X-1512036Y422582D01*
X-1511170Y423015D01*
X-1510449Y423665D01*
X-1510160Y424531D01*
X-1510449Y425397D01*
X-1511170Y426047D01*
X-1512036Y426480D01*
X-1513191Y426805D01*
X-1514490Y426913D01*
X-1515790Y426805D01*
X-1516945Y426480D01*
X-1517811Y426047D01*
X-1518532Y425397D01*
X-1518821Y424531D01*
G01X-1517378Y374836D02*
X-1518243Y375486D01*
X-1518677Y376243D01*
X-1518821Y377110D01*
X-1518532Y378192D01*
X-1517811Y378950D01*
X-1516945Y379167D01*
X-1516078Y379058D01*
X-1515357Y378625D01*
X-1513913Y376460D01*
X-1512903Y375486D01*
X-1511459Y374836D01*
X-1510160Y374619D01*
Y379167D01*
G01X-1513047Y384147D02*
Y386961D01*
G01X-1529452Y389887D02*
X-1538113D01*
X-1536381Y388588D01*
G01X-1529452D02*
Y391186D01*
G01Y398548D02*
X-1529596Y399306D01*
X-1530029Y400172D01*
X-1530751Y400713D01*
X-1531762Y400930D01*
X-1532772Y400713D01*
X-1533638Y400064D01*
X-1534071Y399089D01*
Y398007D01*
X-1534360Y397357D01*
X-1535082Y396816D01*
X-1536092Y396599D01*
X-1537103Y396924D01*
X-1537824Y397682D01*
X-1538113Y398548D01*
X-1537824Y399414D01*
X-1537103Y400172D01*
X-1536092Y400497D01*
X-1535082Y400280D01*
X-1534360Y399739D01*
X-1534071Y399089D01*
Y398007D01*
X-1533638Y397032D01*
X-1532772Y396383D01*
X-1531762Y396166D01*
X-1530751Y396383D01*
X-1530029Y396924D01*
X-1529596Y397790D01*
X-1529452Y398548D01*
G01X-1529163Y407209D02*
X-1529308Y406992D01*
X-1529596D01*
X-1529741Y407209D01*
X-1529596Y407426D01*
X-1529308D01*
X-1529163Y407209D01*
G01X-1538113Y415870D02*
X-1537824Y415004D01*
X-1537103Y414354D01*
X-1536237Y413921D01*
X-1535082Y413596D01*
X-1533782Y413488D01*
X-1532483Y413596D01*
X-1531328Y413921D01*
X-1530462Y414354D01*
X-1529741Y415004D01*
X-1529452Y415870D01*
X-1529741Y416736D01*
X-1530462Y417386D01*
X-1531328Y417819D01*
X-1532483Y418144D01*
X-1533782Y418252D01*
X-1535082Y418144D01*
X-1536237Y417819D01*
X-1537103Y417386D01*
X-1537824Y416736D01*
X-1538113Y415870D01*
G01Y424531D02*
X-1537824Y423665D01*
X-1537103Y423015D01*
X-1536237Y422582D01*
X-1535082Y422257D01*
X-1533782Y422149D01*
X-1532483Y422257D01*
X-1531328Y422582D01*
X-1530462Y423015D01*
X-1529741Y423665D01*
X-1529452Y424531D01*
X-1529741Y425397D01*
X-1530462Y426047D01*
X-1531328Y426480D01*
X-1532483Y426805D01*
X-1533782Y426913D01*
X-1535082Y426805D01*
X-1536237Y426480D01*
X-1537103Y426047D01*
X-1537824Y425397D01*
X-1538113Y424531D01*
G01X-1517772Y731148D02*
X-1518637Y731798D01*
X-1519071Y732555D01*
X-1519215Y733422D01*
X-1518926Y734504D01*
X-1518205Y735262D01*
X-1517339Y735479D01*
X-1516472Y735370D01*
X-1515751Y734937D01*
X-1514307Y732772D01*
X-1513297Y731798D01*
X-1511853Y731148D01*
X-1510554Y730931D01*
Y735479D01*
G01X-1517772Y739809D02*
X-1518637Y740459D01*
X-1519071Y741216D01*
X-1519215Y742083D01*
X-1518926Y743165D01*
X-1518205Y743923D01*
X-1517339Y744140D01*
X-1516472Y744031D01*
X-1515751Y743598D01*
X-1514307Y741433D01*
X-1513297Y740459D01*
X-1511853Y739809D01*
X-1510554Y739592D01*
Y744140D01*
G01X-1510265Y750527D02*
X-1510410Y750310D01*
X-1510698D01*
X-1510843Y750527D01*
X-1510698Y750744D01*
X-1510410D01*
X-1510265Y750527D01*
G01X-1510554Y759188D02*
X-1510698Y759946D01*
X-1511131Y760812D01*
X-1511853Y761353D01*
X-1512864Y761570D01*
X-1513874Y761353D01*
X-1514740Y760704D01*
X-1515173Y759729D01*
Y758647D01*
X-1515462Y757997D01*
X-1516184Y757456D01*
X-1517194Y757239D01*
X-1518205Y757564D01*
X-1518926Y758322D01*
X-1519215Y759188D01*
X-1518926Y760054D01*
X-1518205Y760812D01*
X-1517194Y761137D01*
X-1516184Y760920D01*
X-1515462Y760379D01*
X-1515173Y759729D01*
Y758647D01*
X-1514740Y757672D01*
X-1513874Y757023D01*
X-1512864Y756806D01*
X-1511853Y757023D01*
X-1511131Y757564D01*
X-1510698Y758430D01*
X-1510554Y759188D01*
G01X-1519215Y767849D02*
X-1518926Y766983D01*
X-1518205Y766333D01*
X-1517339Y765900D01*
X-1516184Y765575D01*
X-1514884Y765467D01*
X-1513585Y765575D01*
X-1512430Y765900D01*
X-1511564Y766333D01*
X-1510843Y766983D01*
X-1510554Y767849D01*
X-1510843Y768715D01*
X-1511564Y769365D01*
X-1512430Y769798D01*
X-1513585Y770123D01*
X-1514884Y770231D01*
X-1516184Y770123D01*
X-1517339Y769798D01*
X-1518205Y769365D01*
X-1518926Y768715D01*
X-1519215Y767849D01*
G01X-1529452Y986173D02*
X-1538113D01*
X-1536381Y984874D01*
G01X-1529452D02*
Y987472D01*
G01Y994834D02*
X-1529596Y995592D01*
X-1530029Y996458D01*
X-1530751Y996999D01*
X-1531762Y997216D01*
X-1532772Y996999D01*
X-1533638Y996350D01*
X-1534071Y995375D01*
Y994293D01*
X-1534360Y993643D01*
X-1535082Y993102D01*
X-1536092Y992885D01*
X-1537103Y993210D01*
X-1537824Y993968D01*
X-1538113Y994834D01*
X-1537824Y995700D01*
X-1537103Y996458D01*
X-1536092Y996783D01*
X-1535082Y996566D01*
X-1534360Y996025D01*
X-1534071Y995375D01*
Y994293D01*
X-1533638Y993318D01*
X-1532772Y992669D01*
X-1531762Y992452D01*
X-1530751Y992669D01*
X-1530029Y993210D01*
X-1529596Y994076D01*
X-1529452Y994834D01*
G01X-1529163Y1003495D02*
X-1529308Y1003278D01*
X-1529596D01*
X-1529741Y1003495D01*
X-1529596Y1003712D01*
X-1529308D01*
X-1529163Y1003495D01*
G01X-1538113Y1012156D02*
X-1537824Y1011290D01*
X-1537103Y1010640D01*
X-1536237Y1010207D01*
X-1535082Y1009882D01*
X-1533782Y1009774D01*
X-1532483Y1009882D01*
X-1531328Y1010207D01*
X-1530462Y1010640D01*
X-1529741Y1011290D01*
X-1529452Y1012156D01*
X-1529741Y1013022D01*
X-1530462Y1013672D01*
X-1531328Y1014105D01*
X-1532483Y1014430D01*
X-1533782Y1014538D01*
X-1535082Y1014430D01*
X-1536237Y1014105D01*
X-1537103Y1013672D01*
X-1537824Y1013022D01*
X-1538113Y1012156D01*
G01Y1020817D02*
X-1537824Y1019951D01*
X-1537103Y1019301D01*
X-1536237Y1018868D01*
X-1535082Y1018543D01*
X-1533782Y1018435D01*
X-1532483Y1018543D01*
X-1531328Y1018868D01*
X-1530462Y1019301D01*
X-1529741Y1019951D01*
X-1529452Y1020817D01*
X-1529741Y1021683D01*
X-1530462Y1022333D01*
X-1531328Y1022766D01*
X-1532483Y1023091D01*
X-1533782Y1023199D01*
X-1535082Y1023091D01*
X-1536237Y1022766D01*
X-1537103Y1022333D01*
X-1537824Y1021683D01*
X-1538113Y1020817D01*
G01X-1526488Y1144826D02*
Y1153487D01*
X-1527787Y1151755D01*
G01Y1144826D02*
X-1525189D01*
G01X-1518044D02*
X-1517827Y1146702D01*
X-1517502Y1148290D01*
X-1517069Y1149734D01*
X-1516528Y1151322D01*
X-1515662Y1153487D01*
X-1519992D01*
G01X-1509166D02*
X-1510032Y1153198D01*
X-1510682Y1152477D01*
X-1511115Y1151611D01*
X-1511440Y1150456D01*
X-1511548Y1149156D01*
X-1511440Y1147857D01*
X-1511115Y1146702D01*
X-1510682Y1145836D01*
X-1510032Y1145115D01*
X-1509166Y1144826D01*
X-1508300Y1145115D01*
X-1507650Y1145836D01*
X-1507217Y1146702D01*
X-1506892Y1147857D01*
X-1506784Y1149156D01*
X-1506892Y1150456D01*
X-1507217Y1151611D01*
X-1507650Y1152477D01*
X-1508300Y1153198D01*
X-1509166Y1153487D01*
G01X-1500505Y1144537D02*
X-1500722Y1144682D01*
Y1144970D01*
X-1500505Y1145115D01*
X-1500288Y1144970D01*
Y1144682D01*
X-1500505Y1144537D01*
G01X-1491844Y1153487D02*
X-1492710Y1153198D01*
X-1493360Y1152477D01*
X-1493793Y1151611D01*
X-1494118Y1150456D01*
X-1494226Y1149156D01*
X-1494118Y1147857D01*
X-1493793Y1146702D01*
X-1493360Y1145836D01*
X-1492710Y1145115D01*
X-1491844Y1144826D01*
X-1490978Y1145115D01*
X-1490328Y1145836D01*
X-1489895Y1146702D01*
X-1489570Y1147857D01*
X-1489462Y1149156D01*
X-1489570Y1150456D01*
X-1489895Y1151611D01*
X-1490328Y1152477D01*
X-1490978Y1153198D01*
X-1491844Y1153487D01*
G01X-1483183D02*
X-1484049Y1153198D01*
X-1484699Y1152477D01*
X-1485132Y1151611D01*
X-1485457Y1150456D01*
X-1485565Y1149156D01*
X-1485457Y1147857D01*
X-1485132Y1146702D01*
X-1484699Y1145836D01*
X-1484049Y1145115D01*
X-1483183Y1144826D01*
X-1482317Y1145115D01*
X-1481667Y1145836D01*
X-1481234Y1146702D01*
X-1480909Y1147857D01*
X-1480801Y1149156D01*
X-1480909Y1150456D01*
X-1481234Y1151611D01*
X-1481667Y1152477D01*
X-1482317Y1153198D01*
X-1483183Y1153487D01*
G01X-1514339Y1164558D02*
X-1515422Y1166002D01*
X-1515963Y1167445D01*
Y1173219D01*
X-1515422Y1174663D01*
X-1514339Y1176106D01*
G01X-1507302Y1167445D02*
Y1176106D01*
X-1504704D01*
X-1503838Y1175673D01*
X-1503188Y1174663D01*
X-1502972Y1173508D01*
X-1503188Y1172353D01*
X-1503730Y1171487D01*
X-1504704Y1171054D01*
X-1507302D01*
G01X-1496476Y1176106D02*
Y1167445D01*
G01X-1498966Y1176106D02*
X-1493986D01*
G01X-1490089Y1167445D02*
Y1176106D01*
G01X-1485541D02*
Y1167445D01*
G01Y1171775D02*
X-1490089D01*
G01X-1478613Y1164558D02*
X-1477530Y1166002D01*
X-1476989Y1167445D01*
Y1173219D01*
X-1477530Y1174663D01*
X-1478613Y1176106D01*
G01X-1542814Y1167445D02*
Y1176106D01*
X-1546820Y1169899D01*
X-1541406D01*
G01X-1535452Y1167156D02*
X-1535669Y1167301D01*
Y1167589D01*
X-1535452Y1167734D01*
X-1535235Y1167589D01*
Y1167301D01*
X-1535452Y1167156D01*
G01X-1528848Y1174663D02*
X-1528198Y1175528D01*
X-1527441Y1175962D01*
X-1526574Y1176106D01*
X-1525492Y1175817D01*
X-1524734Y1175096D01*
X-1524517Y1174230D01*
X-1524626Y1173363D01*
X-1525059Y1172642D01*
X-1527224Y1171198D01*
X-1528198Y1170188D01*
X-1528848Y1168744D01*
X-1529065Y1167445D01*
X-1524517D01*
G01X-1518130Y1176106D02*
X-1518996Y1175817D01*
X-1519646Y1175096D01*
X-1520079Y1174230D01*
X-1520404Y1173075D01*
X-1520512Y1171775D01*
X-1520404Y1170476D01*
X-1520079Y1169321D01*
X-1519646Y1168455D01*
X-1518996Y1167734D01*
X-1518130Y1167445D01*
X-1517264Y1167734D01*
X-1516614Y1168455D01*
X-1516181Y1169321D01*
X-1515856Y1170476D01*
X-1515748Y1171775D01*
X-1515856Y1173075D01*
X-1516181Y1174230D01*
X-1516614Y1175096D01*
X-1517264Y1175817D01*
X-1518130Y1176106D01*
G01X-1551152Y1167445D02*
Y1173219D01*
G01Y1171775D02*
X-1550718Y1172497D01*
X-1550069Y1173075D01*
X-1549203Y1173219D01*
X-1548445Y1173075D01*
X-1547795Y1172497D01*
X-1547470Y1171487D01*
Y1167445D01*
G01X-1542997Y1231258D02*
X-1537878Y1240338D01*
X-1541611Y1241589D01*
X-1542997Y1231258D01*
G01X-1554723Y1218870D02*
X-1560906Y1227263D01*
X-1563578Y1224371D01*
X-1554723Y1218870D01*
G01X-1551105Y1292570D02*
X-1559766D01*
X-1558034Y1291271D01*
G01X-1551105D02*
Y1293869D01*
G01X-1558323Y1299174D02*
X-1559188Y1299824D01*
X-1559622Y1300581D01*
X-1559766Y1301448D01*
X-1559477Y1302530D01*
X-1558756Y1303288D01*
X-1557890Y1303505D01*
X-1557023Y1303396D01*
X-1556302Y1302963D01*
X-1554858Y1300798D01*
X-1553848Y1299824D01*
X-1552404Y1299174D01*
X-1551105Y1298957D01*
Y1303505D01*
G01X-1550816Y1309892D02*
X-1550961Y1309675D01*
X-1551249D01*
X-1551394Y1309892D01*
X-1551249Y1310109D01*
X-1550961D01*
X-1550816Y1309892D01*
G01X-1552404Y1316171D02*
X-1551682Y1316821D01*
X-1551249Y1317579D01*
X-1551105Y1318553D01*
X-1551394Y1319527D01*
X-1551971Y1320285D01*
X-1552981Y1320827D01*
X-1554136Y1320935D01*
X-1555291Y1320718D01*
X-1556013Y1320177D01*
X-1556590Y1319419D01*
X-1556735Y1318661D01*
X-1556590Y1317903D01*
X-1556013Y1316929D01*
X-1559766Y1317254D01*
Y1320177D01*
G01Y1327214D02*
X-1559477Y1326348D01*
X-1558756Y1325698D01*
X-1557890Y1325265D01*
X-1556735Y1324940D01*
X-1555435Y1324832D01*
X-1554136Y1324940D01*
X-1552981Y1325265D01*
X-1552115Y1325698D01*
X-1551394Y1326348D01*
X-1551105Y1327214D01*
X-1551394Y1328080D01*
X-1552115Y1328730D01*
X-1552981Y1329163D01*
X-1554136Y1329488D01*
X-1555435Y1329596D01*
X-1556735Y1329488D01*
X-1557890Y1329163D01*
X-1558756Y1328730D01*
X-1559477Y1328080D01*
X-1559766Y1327214D01*
G01X-1570051Y1457609D02*
X-1569198Y1458745D01*
X-1568204Y1459314D01*
X-1567068Y1459503D01*
X-1565648Y1459124D01*
X-1564653Y1458177D01*
X-1564369Y1457041D01*
X-1564511Y1455905D01*
X-1565080Y1454958D01*
X-1567920Y1453065D01*
X-1569198Y1451739D01*
X-1570051Y1449845D01*
X-1570335Y1448141D01*
X-1564369D01*
G01X-1448601Y301891D02*
X-1449684Y303335D01*
X-1450225Y304778D01*
Y310552D01*
X-1449684Y311996D01*
X-1448601Y313439D01*
G01X-1441564Y304778D02*
Y313439D01*
X-1438966D01*
X-1438100Y313006D01*
X-1437450Y311996D01*
X-1437234Y310841D01*
X-1437450Y309686D01*
X-1437992Y308820D01*
X-1438966Y308387D01*
X-1441564D01*
G01X-1433445Y304778D02*
X-1430738Y313439D01*
X-1428031Y304778D01*
G01X-1429006Y307809D02*
X-1432470D01*
G01X-1424459Y304778D02*
Y313439D01*
X-1422294D01*
X-1421427Y313006D01*
X-1420778Y312429D01*
X-1420236Y311563D01*
X-1419803Y310552D01*
X-1419695Y309108D01*
X-1419803Y307665D01*
X-1420236Y306654D01*
X-1420778Y305788D01*
X-1421427Y305211D01*
X-1422294Y304778D01*
X-1424459D01*
G01X-1412875Y301891D02*
X-1411792Y303335D01*
X-1411251Y304778D01*
Y310552D01*
X-1411792Y311996D01*
X-1412875Y313439D01*
G01X-1405296Y301891D02*
X-1406379Y303335D01*
X-1406920Y304778D01*
Y310552D01*
X-1406379Y311996D01*
X-1405296Y313439D01*
G01X-1398584Y304778D02*
Y313439D01*
X-1393604Y304778D01*
Y313439D01*
G01X-1387433Y304778D02*
X-1388299Y304922D01*
X-1389057Y305500D01*
X-1389707Y306366D01*
X-1390140Y307376D01*
X-1390356Y308531D01*
Y309686D01*
X-1390140Y310841D01*
X-1389707Y311851D01*
X-1389057Y312717D01*
X-1388299Y313295D01*
X-1387433Y313439D01*
X-1386567Y313295D01*
X-1385809Y312717D01*
X-1385159Y311851D01*
X-1384726Y310841D01*
X-1384510Y309686D01*
Y308531D01*
X-1384726Y307376D01*
X-1385159Y306366D01*
X-1385809Y305500D01*
X-1386567Y304922D01*
X-1387433Y304778D01*
G01X-1370111Y313439D02*
Y304778D01*
G01X-1372601Y313439D02*
X-1367621D01*
G01X-1363615Y304778D02*
Y313439D01*
X-1360909D01*
X-1360043Y313006D01*
X-1359501Y312429D01*
X-1359285Y311274D01*
X-1359501Y310119D01*
X-1360151Y309397D01*
X-1360909Y308964D01*
X-1363615D01*
G01X-1360909D02*
X-1359285Y304778D01*
G01X-1355496D02*
X-1352789Y313439D01*
X-1350082Y304778D01*
G01X-1351057Y307809D02*
X-1354521D01*
G01X-1341746Y312717D02*
X-1342396Y313150D01*
X-1343154Y313439D01*
X-1344020D01*
X-1344994Y313006D01*
X-1345752Y312284D01*
X-1346293Y311418D01*
X-1346727Y309975D01*
X-1346835Y308675D01*
X-1346618Y307376D01*
X-1346293Y306510D01*
X-1345644Y305644D01*
X-1344886Y305067D01*
X-1344128Y304778D01*
X-1343370D01*
X-1342612Y305067D01*
X-1341963Y305500D01*
X-1341421Y306077D01*
G01X-1333302Y304778D02*
X-1337632D01*
Y313439D01*
X-1333302D01*
G01X-1335034Y309253D02*
X-1337632D01*
G01X-1320852Y304778D02*
X-1318145Y313439D01*
X-1315438Y304778D01*
G01X-1316413Y307809D02*
X-1319877D01*
G01X-1309484Y313439D02*
Y304778D01*
G01X-1311974Y313439D02*
X-1306994D01*
G01X-1294869Y304778D02*
X-1292162Y313439D01*
X-1289455Y304778D01*
G01X-1290430Y307809D02*
X-1293894D01*
G01X-1285666Y313439D02*
Y304778D01*
X-1281336D01*
G01X-1277005Y313439D02*
Y304778D01*
X-1272675D01*
G01X-1259683Y313439D02*
Y304778D01*
X-1255353D01*
G01X-1251564D02*
X-1248857Y313439D01*
X-1246150Y304778D01*
G01X-1247125Y307809D02*
X-1250589D01*
G01X-1240196Y304778D02*
Y308675D01*
X-1242361Y313439D01*
G01X-1238031D02*
X-1240196Y308675D01*
G01X-1229370Y304778D02*
X-1233700D01*
Y313439D01*
X-1229370D01*
G01X-1231102Y309253D02*
X-1233700D01*
G01X-1225039Y304778D02*
Y313439D01*
X-1222333D01*
X-1221467Y313006D01*
X-1220925Y312429D01*
X-1220709Y311274D01*
X-1220925Y310119D01*
X-1221575Y309397D01*
X-1222333Y308964D01*
X-1225039D01*
G01X-1222333D02*
X-1220709Y304778D01*
G01X-1216487Y305933D02*
X-1215620Y305211D01*
X-1214646Y304778D01*
X-1213780D01*
X-1212914Y305211D01*
X-1212264Y305933D01*
X-1211939Y306943D01*
X-1212156Y307954D01*
X-1212697Y308820D01*
X-1213672Y309397D01*
X-1214971Y309686D01*
X-1215729Y310263D01*
X-1216054Y311274D01*
X-1215837Y312284D01*
X-1215296Y313006D01*
X-1214538Y313439D01*
X-1213780D01*
X-1213022Y313150D01*
X-1212372Y312429D01*
G01X-1205011Y301891D02*
X-1203928Y303335D01*
X-1203387Y304778D01*
Y310552D01*
X-1203928Y311996D01*
X-1205011Y313439D01*
G01X-1481083Y305788D02*
X-1480325Y305067D01*
X-1479459Y304778D01*
X-1478592Y305067D01*
X-1477835Y305933D01*
X-1477293Y307232D01*
X-1477077Y308531D01*
Y310119D01*
X-1477293Y311418D01*
X-1477835Y312573D01*
X-1478484Y313150D01*
X-1479242Y313439D01*
X-1480108Y313150D01*
X-1480758Y312573D01*
X-1481191Y311707D01*
X-1481407Y310552D01*
X-1481191Y309542D01*
X-1480649Y308531D01*
X-1480000Y307954D01*
X-1479242Y307809D01*
X-1478376Y308098D01*
X-1477726Y308820D01*
X-1477077Y310119D01*
G01X-1470581Y304489D02*
X-1470798Y304634D01*
Y304922D01*
X-1470581Y305067D01*
X-1470364Y304922D01*
Y304634D01*
X-1470581Y304489D01*
G01X-1464302Y306077D02*
X-1463652Y305355D01*
X-1462894Y304922D01*
X-1461920Y304778D01*
X-1460946Y305067D01*
X-1460188Y305644D01*
X-1459646Y306654D01*
X-1459538Y307809D01*
X-1459755Y308964D01*
X-1460296Y309686D01*
X-1461054Y310263D01*
X-1461812Y310408D01*
X-1462570Y310263D01*
X-1463544Y309686D01*
X-1463219Y313439D01*
X-1460296D01*
G01X-1453259D02*
X-1454125Y313150D01*
X-1454775Y312429D01*
X-1455208Y311563D01*
X-1455533Y310408D01*
X-1455641Y309108D01*
X-1455533Y307809D01*
X-1455208Y306654D01*
X-1454775Y305788D01*
X-1454125Y305067D01*
X-1453259Y304778D01*
X-1452393Y305067D01*
X-1451743Y305788D01*
X-1451310Y306654D01*
X-1450985Y307809D01*
X-1450877Y309108D01*
X-1450985Y310408D01*
X-1451310Y311563D01*
X-1451743Y312429D01*
X-1452393Y313150D01*
X-1453259Y313439D01*
G01X-1492631Y304778D02*
Y310552D01*
G01Y309108D02*
X-1492197Y309830D01*
X-1491548Y310408D01*
X-1490682Y310552D01*
X-1489924Y310408D01*
X-1489274Y309830D01*
X-1488949Y308820D01*
Y304778D01*
G01X-1481853Y387505D02*
X-1480843Y388155D01*
X-1480265Y389021D01*
X-1480121Y389995D01*
X-1480265Y390861D01*
X-1480987Y391728D01*
X-1481853Y392269D01*
X-1482719Y392377D01*
X-1483730Y392161D01*
X-1484451Y391403D01*
X-1484740Y390645D01*
Y389670D01*
G01Y390645D02*
X-1485173Y391294D01*
X-1485895Y391836D01*
X-1486761Y392052D01*
X-1487627Y391836D01*
X-1488349Y391294D01*
X-1488782Y390320D01*
X-1488638Y389346D01*
X-1488060Y388371D01*
G01X-1488782Y398548D02*
X-1488493Y397682D01*
X-1487772Y397032D01*
X-1486906Y396599D01*
X-1485751Y396274D01*
X-1484451Y396166D01*
X-1483152Y396274D01*
X-1481997Y396599D01*
X-1481131Y397032D01*
X-1480410Y397682D01*
X-1480121Y398548D01*
X-1480410Y399414D01*
X-1481131Y400064D01*
X-1481997Y400497D01*
X-1483152Y400822D01*
X-1484451Y400930D01*
X-1485751Y400822D01*
X-1486906Y400497D01*
X-1487772Y400064D01*
X-1488493Y399414D01*
X-1488782Y398548D01*
G01X-1479832Y407209D02*
X-1479977Y406992D01*
X-1480265D01*
X-1480410Y407209D01*
X-1480265Y407426D01*
X-1479977D01*
X-1479832Y407209D01*
G01X-1481420Y413488D02*
X-1480698Y414138D01*
X-1480265Y414896D01*
X-1480121Y415870D01*
X-1480410Y416844D01*
X-1480987Y417602D01*
X-1481997Y418144D01*
X-1483152Y418252D01*
X-1484307Y418035D01*
X-1485029Y417494D01*
X-1485606Y416736D01*
X-1485751Y415978D01*
X-1485606Y415220D01*
X-1485029Y414246D01*
X-1488782Y414571D01*
Y417494D01*
G01X-1481853Y422149D02*
X-1480843Y422799D01*
X-1480265Y423665D01*
X-1480121Y424639D01*
X-1480265Y425505D01*
X-1480987Y426372D01*
X-1481853Y426913D01*
X-1482719Y427021D01*
X-1483730Y426805D01*
X-1484451Y426047D01*
X-1484740Y425289D01*
Y424314D01*
G01Y425289D02*
X-1485173Y425938D01*
X-1485895Y426480D01*
X-1486761Y426696D01*
X-1487627Y426480D01*
X-1488349Y425938D01*
X-1488782Y424964D01*
X-1488638Y423990D01*
X-1488060Y423015D01*
G01X-1491309Y682398D02*
X-1501588Y684128D01*
X-1492684Y678709D01*
X-1491309Y682398D01*
G01X-1502105Y884213D02*
X-1493654Y878111D01*
X-1491993Y881681D01*
X-1502105Y884213D01*
G01X-1443472Y1130595D02*
X-1450980Y1123364D01*
X-1447763Y1121096D01*
X-1443472Y1130595D01*
G01X-1437129Y1187921D02*
X-1445790D01*
X-1439583Y1183915D01*
Y1189329D01*
G01X-1437129Y1195283D02*
X-1445790D01*
X-1444058Y1193984D01*
G01X-1437129D02*
Y1196582D01*
G01X-1436840Y1203944D02*
X-1436985Y1203727D01*
X-1437273D01*
X-1437418Y1203944D01*
X-1437273Y1204161D01*
X-1436985D01*
X-1436840Y1203944D01*
G01X-1437129Y1213904D02*
X-1445790D01*
X-1439583Y1209898D01*
Y1215312D01*
G01X-1438428Y1218884D02*
X-1437706Y1219534D01*
X-1437273Y1220292D01*
X-1437129Y1221266D01*
X-1437418Y1222240D01*
X-1437995Y1222998D01*
X-1439005Y1223540D01*
X-1440160Y1223648D01*
X-1441315Y1223431D01*
X-1442037Y1222890D01*
X-1442614Y1222132D01*
X-1442759Y1221374D01*
X-1442614Y1220616D01*
X-1442037Y1219642D01*
X-1445790Y1219967D01*
Y1222890D01*
G01X-1441494Y1147731D02*
X-1448372Y1155564D01*
X-1450786Y1152454D01*
X-1441494Y1147731D01*
G01X-1453126Y1382261D02*
X-1452368Y1381540D01*
X-1451502Y1381251D01*
X-1450635Y1381540D01*
X-1449878Y1382406D01*
X-1449336Y1383705D01*
X-1449120Y1385004D01*
Y1386592D01*
X-1449336Y1387891D01*
X-1449878Y1389046D01*
X-1450527Y1389623D01*
X-1451285Y1389912D01*
X-1452151Y1389623D01*
X-1452801Y1389046D01*
X-1453234Y1388180D01*
X-1453450Y1387025D01*
X-1453234Y1386015D01*
X-1452692Y1385004D01*
X-1452043Y1384427D01*
X-1451285Y1384282D01*
X-1450419Y1384571D01*
X-1449769Y1385293D01*
X-1449120Y1386592D01*
G01X-1442624Y1380962D02*
X-1442841Y1381107D01*
Y1381395D01*
X-1442624Y1381540D01*
X-1442407Y1381395D01*
Y1381107D01*
X-1442624Y1380962D01*
G01X-1436345Y1382550D02*
X-1435695Y1381828D01*
X-1434937Y1381395D01*
X-1433963Y1381251D01*
X-1432989Y1381540D01*
X-1432231Y1382117D01*
X-1431689Y1383127D01*
X-1431581Y1384282D01*
X-1431798Y1385437D01*
X-1432339Y1386159D01*
X-1433097Y1386736D01*
X-1433855Y1386881D01*
X-1434613Y1386736D01*
X-1435587Y1386159D01*
X-1435262Y1389912D01*
X-1432339D01*
G01X-1425302D02*
X-1426168Y1389623D01*
X-1426818Y1388902D01*
X-1427251Y1388036D01*
X-1427576Y1386881D01*
X-1427684Y1385581D01*
X-1427576Y1384282D01*
X-1427251Y1383127D01*
X-1426818Y1382261D01*
X-1426168Y1381540D01*
X-1425302Y1381251D01*
X-1424436Y1381540D01*
X-1423786Y1382261D01*
X-1423353Y1383127D01*
X-1423028Y1384282D01*
X-1422920Y1385581D01*
X-1423028Y1386881D01*
X-1423353Y1388036D01*
X-1423786Y1388902D01*
X-1424436Y1389623D01*
X-1425302Y1389912D01*
G01X-1464674Y1381251D02*
Y1387025D01*
G01Y1385581D02*
X-1464240Y1386303D01*
X-1463591Y1386881D01*
X-1462725Y1387025D01*
X-1461967Y1386881D01*
X-1461317Y1386303D01*
X-1460992Y1385293D01*
Y1381251D01*
G01X-1432770Y152085D02*
X-1427644Y161162D01*
X-1431376Y162416D01*
X-1432770Y152085D01*
G01X-1376855Y251241D02*
X-1376097Y252251D01*
X-1375448Y252829D01*
X-1374581Y253117D01*
X-1373824Y252829D01*
X-1373282Y252251D01*
X-1372849Y251385D01*
X-1372741Y250375D01*
X-1372849Y249508D01*
X-1373282Y248642D01*
X-1373932Y247921D01*
X-1374690Y247632D01*
X-1375556Y247921D01*
X-1376314Y248787D01*
X-1376747Y250086D01*
X-1376855Y251529D01*
X-1376639Y253406D01*
X-1376314Y254417D01*
X-1375772Y255427D01*
X-1375015Y256149D01*
X-1374257Y256293D01*
X-1373499Y256004D01*
X-1372957Y255283D01*
G01X-1366137Y247343D02*
X-1366354Y247488D01*
Y247776D01*
X-1366137Y247921D01*
X-1365920Y247776D01*
Y247488D01*
X-1366137Y247343D01*
G01X-1359858Y248931D02*
X-1359208Y248209D01*
X-1358450Y247776D01*
X-1357476Y247632D01*
X-1356502Y247921D01*
X-1355744Y248498D01*
X-1355202Y249508D01*
X-1355094Y250663D01*
X-1355311Y251818D01*
X-1355852Y252540D01*
X-1356610Y253117D01*
X-1357368Y253262D01*
X-1358126Y253117D01*
X-1359100Y252540D01*
X-1358775Y256293D01*
X-1355852D01*
G01X-1348815D02*
X-1349681Y256004D01*
X-1350331Y255283D01*
X-1350764Y254417D01*
X-1351089Y253262D01*
X-1351197Y251962D01*
X-1351089Y250663D01*
X-1350764Y249508D01*
X-1350331Y248642D01*
X-1349681Y247921D01*
X-1348815Y247632D01*
X-1347949Y247921D01*
X-1347299Y248642D01*
X-1346866Y249508D01*
X-1346541Y250663D01*
X-1346433Y251962D01*
X-1346541Y253262D01*
X-1346866Y254417D01*
X-1347299Y255283D01*
X-1347949Y256004D01*
X-1348815Y256293D01*
G01X-1388187Y247632D02*
Y253406D01*
G01Y251962D02*
X-1387753Y252684D01*
X-1387104Y253262D01*
X-1386238Y253406D01*
X-1385480Y253262D01*
X-1384830Y252684D01*
X-1384505Y251674D01*
Y247632D01*
G01X-1386596Y633212D02*
Y641873D01*
X-1390602Y635666D01*
X-1385188D01*
G01X-1379234Y641873D02*
X-1380100Y641584D01*
X-1380750Y640863D01*
X-1381183Y639997D01*
X-1381508Y638842D01*
X-1381616Y637542D01*
X-1381508Y636243D01*
X-1381183Y635088D01*
X-1380750Y634222D01*
X-1380100Y633501D01*
X-1379234Y633212D01*
X-1378368Y633501D01*
X-1377718Y634222D01*
X-1377285Y635088D01*
X-1376960Y636243D01*
X-1376852Y637542D01*
X-1376960Y638842D01*
X-1377285Y639997D01*
X-1377718Y640863D01*
X-1378368Y641584D01*
X-1379234Y641873D01*
G01X-1370573Y632923D02*
X-1370790Y633068D01*
Y633356D01*
X-1370573Y633501D01*
X-1370356Y633356D01*
Y633068D01*
X-1370573Y632923D01*
G01X-1361912Y641873D02*
X-1362778Y641584D01*
X-1363428Y640863D01*
X-1363861Y639997D01*
X-1364186Y638842D01*
X-1364294Y637542D01*
X-1364186Y636243D01*
X-1363861Y635088D01*
X-1363428Y634222D01*
X-1362778Y633501D01*
X-1361912Y633212D01*
X-1361046Y633501D01*
X-1360396Y634222D01*
X-1359963Y635088D01*
X-1359638Y636243D01*
X-1359530Y637542D01*
X-1359638Y638842D01*
X-1359963Y639997D01*
X-1360396Y640863D01*
X-1361046Y641584D01*
X-1361912Y641873D01*
G01X-1355633Y634511D02*
X-1354983Y633789D01*
X-1354225Y633356D01*
X-1353251Y633212D01*
X-1352277Y633501D01*
X-1351519Y634078D01*
X-1350977Y635088D01*
X-1350869Y636243D01*
X-1351086Y637398D01*
X-1351627Y638120D01*
X-1352385Y638697D01*
X-1353143Y638842D01*
X-1353901Y638697D01*
X-1354875Y638120D01*
X-1354550Y641873D01*
X-1351627D01*
G01X-1390795Y579215D02*
X-1391878Y580659D01*
X-1392419Y582102D01*
Y587876D01*
X-1391878Y589320D01*
X-1390795Y590763D01*
G01X-1384083Y582102D02*
Y590763D01*
X-1379103Y582102D01*
Y590763D01*
G01X-1375097Y582102D02*
Y590763D01*
X-1372499D01*
X-1371633Y590330D01*
X-1370983Y589320D01*
X-1370767Y588165D01*
X-1370983Y587010D01*
X-1371525Y586144D01*
X-1372499Y585711D01*
X-1375097D01*
G01X-1364271Y590763D02*
Y582102D01*
G01X-1366761Y590763D02*
X-1361781D01*
G01X-1357884Y582102D02*
Y590763D01*
G01X-1353336D02*
Y582102D01*
G01Y586432D02*
X-1357884D01*
G01X-1346408Y579215D02*
X-1345325Y580659D01*
X-1344784Y582102D01*
Y587876D01*
X-1345325Y589320D01*
X-1346408Y590763D01*
G01X-1422086Y583834D02*
X-1421436Y582824D01*
X-1420570Y582246D01*
X-1419596Y582102D01*
X-1418730Y582246D01*
X-1417863Y582968D01*
X-1417322Y583834D01*
X-1417214Y584700D01*
X-1417430Y585711D01*
X-1418188Y586432D01*
X-1418946Y586721D01*
X-1419921D01*
G01X-1418946D02*
X-1418297Y587154D01*
X-1417755Y587876D01*
X-1417539Y588742D01*
X-1417755Y589608D01*
X-1418297Y590330D01*
X-1419271Y590763D01*
X-1420245Y590619D01*
X-1421220Y590041D01*
G01X-1411043Y581813D02*
X-1411260Y581958D01*
Y582246D01*
X-1411043Y582391D01*
X-1410826Y582246D01*
Y581958D01*
X-1411043Y581813D01*
G01X-1404764Y583834D02*
X-1404114Y582824D01*
X-1403248Y582246D01*
X-1402274Y582102D01*
X-1401408Y582246D01*
X-1400541Y582968D01*
X-1400000Y583834D01*
X-1399892Y584700D01*
X-1400108Y585711D01*
X-1400866Y586432D01*
X-1401624Y586721D01*
X-1402599D01*
G01X-1401624D02*
X-1400975Y587154D01*
X-1400433Y587876D01*
X-1400217Y588742D01*
X-1400433Y589608D01*
X-1400975Y590330D01*
X-1401949Y590763D01*
X-1402923Y590619D01*
X-1403898Y590041D01*
G01X-1393721Y590763D02*
X-1394587Y590474D01*
X-1395237Y589753D01*
X-1395670Y588887D01*
X-1395995Y587732D01*
X-1396103Y586432D01*
X-1395995Y585133D01*
X-1395670Y583978D01*
X-1395237Y583112D01*
X-1394587Y582391D01*
X-1393721Y582102D01*
X-1392855Y582391D01*
X-1392205Y583112D01*
X-1391772Y583978D01*
X-1391447Y585133D01*
X-1391339Y586432D01*
X-1391447Y587732D01*
X-1391772Y588887D01*
X-1392205Y589753D01*
X-1392855Y590474D01*
X-1393721Y590763D01*
G01X-1426743Y582102D02*
Y587876D01*
G01Y586432D02*
X-1426309Y587154D01*
X-1425660Y587732D01*
X-1424794Y587876D01*
X-1424036Y587732D01*
X-1423386Y587154D01*
X-1423061Y586144D01*
Y582102D01*
G01X-1431550Y659613D02*
X-1430683Y658891D01*
X-1429709Y658458D01*
X-1428843D01*
X-1427977Y658891D01*
X-1427327Y659613D01*
X-1427002Y660623D01*
X-1427219Y661634D01*
X-1427760Y662500D01*
X-1428735Y663077D01*
X-1430034Y663366D01*
X-1430792Y663943D01*
X-1431117Y664954D01*
X-1430900Y665964D01*
X-1430359Y666686D01*
X-1429601Y667119D01*
X-1428843D01*
X-1428085Y666830D01*
X-1427435Y666109D01*
G01X-1418450Y658458D02*
X-1422780D01*
Y667119D01*
X-1418450D01*
G01X-1420182Y662933D02*
X-1422780D01*
G01X-1409789Y658458D02*
X-1414119D01*
Y667119D01*
X-1409789D01*
G01X-1411521Y662933D02*
X-1414119D01*
G01X-1397014Y658458D02*
Y667119D01*
X-1394849D01*
X-1393982Y666686D01*
X-1393333Y666109D01*
X-1392791Y665243D01*
X-1392358Y664232D01*
X-1392250Y662788D01*
X-1392358Y661345D01*
X-1392791Y660334D01*
X-1393333Y659468D01*
X-1393982Y658891D01*
X-1394849Y658458D01*
X-1397014D01*
G01X-1383806D02*
X-1388136D01*
Y667119D01*
X-1383806D01*
G01X-1385538Y662933D02*
X-1388136D01*
G01X-1377310Y667119D02*
Y658458D01*
G01X-1379800Y667119D02*
X-1374820D01*
G01X-1371356Y658458D02*
X-1368649Y667119D01*
X-1365942Y658458D01*
G01X-1366917Y661489D02*
X-1370381D01*
G01X-1361287Y667119D02*
X-1358689D01*
G01X-1359988D02*
Y658458D01*
G01X-1361287D02*
X-1358689D01*
G01X-1353492Y667119D02*
Y658458D01*
X-1349162D01*
G01X-1336712D02*
X-1334005Y667119D01*
X-1331298Y658458D01*
G01X-1332273Y661489D02*
X-1335737D01*
G01X-1390409Y858166D02*
X-1391492Y859610D01*
X-1392033Y861053D01*
Y866827D01*
X-1391492Y868271D01*
X-1390409Y869714D01*
G01X-1383697Y861053D02*
Y869714D01*
X-1378717Y861053D01*
Y869714D01*
G01X-1374711Y861053D02*
Y869714D01*
X-1372113D01*
X-1371247Y869281D01*
X-1370597Y868271D01*
X-1370381Y867116D01*
X-1370597Y865961D01*
X-1371139Y865095D01*
X-1372113Y864662D01*
X-1374711D01*
G01X-1363885Y869714D02*
Y861053D01*
G01X-1366375Y869714D02*
X-1361395D01*
G01X-1357498Y861053D02*
Y869714D01*
G01X-1352950D02*
Y861053D01*
G01Y865383D02*
X-1357498D01*
G01X-1346022Y858166D02*
X-1344939Y859610D01*
X-1344398Y861053D01*
Y866827D01*
X-1344939Y868271D01*
X-1346022Y869714D01*
G01X-1423431Y862785D02*
X-1422781Y861775D01*
X-1421915Y861197D01*
X-1420941Y861053D01*
X-1420075Y861197D01*
X-1419208Y861919D01*
X-1418667Y862785D01*
X-1418559Y863651D01*
X-1418775Y864662D01*
X-1419533Y865383D01*
X-1420291Y865672D01*
X-1421266D01*
G01X-1420291D02*
X-1419642Y866105D01*
X-1419100Y866827D01*
X-1418884Y867693D01*
X-1419100Y868559D01*
X-1419642Y869281D01*
X-1420616Y869714D01*
X-1421590Y869570D01*
X-1422565Y868992D01*
G01X-1412388Y860764D02*
X-1412605Y860909D01*
Y861197D01*
X-1412388Y861342D01*
X-1412171Y861197D01*
Y860909D01*
X-1412388Y860764D01*
G01X-1406109Y862785D02*
X-1405459Y861775D01*
X-1404593Y861197D01*
X-1403619Y861053D01*
X-1402753Y861197D01*
X-1401886Y861919D01*
X-1401345Y862785D01*
X-1401237Y863651D01*
X-1401453Y864662D01*
X-1402211Y865383D01*
X-1402969Y865672D01*
X-1403944D01*
G01X-1402969D02*
X-1402320Y866105D01*
X-1401778Y866827D01*
X-1401562Y867693D01*
X-1401778Y868559D01*
X-1402320Y869281D01*
X-1403294Y869714D01*
X-1404268Y869570D01*
X-1405243Y868992D01*
G01X-1395066Y869714D02*
X-1395932Y869425D01*
X-1396582Y868704D01*
X-1397015Y867838D01*
X-1397340Y866683D01*
X-1397448Y865383D01*
X-1397340Y864084D01*
X-1397015Y862929D01*
X-1396582Y862063D01*
X-1395932Y861342D01*
X-1395066Y861053D01*
X-1394200Y861342D01*
X-1393550Y862063D01*
X-1393117Y862929D01*
X-1392792Y864084D01*
X-1392684Y865383D01*
X-1392792Y866683D01*
X-1393117Y867838D01*
X-1393550Y868704D01*
X-1394200Y869425D01*
X-1395066Y869714D01*
G01X-1434439Y861053D02*
Y866827D01*
G01Y865383D02*
X-1434005Y866105D01*
X-1433356Y866683D01*
X-1432490Y866827D01*
X-1431732Y866683D01*
X-1431082Y866105D01*
X-1430757Y865095D01*
Y861053D01*
G01X-1425679Y878380D02*
X-1424812Y877658D01*
X-1423838Y877225D01*
X-1422972D01*
X-1422106Y877658D01*
X-1421456Y878380D01*
X-1421131Y879390D01*
X-1421348Y880401D01*
X-1421889Y881267D01*
X-1422864Y881844D01*
X-1424163Y882133D01*
X-1424921Y882710D01*
X-1425246Y883721D01*
X-1425029Y884731D01*
X-1424488Y885453D01*
X-1423730Y885886D01*
X-1422972D01*
X-1422214Y885597D01*
X-1421564Y884876D01*
G01X-1412579Y877225D02*
X-1416909D01*
Y885886D01*
X-1412579D01*
G01X-1414311Y881700D02*
X-1416909D01*
G01X-1403918Y877225D02*
X-1408248D01*
Y885886D01*
X-1403918D01*
G01X-1405650Y881700D02*
X-1408248D01*
G01X-1391143Y877225D02*
Y885886D01*
X-1388978D01*
X-1388111Y885453D01*
X-1387462Y884876D01*
X-1386920Y884010D01*
X-1386487Y882999D01*
X-1386379Y881555D01*
X-1386487Y880112D01*
X-1386920Y879101D01*
X-1387462Y878235D01*
X-1388111Y877658D01*
X-1388978Y877225D01*
X-1391143D01*
G01X-1377935D02*
X-1382265D01*
Y885886D01*
X-1377935D01*
G01X-1379667Y881700D02*
X-1382265D01*
G01X-1371439Y885886D02*
Y877225D01*
G01X-1373929Y885886D02*
X-1368949D01*
G01X-1365485Y877225D02*
X-1362778Y885886D01*
X-1360071Y877225D01*
G01X-1361046Y880256D02*
X-1364510D01*
G01X-1355416Y885886D02*
X-1352818D01*
G01X-1354117D02*
Y877225D01*
G01X-1355416D02*
X-1352818D01*
G01X-1347621Y885886D02*
Y877225D01*
X-1343291D01*
G01X-1380887Y1104801D02*
X-1380020Y1104079D01*
X-1379046Y1103646D01*
X-1378180D01*
X-1377314Y1104079D01*
X-1376664Y1104801D01*
X-1376339Y1105811D01*
X-1376556Y1106822D01*
X-1377097Y1107688D01*
X-1378072Y1108265D01*
X-1379371Y1108554D01*
X-1380129Y1109131D01*
X-1380454Y1110142D01*
X-1380237Y1111152D01*
X-1379696Y1111874D01*
X-1378938Y1112307D01*
X-1378180D01*
X-1377422Y1112018D01*
X-1376772Y1111297D01*
G01X-1372767Y1103646D02*
Y1112307D01*
X-1369952Y1105089D01*
X-1367137Y1112307D01*
Y1103646D01*
G01X-1361291Y1112307D02*
Y1103646D01*
G01X-1363781Y1112307D02*
X-1358801D01*
G01X-1346459Y1103646D02*
Y1112307D01*
X-1341479Y1103646D01*
Y1112307D01*
G01X-1337690D02*
Y1106100D01*
X-1337257Y1104801D01*
X-1336391Y1103935D01*
X-1335308Y1103646D01*
X-1334225Y1103935D01*
X-1333359Y1104801D01*
X-1332926Y1106100D01*
Y1112307D01*
G01X-1326647D02*
Y1103646D01*
G01X-1329137Y1112307D02*
X-1324157D01*
G01X-1318527Y1100759D02*
X-1319610Y1102203D01*
X-1320151Y1103646D01*
Y1109420D01*
X-1319610Y1110864D01*
X-1318527Y1112307D01*
G01X-1309325D02*
X-1310191Y1112018D01*
X-1310841Y1111297D01*
X-1311274Y1110431D01*
X-1311599Y1109276D01*
X-1311707Y1107976D01*
X-1311599Y1106677D01*
X-1311274Y1105522D01*
X-1310841Y1104656D01*
X-1310191Y1103935D01*
X-1309325Y1103646D01*
X-1308459Y1103935D01*
X-1307809Y1104656D01*
X-1307376Y1105522D01*
X-1307051Y1106677D01*
X-1306943Y1107976D01*
X-1307051Y1109276D01*
X-1307376Y1110431D01*
X-1307809Y1111297D01*
X-1308459Y1112018D01*
X-1309325Y1112307D01*
G01X-1300664Y1103646D02*
X-1299906Y1103790D01*
X-1299040Y1104223D01*
X-1298499Y1104945D01*
X-1298282Y1105956D01*
X-1298499Y1106966D01*
X-1299148Y1107832D01*
X-1300123Y1108265D01*
X-1301205D01*
X-1301855Y1108554D01*
X-1302396Y1109276D01*
X-1302613Y1110286D01*
X-1302288Y1111297D01*
X-1301530Y1112018D01*
X-1300664Y1112307D01*
X-1299798Y1112018D01*
X-1299040Y1111297D01*
X-1298715Y1110286D01*
X-1298932Y1109276D01*
X-1299473Y1108554D01*
X-1300123Y1108265D01*
X-1301205D01*
X-1302180Y1107832D01*
X-1302829Y1106966D01*
X-1303046Y1105956D01*
X-1302829Y1104945D01*
X-1302288Y1104223D01*
X-1301422Y1103790D01*
X-1300664Y1103646D01*
G01X-1292220D02*
X-1292003Y1105522D01*
X-1291678Y1107110D01*
X-1291245Y1108554D01*
X-1290704Y1110142D01*
X-1289838Y1112307D01*
X-1294168D01*
G01X-1283342Y1103357D02*
X-1283559Y1103502D01*
Y1103790D01*
X-1283342Y1103935D01*
X-1283125Y1103790D01*
Y1103502D01*
X-1283342Y1103357D01*
G01X-1274898Y1103646D02*
X-1274681Y1105522D01*
X-1274356Y1107110D01*
X-1273923Y1108554D01*
X-1273382Y1110142D01*
X-1272516Y1112307D01*
X-1276846D01*
G01X-1266020Y1103646D02*
Y1112307D01*
X-1267319Y1110575D01*
G01Y1103646D02*
X-1264721D01*
G01X-1259416Y1110864D02*
X-1258766Y1111729D01*
X-1258009Y1112163D01*
X-1257142Y1112307D01*
X-1256060Y1112018D01*
X-1255302Y1111297D01*
X-1255085Y1110431D01*
X-1255194Y1109564D01*
X-1255627Y1108843D01*
X-1257792Y1107399D01*
X-1258766Y1106389D01*
X-1259416Y1104945D01*
X-1259633Y1103646D01*
X-1255085D01*
G01X-1247399D02*
Y1112307D01*
X-1251405Y1106100D01*
X-1245991D01*
G01X-1242094Y1110864D02*
X-1241444Y1111729D01*
X-1240687Y1112163D01*
X-1239820Y1112307D01*
X-1238738Y1112018D01*
X-1237980Y1111297D01*
X-1237763Y1110431D01*
X-1237872Y1109564D01*
X-1238305Y1108843D01*
X-1240470Y1107399D01*
X-1241444Y1106389D01*
X-1242094Y1104945D01*
X-1242311Y1103646D01*
X-1237763D01*
G01X-1231376Y1103357D02*
X-1231593Y1103502D01*
Y1103790D01*
X-1231376Y1103935D01*
X-1231159Y1103790D01*
Y1103502D01*
X-1231376Y1103357D01*
G01X-1222715Y1112307D02*
X-1223581Y1112018D01*
X-1224231Y1111297D01*
X-1224664Y1110431D01*
X-1224989Y1109276D01*
X-1225097Y1107976D01*
X-1224989Y1106677D01*
X-1224664Y1105522D01*
X-1224231Y1104656D01*
X-1223581Y1103935D01*
X-1222715Y1103646D01*
X-1221849Y1103935D01*
X-1221199Y1104656D01*
X-1220766Y1105522D01*
X-1220441Y1106677D01*
X-1220333Y1107976D01*
X-1220441Y1109276D01*
X-1220766Y1110431D01*
X-1221199Y1111297D01*
X-1221849Y1112018D01*
X-1222715Y1112307D01*
G01X-1212755Y1103646D02*
Y1112307D01*
X-1216761Y1106100D01*
X-1211347D01*
G01X-1207450Y1107255D02*
X-1206692Y1108265D01*
X-1206043Y1108843D01*
X-1205176Y1109131D01*
X-1204419Y1108843D01*
X-1203877Y1108265D01*
X-1203444Y1107399D01*
X-1203336Y1106389D01*
X-1203444Y1105522D01*
X-1203877Y1104656D01*
X-1204527Y1103935D01*
X-1205285Y1103646D01*
X-1206151Y1103935D01*
X-1206909Y1104801D01*
X-1207342Y1106100D01*
X-1207450Y1107543D01*
X-1207234Y1109420D01*
X-1206909Y1110431D01*
X-1206367Y1111441D01*
X-1205610Y1112163D01*
X-1204852Y1112307D01*
X-1204094Y1112018D01*
X-1203552Y1111297D01*
G01X-1199114Y1104945D02*
X-1198464Y1104223D01*
X-1197706Y1103790D01*
X-1196732Y1103646D01*
X-1195758Y1103935D01*
X-1195000Y1104512D01*
X-1194458Y1105522D01*
X-1194350Y1106677D01*
X-1194567Y1107832D01*
X-1195108Y1108554D01*
X-1195866Y1109131D01*
X-1196624Y1109276D01*
X-1197382Y1109131D01*
X-1198356Y1108554D01*
X-1198031Y1112307D01*
X-1195108D01*
G01X-1187530Y1100759D02*
X-1186447Y1102203D01*
X-1185906Y1103646D01*
Y1109420D01*
X-1186447Y1110864D01*
X-1187530Y1112307D01*
G01X-1418202Y1135372D02*
X-1426823Y1141232D01*
X-1420991Y1132593D01*
X-1418202Y1135372D01*
G01X-1431986Y1155105D02*
X-1427690Y1164602D01*
X-1431519Y1165518D01*
X-1431986Y1155105D01*
G01X-1378385Y1282293D02*
X-1377627Y1283303D01*
X-1376978Y1283881D01*
X-1376111Y1284169D01*
X-1375354Y1283881D01*
X-1374812Y1283303D01*
X-1374379Y1282437D01*
X-1374271Y1281427D01*
X-1374379Y1280560D01*
X-1374812Y1279694D01*
X-1375462Y1278973D01*
X-1376220Y1278684D01*
X-1377086Y1278973D01*
X-1377844Y1279839D01*
X-1378277Y1281138D01*
X-1378385Y1282581D01*
X-1378169Y1284458D01*
X-1377844Y1285469D01*
X-1377302Y1286479D01*
X-1376545Y1287201D01*
X-1375787Y1287345D01*
X-1375029Y1287056D01*
X-1374487Y1286335D01*
G01X-1367667Y1278395D02*
X-1367884Y1278540D01*
Y1278828D01*
X-1367667Y1278973D01*
X-1367450Y1278828D01*
Y1278540D01*
X-1367667Y1278395D01*
G01X-1361388Y1279983D02*
X-1360738Y1279261D01*
X-1359980Y1278828D01*
X-1359006Y1278684D01*
X-1358032Y1278973D01*
X-1357274Y1279550D01*
X-1356732Y1280560D01*
X-1356624Y1281715D01*
X-1356841Y1282870D01*
X-1357382Y1283592D01*
X-1358140Y1284169D01*
X-1358898Y1284314D01*
X-1359656Y1284169D01*
X-1360630Y1283592D01*
X-1360305Y1287345D01*
X-1357382D01*
G01X-1350345D02*
X-1351211Y1287056D01*
X-1351861Y1286335D01*
X-1352294Y1285469D01*
X-1352619Y1284314D01*
X-1352727Y1283014D01*
X-1352619Y1281715D01*
X-1352294Y1280560D01*
X-1351861Y1279694D01*
X-1351211Y1278973D01*
X-1350345Y1278684D01*
X-1349479Y1278973D01*
X-1348829Y1279694D01*
X-1348396Y1280560D01*
X-1348071Y1281715D01*
X-1347963Y1283014D01*
X-1348071Y1284314D01*
X-1348396Y1285469D01*
X-1348829Y1286335D01*
X-1349479Y1287056D01*
X-1350345Y1287345D01*
G01X-1389717Y1278684D02*
Y1284458D01*
G01Y1283014D02*
X-1389283Y1283736D01*
X-1388634Y1284314D01*
X-1387768Y1284458D01*
X-1387010Y1284314D01*
X-1386360Y1283736D01*
X-1386035Y1282726D01*
Y1278684D01*
G01X-1420645Y1378364D02*
X-1421728Y1379808D01*
X-1422269Y1381251D01*
Y1387025D01*
X-1421728Y1388469D01*
X-1420645Y1389912D01*
G01X-1413608Y1381251D02*
Y1389912D01*
X-1411010D01*
X-1410144Y1389479D01*
X-1409494Y1388469D01*
X-1409278Y1387314D01*
X-1409494Y1386159D01*
X-1410036Y1385293D01*
X-1411010Y1384860D01*
X-1413608D01*
G01X-1405489Y1381251D02*
X-1402782Y1389912D01*
X-1400075Y1381251D01*
G01X-1401050Y1384282D02*
X-1404514D01*
G01X-1396503Y1381251D02*
Y1389912D01*
X-1394338D01*
X-1393471Y1389479D01*
X-1392822Y1388902D01*
X-1392280Y1388036D01*
X-1391847Y1387025D01*
X-1391739Y1385581D01*
X-1391847Y1384138D01*
X-1392280Y1383127D01*
X-1392822Y1382261D01*
X-1393471Y1381684D01*
X-1394338Y1381251D01*
X-1396503D01*
G01X-1384919Y1378364D02*
X-1383836Y1379808D01*
X-1383295Y1381251D01*
Y1387025D01*
X-1383836Y1388469D01*
X-1384919Y1389912D01*
G01X-1377340Y1378364D02*
X-1378423Y1379808D01*
X-1378964Y1381251D01*
Y1387025D01*
X-1378423Y1388469D01*
X-1377340Y1389912D01*
G01X-1370628Y1381251D02*
Y1389912D01*
X-1365648Y1381251D01*
Y1389912D01*
G01X-1359477Y1381251D02*
X-1360343Y1381395D01*
X-1361101Y1381973D01*
X-1361751Y1382839D01*
X-1362184Y1383849D01*
X-1362400Y1385004D01*
Y1386159D01*
X-1362184Y1387314D01*
X-1361751Y1388324D01*
X-1361101Y1389190D01*
X-1360343Y1389768D01*
X-1359477Y1389912D01*
X-1358611Y1389768D01*
X-1357853Y1389190D01*
X-1357203Y1388324D01*
X-1356770Y1387314D01*
X-1356554Y1386159D01*
Y1385004D01*
X-1356770Y1383849D01*
X-1357203Y1382839D01*
X-1357853Y1381973D01*
X-1358611Y1381395D01*
X-1359477Y1381251D01*
G01X-1342155Y1389912D02*
Y1381251D01*
G01X-1344645Y1389912D02*
X-1339665D01*
G01X-1335659Y1381251D02*
Y1389912D01*
X-1332953D01*
X-1332087Y1389479D01*
X-1331545Y1388902D01*
X-1331329Y1387747D01*
X-1331545Y1386592D01*
X-1332195Y1385870D01*
X-1332953Y1385437D01*
X-1335659D01*
G01X-1332953D02*
X-1331329Y1381251D01*
G01X-1327540D02*
X-1324833Y1389912D01*
X-1322126Y1381251D01*
G01X-1323101Y1384282D02*
X-1326565D01*
G01X-1313790Y1389190D02*
X-1314440Y1389623D01*
X-1315198Y1389912D01*
X-1316064D01*
X-1317038Y1389479D01*
X-1317796Y1388757D01*
X-1318337Y1387891D01*
X-1318771Y1386448D01*
X-1318879Y1385148D01*
X-1318662Y1383849D01*
X-1318337Y1382983D01*
X-1317688Y1382117D01*
X-1316930Y1381540D01*
X-1316172Y1381251D01*
X-1315414D01*
X-1314656Y1381540D01*
X-1314007Y1381973D01*
X-1313465Y1382550D01*
G01X-1305346Y1381251D02*
X-1309676D01*
Y1389912D01*
X-1305346D01*
G01X-1307078Y1385726D02*
X-1309676D01*
G01X-1292896Y1381251D02*
X-1290189Y1389912D01*
X-1287482Y1381251D01*
G01X-1288457Y1384282D02*
X-1291921D01*
G01X-1281528Y1389912D02*
Y1381251D01*
G01X-1284018Y1389912D02*
X-1279038D01*
G01X-1266913Y1381251D02*
X-1264206Y1389912D01*
X-1261499Y1381251D01*
G01X-1262474Y1384282D02*
X-1265938D01*
G01X-1257710Y1389912D02*
Y1381251D01*
X-1253380D01*
G01X-1249049Y1389912D02*
Y1381251D01*
X-1244719D01*
G01X-1231727Y1389912D02*
Y1381251D01*
X-1227397D01*
G01X-1223608D02*
X-1220901Y1389912D01*
X-1218194Y1381251D01*
G01X-1219169Y1384282D02*
X-1222633D01*
G01X-1212240Y1381251D02*
Y1385148D01*
X-1214405Y1389912D01*
G01X-1210075D02*
X-1212240Y1385148D01*
G01X-1201414Y1381251D02*
X-1205744D01*
Y1389912D01*
X-1201414D01*
G01X-1203146Y1385726D02*
X-1205744D01*
G01X-1197083Y1381251D02*
Y1389912D01*
X-1194377D01*
X-1193511Y1389479D01*
X-1192969Y1388902D01*
X-1192753Y1387747D01*
X-1192969Y1386592D01*
X-1193619Y1385870D01*
X-1194377Y1385437D01*
X-1197083D01*
G01X-1194377D02*
X-1192753Y1381251D01*
G01X-1188531Y1382406D02*
X-1187664Y1381684D01*
X-1186690Y1381251D01*
X-1185824D01*
X-1184958Y1381684D01*
X-1184308Y1382406D01*
X-1183983Y1383416D01*
X-1184200Y1384427D01*
X-1184741Y1385293D01*
X-1185716Y1385870D01*
X-1187015Y1386159D01*
X-1187773Y1386736D01*
X-1188098Y1387747D01*
X-1187881Y1388757D01*
X-1187340Y1389479D01*
X-1186582Y1389912D01*
X-1185824D01*
X-1185066Y1389623D01*
X-1184416Y1388902D01*
G01X-1177055Y1378364D02*
X-1175972Y1379808D01*
X-1175431Y1381251D01*
Y1387025D01*
X-1175972Y1388469D01*
X-1177055Y1389912D01*
G01X-1350808Y-727343D02*
X-1349956Y-728668D01*
X-1348819Y-729426D01*
X-1347541Y-729615D01*
X-1346405Y-729426D01*
X-1345268Y-728479D01*
X-1344558Y-727343D01*
X-1344416Y-726206D01*
X-1344700Y-724881D01*
X-1345695Y-723934D01*
X-1346689Y-723555D01*
X-1347967D01*
G01X-1346689D02*
X-1345837Y-722987D01*
X-1345126Y-722041D01*
X-1344842Y-720904D01*
X-1345126Y-719768D01*
X-1345837Y-718821D01*
X-1347115Y-718253D01*
X-1348393Y-718442D01*
X-1349671Y-719200D01*
G01X-1344158Y244745D02*
X-1345241Y246189D01*
X-1345782Y247632D01*
Y253406D01*
X-1345241Y254850D01*
X-1344158Y256293D01*
G01X-1337121Y247632D02*
Y256293D01*
X-1334523D01*
X-1333657Y255860D01*
X-1333007Y254850D01*
X-1332791Y253695D01*
X-1333007Y252540D01*
X-1333549Y251674D01*
X-1334523Y251241D01*
X-1337121D01*
G01X-1329002Y247632D02*
X-1326295Y256293D01*
X-1323588Y247632D01*
G01X-1324563Y250663D02*
X-1328027D01*
G01X-1320016Y247632D02*
Y256293D01*
X-1317851D01*
X-1316984Y255860D01*
X-1316335Y255283D01*
X-1315793Y254417D01*
X-1315360Y253406D01*
X-1315252Y251962D01*
X-1315360Y250519D01*
X-1315793Y249508D01*
X-1316335Y248642D01*
X-1316984Y248065D01*
X-1317851Y247632D01*
X-1320016D01*
G01X-1308432Y244745D02*
X-1307349Y246189D01*
X-1306808Y247632D01*
Y253406D01*
X-1307349Y254850D01*
X-1308432Y256293D01*
G01X-1312798Y389670D02*
X-1314674Y389887D01*
X-1316262Y390212D01*
X-1317706Y390645D01*
X-1319294Y391186D01*
X-1321459Y392052D01*
Y387722D01*
G01X-1314530Y396166D02*
X-1313520Y396816D01*
X-1312942Y397682D01*
X-1312798Y398656D01*
X-1312942Y399522D01*
X-1313664Y400389D01*
X-1314530Y400930D01*
X-1315396Y401038D01*
X-1316407Y400822D01*
X-1317128Y400064D01*
X-1317417Y399306D01*
Y398331D01*
G01Y399306D02*
X-1317850Y399955D01*
X-1318572Y400497D01*
X-1319438Y400713D01*
X-1320304Y400497D01*
X-1321026Y399955D01*
X-1321459Y398981D01*
X-1321315Y398007D01*
X-1320737Y397032D01*
G01X-1312509Y407209D02*
X-1312654Y406992D01*
X-1312942D01*
X-1313087Y407209D01*
X-1312942Y407426D01*
X-1312654D01*
X-1312509Y407209D01*
G01X-1321459Y415870D02*
X-1321170Y415004D01*
X-1320449Y414354D01*
X-1319583Y413921D01*
X-1318428Y413596D01*
X-1317128Y413488D01*
X-1315829Y413596D01*
X-1314674Y413921D01*
X-1313808Y414354D01*
X-1313087Y415004D01*
X-1312798Y415870D01*
X-1313087Y416736D01*
X-1313808Y417386D01*
X-1314674Y417819D01*
X-1315829Y418144D01*
X-1317128Y418252D01*
X-1318428Y418144D01*
X-1319583Y417819D01*
X-1320449Y417386D01*
X-1321170Y416736D01*
X-1321459Y415870D01*
G01X-1314530Y422149D02*
X-1313520Y422799D01*
X-1312942Y423665D01*
X-1312798Y424639D01*
X-1312942Y425505D01*
X-1313664Y426372D01*
X-1314530Y426913D01*
X-1315396Y427021D01*
X-1316407Y426805D01*
X-1317128Y426047D01*
X-1317417Y425289D01*
Y424314D01*
G01Y425289D02*
X-1317850Y425938D01*
X-1318572Y426480D01*
X-1319438Y426696D01*
X-1320304Y426480D01*
X-1321026Y425938D01*
X-1321459Y424964D01*
X-1321315Y423990D01*
X-1320737Y423015D01*
G01X-1291066Y389670D02*
X-1292942Y389887D01*
X-1294530Y390212D01*
X-1295974Y390645D01*
X-1297562Y391186D01*
X-1299727Y392052D01*
Y387722D01*
G01X-1291066Y398548D02*
X-1291210Y399306D01*
X-1291643Y400172D01*
X-1292365Y400713D01*
X-1293376Y400930D01*
X-1294386Y400713D01*
X-1295252Y400064D01*
X-1295685Y399089D01*
Y398007D01*
X-1295974Y397357D01*
X-1296696Y396816D01*
X-1297706Y396599D01*
X-1298717Y396924D01*
X-1299438Y397682D01*
X-1299727Y398548D01*
X-1299438Y399414D01*
X-1298717Y400172D01*
X-1297706Y400497D01*
X-1296696Y400280D01*
X-1295974Y399739D01*
X-1295685Y399089D01*
Y398007D01*
X-1295252Y397032D01*
X-1294386Y396383D01*
X-1293376Y396166D01*
X-1292365Y396383D01*
X-1291643Y396924D01*
X-1291210Y397790D01*
X-1291066Y398548D01*
G01X-1290777Y407209D02*
X-1290922Y406992D01*
X-1291210D01*
X-1291355Y407209D01*
X-1291210Y407426D01*
X-1290922D01*
X-1290777Y407209D01*
G01X-1292365Y413488D02*
X-1291643Y414138D01*
X-1291210Y414896D01*
X-1291066Y415870D01*
X-1291355Y416844D01*
X-1291932Y417602D01*
X-1292942Y418144D01*
X-1294097Y418252D01*
X-1295252Y418035D01*
X-1295974Y417494D01*
X-1296551Y416736D01*
X-1296696Y415978D01*
X-1296551Y415220D01*
X-1295974Y414246D01*
X-1299727Y414571D01*
Y417494D01*
G01X-1292365Y422149D02*
X-1291643Y422799D01*
X-1291210Y423557D01*
X-1291066Y424531D01*
X-1291355Y425505D01*
X-1291932Y426263D01*
X-1292942Y426805D01*
X-1294097Y426913D01*
X-1295252Y426696D01*
X-1295974Y426155D01*
X-1296551Y425397D01*
X-1296696Y424639D01*
X-1296551Y423881D01*
X-1295974Y422907D01*
X-1299727Y423232D01*
Y426155D01*
G01X-1298284Y374836D02*
X-1299149Y375486D01*
X-1299583Y376243D01*
X-1299727Y377110D01*
X-1299438Y378192D01*
X-1298717Y378950D01*
X-1297851Y379167D01*
X-1296984Y379058D01*
X-1296263Y378625D01*
X-1294819Y376460D01*
X-1293809Y375486D01*
X-1292365Y374836D01*
X-1291066Y374619D01*
Y379167D01*
G01X-1293953Y384147D02*
Y386961D01*
G01X-1291263Y389670D02*
X-1293139Y389887D01*
X-1294727Y390212D01*
X-1296171Y390645D01*
X-1297759Y391186D01*
X-1299924Y392052D01*
Y387722D01*
G01X-1291263Y398548D02*
X-1291407Y399306D01*
X-1291840Y400172D01*
X-1292562Y400713D01*
X-1293573Y400930D01*
X-1294583Y400713D01*
X-1295449Y400064D01*
X-1295882Y399089D01*
Y398007D01*
X-1296171Y397357D01*
X-1296893Y396816D01*
X-1297903Y396599D01*
X-1298914Y396924D01*
X-1299635Y397682D01*
X-1299924Y398548D01*
X-1299635Y399414D01*
X-1298914Y400172D01*
X-1297903Y400497D01*
X-1296893Y400280D01*
X-1296171Y399739D01*
X-1295882Y399089D01*
Y398007D01*
X-1295449Y397032D01*
X-1294583Y396383D01*
X-1293573Y396166D01*
X-1292562Y396383D01*
X-1291840Y396924D01*
X-1291407Y397790D01*
X-1291263Y398548D01*
G01X-1290974Y407209D02*
X-1291119Y406992D01*
X-1291407D01*
X-1291552Y407209D01*
X-1291407Y407426D01*
X-1291119D01*
X-1290974Y407209D01*
G01X-1292562Y413488D02*
X-1291840Y414138D01*
X-1291407Y414896D01*
X-1291263Y415870D01*
X-1291552Y416844D01*
X-1292129Y417602D01*
X-1293139Y418144D01*
X-1294294Y418252D01*
X-1295449Y418035D01*
X-1296171Y417494D01*
X-1296748Y416736D01*
X-1296893Y415978D01*
X-1296748Y415220D01*
X-1296171Y414246D01*
X-1299924Y414571D01*
Y417494D01*
G01Y424531D02*
X-1299635Y423665D01*
X-1298914Y423015D01*
X-1298048Y422582D01*
X-1296893Y422257D01*
X-1295593Y422149D01*
X-1294294Y422257D01*
X-1293139Y422582D01*
X-1292273Y423015D01*
X-1291552Y423665D01*
X-1291263Y424531D01*
X-1291552Y425397D01*
X-1292273Y426047D01*
X-1293139Y426480D01*
X-1294294Y426805D01*
X-1295593Y426913D01*
X-1296893Y426805D01*
X-1298048Y426480D01*
X-1298914Y426047D01*
X-1299635Y425397D01*
X-1299924Y424531D01*
G01X-1293268Y626066D02*
X-1301348Y619481D01*
X-1298330Y616954D01*
X-1293268Y626066D01*
G01X-1340367Y877225D02*
X-1337660Y885886D01*
X-1334953Y877225D01*
G01X-1335928Y880256D02*
X-1339392D01*
G01X-1325549Y879425D02*
X-1315434Y881944D01*
X-1325762Y883357D01*
X-1325549Y879425D01*
G01X-1345687Y1275797D02*
X-1346770Y1277241D01*
X-1347311Y1278684D01*
Y1284458D01*
X-1346770Y1285902D01*
X-1345687Y1287345D01*
G01X-1338650Y1278684D02*
Y1287345D01*
X-1336052D01*
X-1335186Y1286912D01*
X-1334536Y1285902D01*
X-1334320Y1284747D01*
X-1334536Y1283592D01*
X-1335078Y1282726D01*
X-1336052Y1282293D01*
X-1338650D01*
G01X-1330531Y1278684D02*
X-1327824Y1287345D01*
X-1325117Y1278684D01*
G01X-1326092Y1281715D02*
X-1329556D01*
G01X-1321545Y1278684D02*
Y1287345D01*
X-1319380D01*
X-1318513Y1286912D01*
X-1317864Y1286335D01*
X-1317322Y1285469D01*
X-1316889Y1284458D01*
X-1316781Y1283014D01*
X-1316889Y1281571D01*
X-1317322Y1280560D01*
X-1317864Y1279694D01*
X-1318513Y1279117D01*
X-1319380Y1278684D01*
X-1321545D01*
G01X-1309961Y1275797D02*
X-1308878Y1277241D01*
X-1308337Y1278684D01*
Y1284458D01*
X-1308878Y1285902D01*
X-1309961Y1287345D01*
G01X-1350808Y1450413D02*
X-1349956Y1449088D01*
X-1348819Y1448330D01*
X-1347541Y1448141D01*
X-1346405Y1448330D01*
X-1345268Y1449277D01*
X-1344558Y1450413D01*
X-1344416Y1451550D01*
X-1344700Y1452875D01*
X-1345695Y1453822D01*
X-1346689Y1454201D01*
X-1347967D01*
G01X-1346689D02*
X-1345837Y1454769D01*
X-1345126Y1455715D01*
X-1344842Y1456852D01*
X-1345126Y1457988D01*
X-1345837Y1458935D01*
X-1347115Y1459503D01*
X-1348393Y1459314D01*
X-1349671Y1458556D01*
G01X-1224906Y225979D02*
X-1217315Y233123D01*
X-1220505Y235429D01*
X-1224906Y225979D01*
G01X-1248658Y347356D02*
X-1249308Y347789D01*
X-1250066Y348078D01*
X-1250932D01*
X-1251906Y347645D01*
X-1252664Y346923D01*
X-1253205Y346057D01*
X-1253639Y344614D01*
X-1253747Y343314D01*
X-1253530Y342015D01*
X-1253205Y341149D01*
X-1252556Y340283D01*
X-1251798Y339706D01*
X-1251040Y339417D01*
X-1250282D01*
X-1249524Y339706D01*
X-1248875Y340139D01*
X-1248333Y340716D01*
G01X-1242379Y339417D02*
X-1243245Y339561D01*
X-1244003Y340139D01*
X-1244653Y341005D01*
X-1245086Y342015D01*
X-1245302Y343170D01*
Y344325D01*
X-1245086Y345480D01*
X-1244653Y346490D01*
X-1244003Y347356D01*
X-1243245Y347934D01*
X-1242379Y348078D01*
X-1241513Y347934D01*
X-1240755Y347356D01*
X-1240105Y346490D01*
X-1239672Y345480D01*
X-1239456Y344325D01*
Y343170D01*
X-1239672Y342015D01*
X-1240105Y341005D01*
X-1240755Y340139D01*
X-1241513Y339561D01*
X-1242379Y339417D01*
G01X-1236533D02*
Y348078D01*
X-1233718Y340860D01*
X-1230903Y348078D01*
Y339417D01*
G01X-1227222D02*
Y348078D01*
X-1224624D01*
X-1223758Y347645D01*
X-1223108Y346635D01*
X-1222892Y345480D01*
X-1223108Y344325D01*
X-1223650Y343459D01*
X-1224624Y343026D01*
X-1227222D01*
G01X-1216396Y339417D02*
X-1217262Y339561D01*
X-1218020Y340139D01*
X-1218670Y341005D01*
X-1219103Y342015D01*
X-1219319Y343170D01*
Y344325D01*
X-1219103Y345480D01*
X-1218670Y346490D01*
X-1218020Y347356D01*
X-1217262Y347934D01*
X-1216396Y348078D01*
X-1215530Y347934D01*
X-1214772Y347356D01*
X-1214122Y346490D01*
X-1213689Y345480D01*
X-1213473Y344325D01*
Y343170D01*
X-1213689Y342015D01*
X-1214122Y341005D01*
X-1214772Y340139D01*
X-1215530Y339561D01*
X-1216396Y339417D01*
G01X-1210225D02*
Y348078D01*
X-1205245Y339417D01*
Y348078D01*
G01X-1196909Y339417D02*
X-1201239D01*
Y348078D01*
X-1196909D01*
G01X-1198641Y343892D02*
X-1201239D01*
G01X-1192903Y339417D02*
Y348078D01*
X-1187923Y339417D01*
Y348078D01*
G01X-1181752D02*
Y339417D01*
G01X-1184242Y348078D02*
X-1179262D01*
G01X-1166704Y340572D02*
X-1165837Y339850D01*
X-1164863Y339417D01*
X-1163997D01*
X-1163131Y339850D01*
X-1162481Y340572D01*
X-1162156Y341582D01*
X-1162373Y342593D01*
X-1162914Y343459D01*
X-1163889Y344036D01*
X-1165188Y344325D01*
X-1165946Y344902D01*
X-1166271Y345913D01*
X-1166054Y346923D01*
X-1165513Y347645D01*
X-1164755Y348078D01*
X-1163997D01*
X-1163239Y347789D01*
X-1162589Y347068D01*
G01X-1157068Y348078D02*
X-1154470D01*
G01X-1155769D02*
Y339417D01*
G01X-1157068D02*
X-1154470D01*
G01X-1149490D02*
Y348078D01*
X-1147325D01*
X-1146458Y347645D01*
X-1145809Y347068D01*
X-1145267Y346202D01*
X-1144834Y345191D01*
X-1144726Y343747D01*
X-1144834Y342304D01*
X-1145267Y341293D01*
X-1145809Y340427D01*
X-1146458Y339850D01*
X-1147325Y339417D01*
X-1149490D01*
G01X-1136282D02*
X-1140612D01*
Y348078D01*
X-1136282D01*
G01X-1138014Y343892D02*
X-1140612D01*
G01X-1239194Y947976D02*
Y956637D01*
X-1240493Y954905D01*
G01Y947976D02*
X-1237895D01*
G01X-1232590Y955194D02*
X-1231940Y956059D01*
X-1231183Y956493D01*
X-1230316Y956637D01*
X-1229234Y956348D01*
X-1228476Y955627D01*
X-1228259Y954761D01*
X-1228368Y953894D01*
X-1228801Y953173D01*
X-1230966Y951729D01*
X-1231940Y950719D01*
X-1232590Y949275D01*
X-1232807Y947976D01*
X-1228259D01*
G01X-1221872Y956637D02*
X-1222738Y956348D01*
X-1223388Y955627D01*
X-1223821Y954761D01*
X-1224146Y953606D01*
X-1224254Y952306D01*
X-1224146Y951007D01*
X-1223821Y949852D01*
X-1223388Y948986D01*
X-1222738Y948265D01*
X-1221872Y947976D01*
X-1221006Y948265D01*
X-1220356Y948986D01*
X-1219923Y949852D01*
X-1219598Y951007D01*
X-1219490Y952306D01*
X-1219598Y953606D01*
X-1219923Y954761D01*
X-1220356Y955627D01*
X-1221006Y956348D01*
X-1221872Y956637D01*
G01X-1213211Y947687D02*
X-1213428Y947832D01*
Y948120D01*
X-1213211Y948265D01*
X-1212994Y948120D01*
Y947832D01*
X-1213211Y947687D01*
G01X-1204550Y956637D02*
X-1205416Y956348D01*
X-1206066Y955627D01*
X-1206499Y954761D01*
X-1206824Y953606D01*
X-1206932Y952306D01*
X-1206824Y951007D01*
X-1206499Y949852D01*
X-1206066Y948986D01*
X-1205416Y948265D01*
X-1204550Y947976D01*
X-1203684Y948265D01*
X-1203034Y948986D01*
X-1202601Y949852D01*
X-1202276Y951007D01*
X-1202168Y952306D01*
X-1202276Y953606D01*
X-1202601Y954761D01*
X-1203034Y955627D01*
X-1203684Y956348D01*
X-1204550Y956637D01*
G01X-1195889D02*
X-1196755Y956348D01*
X-1197405Y955627D01*
X-1197838Y954761D01*
X-1198163Y953606D01*
X-1198271Y952306D01*
X-1198163Y951007D01*
X-1197838Y949852D01*
X-1197405Y948986D01*
X-1196755Y948265D01*
X-1195889Y947976D01*
X-1195023Y948265D01*
X-1194373Y948986D01*
X-1193940Y949852D01*
X-1193615Y951007D01*
X-1193507Y952306D01*
X-1193615Y953606D01*
X-1193940Y954761D01*
X-1194373Y955627D01*
X-1195023Y956348D01*
X-1195889Y956637D01*
G01X-1285357Y996069D02*
X-1285501Y996827D01*
X-1285934Y997693D01*
X-1286656Y998234D01*
X-1287667Y998451D01*
X-1288677Y998234D01*
X-1289543Y997585D01*
X-1289976Y996610D01*
Y995528D01*
X-1290265Y994878D01*
X-1290987Y994337D01*
X-1291997Y994120D01*
X-1293008Y994445D01*
X-1293729Y995203D01*
X-1294018Y996069D01*
X-1293729Y996935D01*
X-1293008Y997693D01*
X-1291997Y998018D01*
X-1290987Y997801D01*
X-1290265Y997260D01*
X-1289976Y996610D01*
Y995528D01*
X-1289543Y994553D01*
X-1288677Y993904D01*
X-1287667Y993687D01*
X-1286656Y993904D01*
X-1285934Y994445D01*
X-1285501Y995311D01*
X-1285357Y996069D01*
G01X-1294018Y1004730D02*
X-1293729Y1003864D01*
X-1293008Y1003214D01*
X-1292142Y1002781D01*
X-1290987Y1002456D01*
X-1289687Y1002348D01*
X-1288388Y1002456D01*
X-1287233Y1002781D01*
X-1286367Y1003214D01*
X-1285646Y1003864D01*
X-1285357Y1004730D01*
X-1285646Y1005596D01*
X-1286367Y1006246D01*
X-1287233Y1006679D01*
X-1288388Y1007004D01*
X-1289687Y1007112D01*
X-1290987Y1007004D01*
X-1292142Y1006679D01*
X-1293008Y1006246D01*
X-1293729Y1005596D01*
X-1294018Y1004730D01*
G01X-1285068Y1013391D02*
X-1285213Y1013174D01*
X-1285501D01*
X-1285646Y1013391D01*
X-1285501Y1013608D01*
X-1285213D01*
X-1285068Y1013391D01*
G01X-1294018Y1022052D02*
X-1293729Y1021186D01*
X-1293008Y1020536D01*
X-1292142Y1020103D01*
X-1290987Y1019778D01*
X-1289687Y1019670D01*
X-1288388Y1019778D01*
X-1287233Y1020103D01*
X-1286367Y1020536D01*
X-1285646Y1021186D01*
X-1285357Y1022052D01*
X-1285646Y1022918D01*
X-1286367Y1023568D01*
X-1287233Y1024001D01*
X-1288388Y1024326D01*
X-1289687Y1024434D01*
X-1290987Y1024326D01*
X-1292142Y1024001D01*
X-1293008Y1023568D01*
X-1293729Y1022918D01*
X-1294018Y1022052D01*
G01Y1030713D02*
X-1293729Y1029847D01*
X-1293008Y1029197D01*
X-1292142Y1028764D01*
X-1290987Y1028439D01*
X-1289687Y1028331D01*
X-1288388Y1028439D01*
X-1287233Y1028764D01*
X-1286367Y1029197D01*
X-1285646Y1029847D01*
X-1285357Y1030713D01*
X-1285646Y1031579D01*
X-1286367Y1032229D01*
X-1287233Y1032662D01*
X-1288388Y1032987D01*
X-1289687Y1033095D01*
X-1290987Y1032987D01*
X-1292142Y1032662D01*
X-1293008Y1032229D01*
X-1293729Y1031579D01*
X-1294018Y1030713D01*
G01X-1237155Y1281056D02*
X-1236434Y1281814D01*
X-1236145Y1282680D01*
X-1236434Y1283547D01*
X-1237300Y1284304D01*
X-1238599Y1284846D01*
X-1239898Y1285062D01*
X-1241486D01*
X-1242785Y1284846D01*
X-1243940Y1284304D01*
X-1244517Y1283655D01*
X-1244806Y1282897D01*
X-1244517Y1282031D01*
X-1243940Y1281381D01*
X-1243074Y1280948D01*
X-1241919Y1280732D01*
X-1240909Y1280948D01*
X-1239898Y1281490D01*
X-1239321Y1282139D01*
X-1239176Y1282897D01*
X-1239465Y1283763D01*
X-1240187Y1284413D01*
X-1241486Y1285062D01*
G01X-1243363Y1289501D02*
X-1244228Y1290151D01*
X-1244662Y1290908D01*
X-1244806Y1291775D01*
X-1244517Y1292857D01*
X-1243796Y1293615D01*
X-1242930Y1293832D01*
X-1242063Y1293723D01*
X-1241342Y1293290D01*
X-1239898Y1291125D01*
X-1238888Y1290151D01*
X-1237444Y1289501D01*
X-1236145Y1289284D01*
Y1293832D01*
G01X-1235856Y1300219D02*
X-1236001Y1300002D01*
X-1236289D01*
X-1236434Y1300219D01*
X-1236289Y1300436D01*
X-1236001D01*
X-1235856Y1300219D01*
G01X-1237444Y1306498D02*
X-1236722Y1307148D01*
X-1236289Y1307906D01*
X-1236145Y1308880D01*
X-1236434Y1309854D01*
X-1237011Y1310612D01*
X-1238021Y1311154D01*
X-1239176Y1311262D01*
X-1240331Y1311045D01*
X-1241053Y1310504D01*
X-1241630Y1309746D01*
X-1241775Y1308988D01*
X-1241630Y1308230D01*
X-1241053Y1307256D01*
X-1244806Y1307581D01*
Y1310504D01*
G01Y1317541D02*
X-1244517Y1316675D01*
X-1243796Y1316025D01*
X-1242930Y1315592D01*
X-1241775Y1315267D01*
X-1240475Y1315159D01*
X-1239176Y1315267D01*
X-1238021Y1315592D01*
X-1237155Y1316025D01*
X-1236434Y1316675D01*
X-1236145Y1317541D01*
X-1236434Y1318407D01*
X-1237155Y1319057D01*
X-1238021Y1319490D01*
X-1239176Y1319815D01*
X-1240475Y1319923D01*
X-1241775Y1319815D01*
X-1242930Y1319490D01*
X-1243796Y1319057D01*
X-1244517Y1318407D01*
X-1244806Y1317541D01*
G01X-1228491Y1217692D02*
X-1219147Y1222312D01*
X-1221527Y1225448D01*
X-1228491Y1217692D01*
G01X-1230127Y1231827D02*
X-1226092Y1241438D01*
X-1229944Y1242249D01*
X-1230127Y1231827D01*
G01X-1158893Y-651592D02*
X-1158026Y-652314D01*
X-1157052Y-652747D01*
X-1156186D01*
X-1155320Y-652314D01*
X-1154670Y-651592D01*
X-1154345Y-650582D01*
X-1154562Y-649571D01*
X-1155103Y-648705D01*
X-1156078Y-648128D01*
X-1157377Y-647839D01*
X-1158135Y-647262D01*
X-1158460Y-646251D01*
X-1158243Y-645241D01*
X-1157702Y-644519D01*
X-1156944Y-644086D01*
X-1156186D01*
X-1155428Y-644375D01*
X-1154778Y-645096D01*
G01X-1147958Y-652747D02*
X-1148824Y-652603D01*
X-1149582Y-652025D01*
X-1150232Y-651159D01*
X-1150665Y-650149D01*
X-1150881Y-648994D01*
Y-647839D01*
X-1150665Y-646684D01*
X-1150232Y-645674D01*
X-1149582Y-644808D01*
X-1148824Y-644230D01*
X-1147958Y-644086D01*
X-1147092Y-644230D01*
X-1146334Y-644808D01*
X-1145684Y-645674D01*
X-1145251Y-646684D01*
X-1145035Y-647839D01*
Y-648994D01*
X-1145251Y-650149D01*
X-1145684Y-651159D01*
X-1146334Y-652025D01*
X-1147092Y-652603D01*
X-1147958Y-652747D01*
G01X-1141462Y-644086D02*
Y-652747D01*
X-1137132D01*
G01X-1133018D02*
Y-644086D01*
X-1130853D01*
X-1129986Y-644519D01*
X-1129337Y-645096D01*
X-1128795Y-645962D01*
X-1128362Y-646973D01*
X-1128254Y-648417D01*
X-1128362Y-649860D01*
X-1128795Y-650871D01*
X-1129337Y-651737D01*
X-1129986Y-652314D01*
X-1130853Y-652747D01*
X-1133018D01*
G01X-1119810D02*
X-1124140D01*
Y-644086D01*
X-1119810D01*
G01X-1121542Y-648272D02*
X-1124140D01*
G01X-1115479Y-652747D02*
Y-644086D01*
X-1112773D01*
X-1111907Y-644519D01*
X-1111365Y-645096D01*
X-1111149Y-646251D01*
X-1111365Y-647406D01*
X-1112015Y-648128D01*
X-1112773Y-648561D01*
X-1115479D01*
G01X-1112773D02*
X-1111149Y-652747D01*
G01X-1098266Y-651592D02*
X-1097399Y-652314D01*
X-1096425Y-652747D01*
X-1095559D01*
X-1094693Y-652314D01*
X-1094043Y-651592D01*
X-1093718Y-650582D01*
X-1093935Y-649571D01*
X-1094476Y-648705D01*
X-1095451Y-648128D01*
X-1096750Y-647839D01*
X-1097508Y-647262D01*
X-1097833Y-646251D01*
X-1097616Y-645241D01*
X-1097075Y-644519D01*
X-1096317Y-644086D01*
X-1095559D01*
X-1094801Y-644375D01*
X-1094151Y-645096D01*
G01X-1088630Y-644086D02*
X-1086032D01*
G01X-1087331D02*
Y-652747D01*
G01X-1088630D02*
X-1086032D01*
G01X-1081052D02*
Y-644086D01*
X-1078887D01*
X-1078020Y-644519D01*
X-1077371Y-645096D01*
X-1076829Y-645962D01*
X-1076396Y-646973D01*
X-1076288Y-648417D01*
X-1076396Y-649860D01*
X-1076829Y-650871D01*
X-1077371Y-651737D01*
X-1078020Y-652314D01*
X-1078887Y-652747D01*
X-1081052D01*
G01X-1067844D02*
X-1072174D01*
Y-644086D01*
X-1067844D01*
G01X-1069576Y-648272D02*
X-1072174D01*
G01X-1201663Y-388233D02*
X-1201013Y-389243D01*
X-1200147Y-389821D01*
X-1199173Y-389965D01*
X-1198307Y-389821D01*
X-1197440Y-389099D01*
X-1196899Y-388233D01*
X-1196791Y-387367D01*
X-1197007Y-386356D01*
X-1197765Y-385635D01*
X-1198523Y-385346D01*
X-1199498D01*
G01X-1198523D02*
X-1197874Y-384913D01*
X-1197332Y-384191D01*
X-1197116Y-383325D01*
X-1197332Y-382459D01*
X-1197874Y-381737D01*
X-1198848Y-381304D01*
X-1199822Y-381448D01*
X-1200797Y-382026D01*
G01X-1189321Y-389965D02*
Y-381304D01*
X-1193327Y-387511D01*
X-1187913D01*
G01X-1181959Y-390254D02*
X-1182176Y-390109D01*
Y-389821D01*
X-1181959Y-389676D01*
X-1181742Y-389821D01*
Y-390109D01*
X-1181959Y-390254D01*
G01X-1173298Y-389965D02*
X-1172540Y-389821D01*
X-1171674Y-389388D01*
X-1171133Y-388666D01*
X-1170916Y-387655D01*
X-1171133Y-386645D01*
X-1171782Y-385779D01*
X-1172757Y-385346D01*
X-1173839D01*
X-1174489Y-385057D01*
X-1175030Y-384335D01*
X-1175247Y-383325D01*
X-1174922Y-382314D01*
X-1174164Y-381593D01*
X-1173298Y-381304D01*
X-1172432Y-381593D01*
X-1171674Y-382314D01*
X-1171349Y-383325D01*
X-1171566Y-384335D01*
X-1172107Y-385057D01*
X-1172757Y-385346D01*
X-1173839D01*
X-1174814Y-385779D01*
X-1175463Y-386645D01*
X-1175680Y-387655D01*
X-1175463Y-388666D01*
X-1174922Y-389388D01*
X-1174056Y-389821D01*
X-1173298Y-389965D01*
G01X-1167019Y-388666D02*
X-1166369Y-389388D01*
X-1165611Y-389821D01*
X-1164637Y-389965D01*
X-1163663Y-389676D01*
X-1162905Y-389099D01*
X-1162363Y-388089D01*
X-1162255Y-386934D01*
X-1162472Y-385779D01*
X-1163013Y-385057D01*
X-1163771Y-384480D01*
X-1164529Y-384335D01*
X-1165287Y-384480D01*
X-1166261Y-385057D01*
X-1165936Y-381304D01*
X-1163013D01*
G01X-1201778Y-362446D02*
Y-353785D01*
X-1205784Y-359992D01*
X-1200370D01*
G01X-1194416Y-362446D02*
Y-353785D01*
X-1195715Y-355517D01*
G01Y-362446D02*
X-1193117D01*
G01X-1185755Y-362735D02*
X-1185972Y-362590D01*
Y-362302D01*
X-1185755Y-362157D01*
X-1185538Y-362302D01*
Y-362590D01*
X-1185755Y-362735D01*
G01X-1177094Y-362446D02*
X-1176336Y-362302D01*
X-1175470Y-361869D01*
X-1174929Y-361147D01*
X-1174712Y-360136D01*
X-1174929Y-359126D01*
X-1175578Y-358260D01*
X-1176553Y-357827D01*
X-1177635D01*
X-1178285Y-357538D01*
X-1178826Y-356816D01*
X-1179043Y-355806D01*
X-1178718Y-354795D01*
X-1177960Y-354074D01*
X-1177094Y-353785D01*
X-1176228Y-354074D01*
X-1175470Y-354795D01*
X-1175145Y-355806D01*
X-1175362Y-356816D01*
X-1175903Y-357538D01*
X-1176553Y-357827D01*
X-1177635D01*
X-1178610Y-358260D01*
X-1179259Y-359126D01*
X-1179476Y-360136D01*
X-1179259Y-361147D01*
X-1178718Y-361869D01*
X-1177852Y-362302D01*
X-1177094Y-362446D01*
G01X-1167134D02*
Y-353785D01*
X-1171140Y-359992D01*
X-1165726D01*
G01X-1173105Y266564D02*
X-1172347Y265843D01*
X-1171481Y265554D01*
X-1170614Y265843D01*
X-1169857Y266709D01*
X-1169315Y268008D01*
X-1169099Y269307D01*
Y270895D01*
X-1169315Y272194D01*
X-1169857Y273349D01*
X-1170506Y273926D01*
X-1171264Y274215D01*
X-1172130Y273926D01*
X-1172780Y273349D01*
X-1173213Y272483D01*
X-1173429Y271328D01*
X-1173213Y270318D01*
X-1172671Y269307D01*
X-1172022Y268730D01*
X-1171264Y268585D01*
X-1170398Y268874D01*
X-1169748Y269596D01*
X-1169099Y270895D01*
G01X-1162603Y265265D02*
X-1162820Y265410D01*
Y265698D01*
X-1162603Y265843D01*
X-1162386Y265698D01*
Y265410D01*
X-1162603Y265265D01*
G01X-1156324Y266853D02*
X-1155674Y266131D01*
X-1154916Y265698D01*
X-1153942Y265554D01*
X-1152968Y265843D01*
X-1152210Y266420D01*
X-1151668Y267430D01*
X-1151560Y268585D01*
X-1151777Y269740D01*
X-1152318Y270462D01*
X-1153076Y271039D01*
X-1153834Y271184D01*
X-1154592Y271039D01*
X-1155566Y270462D01*
X-1155241Y274215D01*
X-1152318D01*
G01X-1145281D02*
X-1146147Y273926D01*
X-1146797Y273205D01*
X-1147230Y272339D01*
X-1147555Y271184D01*
X-1147663Y269884D01*
X-1147555Y268585D01*
X-1147230Y267430D01*
X-1146797Y266564D01*
X-1146147Y265843D01*
X-1145281Y265554D01*
X-1144415Y265843D01*
X-1143765Y266564D01*
X-1143332Y267430D01*
X-1143007Y268585D01*
X-1142899Y269884D01*
X-1143007Y271184D01*
X-1143332Y272339D01*
X-1143765Y273205D01*
X-1144415Y273926D01*
X-1145281Y274215D01*
G01X-1184653Y265554D02*
Y271328D01*
G01Y269884D02*
X-1184219Y270606D01*
X-1183570Y271184D01*
X-1182704Y271328D01*
X-1181946Y271184D01*
X-1181296Y270606D01*
X-1180971Y269596D01*
Y265554D01*
G01X-1194806Y381226D02*
X-1203467D01*
X-1201735Y379927D01*
G01X-1194806D02*
Y382525D01*
G01X-1203467Y389887D02*
X-1203178Y389021D01*
X-1202457Y388371D01*
X-1201591Y387938D01*
X-1200436Y387613D01*
X-1199136Y387505D01*
X-1197837Y387613D01*
X-1196682Y387938D01*
X-1195816Y388371D01*
X-1195095Y389021D01*
X-1194806Y389887D01*
X-1195095Y390753D01*
X-1195816Y391403D01*
X-1196682Y391836D01*
X-1197837Y392161D01*
X-1199136Y392269D01*
X-1200436Y392161D01*
X-1201591Y391836D01*
X-1202457Y391403D01*
X-1203178Y390753D01*
X-1203467Y389887D01*
G01X-1196538Y396166D02*
X-1195528Y396816D01*
X-1194950Y397682D01*
X-1194806Y398656D01*
X-1194950Y399522D01*
X-1195672Y400389D01*
X-1196538Y400930D01*
X-1197404Y401038D01*
X-1198415Y400822D01*
X-1199136Y400064D01*
X-1199425Y399306D01*
Y398331D01*
G01Y399306D02*
X-1199858Y399955D01*
X-1200580Y400497D01*
X-1201446Y400713D01*
X-1202312Y400497D01*
X-1203034Y399955D01*
X-1203467Y398981D01*
X-1203323Y398007D01*
X-1202745Y397032D01*
G01X-1194517Y407209D02*
X-1194662Y406992D01*
X-1194950D01*
X-1195095Y407209D01*
X-1194950Y407426D01*
X-1194662D01*
X-1194517Y407209D01*
G01X-1203467Y415870D02*
X-1203178Y415004D01*
X-1202457Y414354D01*
X-1201591Y413921D01*
X-1200436Y413596D01*
X-1199136Y413488D01*
X-1197837Y413596D01*
X-1196682Y413921D01*
X-1195816Y414354D01*
X-1195095Y415004D01*
X-1194806Y415870D01*
X-1195095Y416736D01*
X-1195816Y417386D01*
X-1196682Y417819D01*
X-1197837Y418144D01*
X-1199136Y418252D01*
X-1200436Y418144D01*
X-1201591Y417819D01*
X-1202457Y417386D01*
X-1203178Y416736D01*
X-1203467Y415870D01*
G01Y424531D02*
X-1203178Y423665D01*
X-1202457Y423015D01*
X-1201591Y422582D01*
X-1200436Y422257D01*
X-1199136Y422149D01*
X-1197837Y422257D01*
X-1196682Y422582D01*
X-1195816Y423015D01*
X-1195095Y423665D01*
X-1194806Y424531D01*
X-1195095Y425397D01*
X-1195816Y426047D01*
X-1196682Y426480D01*
X-1197837Y426805D01*
X-1199136Y426913D01*
X-1200436Y426805D01*
X-1201591Y426480D01*
X-1202457Y426047D01*
X-1203178Y425397D01*
X-1203467Y424531D01*
G01X-1170947Y889117D02*
Y897778D01*
X-1172246Y896046D01*
G01Y889117D02*
X-1169648D01*
G01X-1162286Y897778D02*
X-1163152Y897489D01*
X-1163802Y896768D01*
X-1164235Y895902D01*
X-1164560Y894747D01*
X-1164668Y893447D01*
X-1164560Y892148D01*
X-1164235Y890993D01*
X-1163802Y890127D01*
X-1163152Y889406D01*
X-1162286Y889117D01*
X-1161420Y889406D01*
X-1160770Y890127D01*
X-1160337Y890993D01*
X-1160012Y892148D01*
X-1159904Y893447D01*
X-1160012Y894747D01*
X-1160337Y895902D01*
X-1160770Y896768D01*
X-1161420Y897489D01*
X-1162286Y897778D01*
G01X-1156007Y890416D02*
X-1155357Y889694D01*
X-1154599Y889261D01*
X-1153625Y889117D01*
X-1152651Y889406D01*
X-1151893Y889983D01*
X-1151351Y890993D01*
X-1151243Y892148D01*
X-1151460Y893303D01*
X-1152001Y894025D01*
X-1152759Y894602D01*
X-1153517Y894747D01*
X-1154275Y894602D01*
X-1155249Y894025D01*
X-1154924Y897778D01*
X-1152001D01*
G01X-1144964Y888828D02*
X-1145181Y888973D01*
Y889261D01*
X-1144964Y889406D01*
X-1144747Y889261D01*
Y888973D01*
X-1144964Y888828D01*
G01X-1136303Y897778D02*
X-1137169Y897489D01*
X-1137819Y896768D01*
X-1138252Y895902D01*
X-1138577Y894747D01*
X-1138685Y893447D01*
X-1138577Y892148D01*
X-1138252Y890993D01*
X-1137819Y890127D01*
X-1137169Y889406D01*
X-1136303Y889117D01*
X-1135437Y889406D01*
X-1134787Y890127D01*
X-1134354Y890993D01*
X-1134029Y892148D01*
X-1133921Y893447D01*
X-1134029Y894747D01*
X-1134354Y895902D01*
X-1134787Y896768D01*
X-1135437Y897489D01*
X-1136303Y897778D01*
G01X-1130024Y890416D02*
X-1129374Y889694D01*
X-1128616Y889261D01*
X-1127642Y889117D01*
X-1126668Y889406D01*
X-1125910Y889983D01*
X-1125368Y890993D01*
X-1125260Y892148D01*
X-1125477Y893303D01*
X-1126018Y894025D01*
X-1126776Y894602D01*
X-1127534Y894747D01*
X-1128292Y894602D01*
X-1129266Y894025D01*
X-1128941Y897778D01*
X-1126018D01*
G01X-1192050Y1279767D02*
X-1200711D01*
X-1198979Y1278468D01*
G01X-1192050D02*
Y1281066D01*
G01X-1200711Y1288428D02*
X-1200422Y1287562D01*
X-1199701Y1286912D01*
X-1198835Y1286479D01*
X-1197680Y1286154D01*
X-1196380Y1286046D01*
X-1195081Y1286154D01*
X-1193926Y1286479D01*
X-1193060Y1286912D01*
X-1192339Y1287562D01*
X-1192050Y1288428D01*
X-1192339Y1289294D01*
X-1193060Y1289944D01*
X-1193926Y1290377D01*
X-1195081Y1290702D01*
X-1196380Y1290810D01*
X-1197680Y1290702D01*
X-1198835Y1290377D01*
X-1199701Y1289944D01*
X-1200422Y1289294D01*
X-1200711Y1288428D01*
G01X-1193782Y1294707D02*
X-1192772Y1295357D01*
X-1192194Y1296223D01*
X-1192050Y1297197D01*
X-1192194Y1298063D01*
X-1192916Y1298930D01*
X-1193782Y1299471D01*
X-1194648Y1299579D01*
X-1195659Y1299363D01*
X-1196380Y1298605D01*
X-1196669Y1297847D01*
Y1296872D01*
G01Y1297847D02*
X-1197102Y1298496D01*
X-1197824Y1299038D01*
X-1198690Y1299254D01*
X-1199556Y1299038D01*
X-1200278Y1298496D01*
X-1200711Y1297522D01*
X-1200567Y1296548D01*
X-1199989Y1295573D01*
G01X-1191761Y1305750D02*
X-1191906Y1305533D01*
X-1192194D01*
X-1192339Y1305750D01*
X-1192194Y1305967D01*
X-1191906D01*
X-1191761Y1305750D01*
G01X-1192050Y1314194D02*
X-1193926Y1314411D01*
X-1195514Y1314736D01*
X-1196958Y1315169D01*
X-1198546Y1315710D01*
X-1200711Y1316576D01*
Y1312246D01*
G01Y1323072D02*
X-1200422Y1322206D01*
X-1199701Y1321556D01*
X-1198835Y1321123D01*
X-1197680Y1320798D01*
X-1196380Y1320690D01*
X-1195081Y1320798D01*
X-1193926Y1321123D01*
X-1193060Y1321556D01*
X-1192339Y1322206D01*
X-1192050Y1323072D01*
X-1192339Y1323938D01*
X-1193060Y1324588D01*
X-1193926Y1325021D01*
X-1195081Y1325346D01*
X-1196380Y1325454D01*
X-1197680Y1325346D01*
X-1198835Y1325021D01*
X-1199701Y1324588D01*
X-1200422Y1323938D01*
X-1200711Y1323072D01*
G01X-1171301Y1251831D02*
Y1260492D01*
X-1172600Y1258760D01*
G01Y1251831D02*
X-1170002D01*
G01X-1162640D02*
Y1260492D01*
X-1163939Y1258760D01*
G01Y1251831D02*
X-1161341D01*
G01X-1155386Y1254718D02*
X-1152572D01*
G01X-1156776Y1354694D02*
X-1156018Y1353973D01*
X-1155152Y1353684D01*
X-1154285Y1353973D01*
X-1153528Y1354839D01*
X-1152986Y1356138D01*
X-1152770Y1357437D01*
Y1359025D01*
X-1152986Y1360324D01*
X-1153528Y1361479D01*
X-1154177Y1362056D01*
X-1154935Y1362345D01*
X-1155801Y1362056D01*
X-1156451Y1361479D01*
X-1156884Y1360613D01*
X-1157100Y1359458D01*
X-1156884Y1358448D01*
X-1156342Y1357437D01*
X-1155693Y1356860D01*
X-1154935Y1356715D01*
X-1154069Y1357004D01*
X-1153419Y1357726D01*
X-1152770Y1359025D01*
G01X-1146274Y1353395D02*
X-1146491Y1353540D01*
Y1353828D01*
X-1146274Y1353973D01*
X-1146057Y1353828D01*
Y1353540D01*
X-1146274Y1353395D01*
G01X-1139995Y1354983D02*
X-1139345Y1354261D01*
X-1138587Y1353828D01*
X-1137613Y1353684D01*
X-1136639Y1353973D01*
X-1135881Y1354550D01*
X-1135339Y1355560D01*
X-1135231Y1356715D01*
X-1135448Y1357870D01*
X-1135989Y1358592D01*
X-1136747Y1359169D01*
X-1137505Y1359314D01*
X-1138263Y1359169D01*
X-1139237Y1358592D01*
X-1138912Y1362345D01*
X-1135989D01*
G01X-1128952D02*
X-1129818Y1362056D01*
X-1130468Y1361335D01*
X-1130901Y1360469D01*
X-1131226Y1359314D01*
X-1131334Y1358014D01*
X-1131226Y1356715D01*
X-1130901Y1355560D01*
X-1130468Y1354694D01*
X-1129818Y1353973D01*
X-1128952Y1353684D01*
X-1128086Y1353973D01*
X-1127436Y1354694D01*
X-1127003Y1355560D01*
X-1126678Y1356715D01*
X-1126570Y1358014D01*
X-1126678Y1359314D01*
X-1127003Y1360469D01*
X-1127436Y1361335D01*
X-1128086Y1362056D01*
X-1128952Y1362345D01*
G01X-1168324Y1353684D02*
Y1359458D01*
G01Y1358014D02*
X-1167890Y1358736D01*
X-1167241Y1359314D01*
X-1166375Y1359458D01*
X-1165617Y1359314D01*
X-1164967Y1358736D01*
X-1164642Y1357726D01*
Y1353684D01*
G01X-1189869D02*
Y1362345D01*
X-1191168Y1360613D01*
G01Y1353684D02*
X-1188570D01*
G01X-1181208D02*
Y1362345D01*
X-1182507Y1360613D01*
G01Y1353684D02*
X-1179909D01*
G01X-1173954Y1356571D02*
X-1171140D01*
G01X-1126310Y-729615D02*
Y-718253D01*
X-1131565Y-726396D01*
X-1124463D01*
G01X-1113379Y-615259D02*
X-1122040D01*
X-1120308Y-616558D01*
G01X-1113379D02*
Y-613960D01*
G01X-1120597Y-608655D02*
X-1121462Y-608005D01*
X-1121896Y-607248D01*
X-1122040Y-606381D01*
X-1121751Y-605299D01*
X-1121030Y-604541D01*
X-1120164Y-604324D01*
X-1119297Y-604433D01*
X-1118576Y-604866D01*
X-1117132Y-607031D01*
X-1116122Y-608005D01*
X-1114678Y-608655D01*
X-1113379Y-608872D01*
Y-604324D01*
G01Y-596638D02*
X-1122040D01*
X-1115833Y-600644D01*
Y-595230D01*
G01X-1113090Y-589276D02*
X-1113235Y-589493D01*
X-1113523D01*
X-1113668Y-589276D01*
X-1113523Y-589059D01*
X-1113235D01*
X-1113090Y-589276D01*
G01X-1113379Y-580615D02*
X-1122040D01*
X-1120308Y-581914D01*
G01X-1113379D02*
Y-579316D01*
G01X-1116988Y-574011D02*
X-1117998Y-573253D01*
X-1118576Y-572604D01*
X-1118864Y-571737D01*
X-1118576Y-570980D01*
X-1117998Y-570438D01*
X-1117132Y-570005D01*
X-1116122Y-569897D01*
X-1115255Y-570005D01*
X-1114389Y-570438D01*
X-1113668Y-571088D01*
X-1113379Y-571846D01*
X-1113668Y-572712D01*
X-1114534Y-573470D01*
X-1115833Y-573903D01*
X-1117276Y-574011D01*
X-1119153Y-573795D01*
X-1120164Y-573470D01*
X-1121174Y-572928D01*
X-1121896Y-572171D01*
X-1122040Y-571413D01*
X-1121751Y-570655D01*
X-1121030Y-570113D01*
G01X-1120597Y-629443D02*
X-1121462Y-628793D01*
X-1121896Y-628036D01*
X-1122040Y-627169D01*
X-1121751Y-626087D01*
X-1121030Y-625329D01*
X-1120164Y-625112D01*
X-1119297Y-625221D01*
X-1118576Y-625654D01*
X-1117132Y-627819D01*
X-1116122Y-628793D01*
X-1114678Y-629443D01*
X-1113379Y-629660D01*
Y-625112D01*
G01X-1116266Y-620132D02*
Y-617318D01*
G01X-1106381Y-402908D02*
X-1103989Y-413054D01*
X-1100397Y-411443D01*
X-1106381Y-402908D01*
G01X-1107853Y-395859D02*
X-1102462Y-404781D01*
X-1099538Y-402145D01*
X-1107853Y-395859D01*
G01X-1106670Y-365977D02*
X-1097435Y-370810D01*
X-1096301Y-367040D01*
X-1106670Y-365977D01*
G01X-1140624Y262667D02*
X-1141707Y264111D01*
X-1142248Y265554D01*
Y271328D01*
X-1141707Y272772D01*
X-1140624Y274215D01*
G01X-1133587Y265554D02*
Y274215D01*
X-1130989D01*
X-1130123Y273782D01*
X-1129473Y272772D01*
X-1129257Y271617D01*
X-1129473Y270462D01*
X-1130015Y269596D01*
X-1130989Y269163D01*
X-1133587D01*
G01X-1125468Y265554D02*
X-1122761Y274215D01*
X-1120054Y265554D01*
G01X-1121029Y268585D02*
X-1124493D01*
G01X-1116482Y265554D02*
Y274215D01*
X-1114317D01*
X-1113450Y273782D01*
X-1112801Y273205D01*
X-1112259Y272339D01*
X-1111826Y271328D01*
X-1111718Y269884D01*
X-1111826Y268441D01*
X-1112259Y267430D01*
X-1112801Y266564D01*
X-1113450Y265987D01*
X-1114317Y265554D01*
X-1116482D01*
G01X-1104898Y262667D02*
X-1103815Y264111D01*
X-1103274Y265554D01*
Y271328D01*
X-1103815Y272772D01*
X-1104898Y274215D01*
G01X-1097319Y262667D02*
X-1098402Y264111D01*
X-1098943Y265554D01*
Y271328D01*
X-1098402Y272772D01*
X-1097319Y274215D01*
G01X-1090607Y265554D02*
Y274215D01*
X-1085627Y265554D01*
Y274215D01*
G01X-1079456Y265554D02*
X-1080322Y265698D01*
X-1081080Y266276D01*
X-1081730Y267142D01*
X-1082163Y268152D01*
X-1082379Y269307D01*
Y270462D01*
X-1082163Y271617D01*
X-1081730Y272627D01*
X-1081080Y273493D01*
X-1080322Y274071D01*
X-1079456Y274215D01*
X-1078590Y274071D01*
X-1077832Y273493D01*
X-1077182Y272627D01*
X-1076749Y271617D01*
X-1076533Y270462D01*
Y269307D01*
X-1076749Y268152D01*
X-1077182Y267142D01*
X-1077832Y266276D01*
X-1078590Y265698D01*
X-1079456Y265554D01*
G01X-1062134Y274215D02*
Y265554D01*
G01X-1064624Y274215D02*
X-1059644D01*
G01X-1055638Y265554D02*
Y274215D01*
X-1052932D01*
X-1052066Y273782D01*
X-1051524Y273205D01*
X-1051308Y272050D01*
X-1051524Y270895D01*
X-1052174Y270173D01*
X-1052932Y269740D01*
X-1055638D01*
G01X-1052932D02*
X-1051308Y265554D01*
G01X-1047519D02*
X-1044812Y274215D01*
X-1042105Y265554D01*
G01X-1043080Y268585D02*
X-1046544D01*
G01X-1033769Y273493D02*
X-1034419Y273926D01*
X-1035177Y274215D01*
X-1036043D01*
X-1037017Y273782D01*
X-1037775Y273060D01*
X-1038316Y272194D01*
X-1038750Y270751D01*
X-1038858Y269451D01*
X-1038641Y268152D01*
X-1038316Y267286D01*
X-1037667Y266420D01*
X-1036909Y265843D01*
X-1036151Y265554D01*
X-1035393D01*
X-1034635Y265843D01*
X-1033986Y266276D01*
X-1033444Y266853D01*
G01X-1025325Y265554D02*
X-1029655D01*
Y274215D01*
X-1025325D01*
G01X-1027057Y270029D02*
X-1029655D01*
G01X-1012875Y265554D02*
X-1010168Y274215D01*
X-1007461Y265554D01*
G01X-1008436Y268585D02*
X-1011900D01*
G01X-1001507Y274215D02*
Y265554D01*
G01X-1003997Y274215D02*
X-999017D01*
G01X-986892Y265554D02*
X-984185Y274215D01*
X-981478Y265554D01*
G01X-982453Y268585D02*
X-985917D01*
G01X-977689Y274215D02*
Y265554D01*
X-973359D01*
G01X-969028Y274215D02*
Y265554D01*
X-964698D01*
G01X-951706Y274215D02*
Y265554D01*
X-947376D01*
G01X-943587D02*
X-940880Y274215D01*
X-938173Y265554D01*
G01X-939148Y268585D02*
X-942612D01*
G01X-932219Y265554D02*
Y269451D01*
X-934384Y274215D01*
G01X-930054D02*
X-932219Y269451D01*
G01X-921393Y265554D02*
X-925723D01*
Y274215D01*
X-921393D01*
G01X-923125Y270029D02*
X-925723D01*
G01X-917062Y265554D02*
Y274215D01*
X-914356D01*
X-913490Y273782D01*
X-912948Y273205D01*
X-912732Y272050D01*
X-912948Y270895D01*
X-913598Y270173D01*
X-914356Y269740D01*
X-917062D01*
G01X-914356D02*
X-912732Y265554D01*
G01X-908510Y266709D02*
X-907643Y265987D01*
X-906669Y265554D01*
X-905803D01*
X-904937Y265987D01*
X-904287Y266709D01*
X-903962Y267719D01*
X-904179Y268730D01*
X-904720Y269596D01*
X-905695Y270173D01*
X-906994Y270462D01*
X-907752Y271039D01*
X-908077Y272050D01*
X-907860Y273060D01*
X-907319Y273782D01*
X-906561Y274215D01*
X-905803D01*
X-905045Y273926D01*
X-904395Y273205D01*
G01X-897034Y262667D02*
X-895951Y264111D01*
X-895410Y265554D01*
Y271328D01*
X-895951Y272772D01*
X-897034Y274215D01*
G01X-1094536Y947976D02*
Y956637D01*
X-1095835Y954905D01*
G01Y947976D02*
X-1093237D01*
G01X-1087932Y955194D02*
X-1087282Y956059D01*
X-1086525Y956493D01*
X-1085658Y956637D01*
X-1084576Y956348D01*
X-1083818Y955627D01*
X-1083601Y954761D01*
X-1083710Y953894D01*
X-1084143Y953173D01*
X-1086308Y951729D01*
X-1087282Y950719D01*
X-1087932Y949275D01*
X-1088149Y947976D01*
X-1083601D01*
G01X-1077214Y956637D02*
X-1078080Y956348D01*
X-1078730Y955627D01*
X-1079163Y954761D01*
X-1079488Y953606D01*
X-1079596Y952306D01*
X-1079488Y951007D01*
X-1079163Y949852D01*
X-1078730Y948986D01*
X-1078080Y948265D01*
X-1077214Y947976D01*
X-1076348Y948265D01*
X-1075698Y948986D01*
X-1075265Y949852D01*
X-1074940Y951007D01*
X-1074832Y952306D01*
X-1074940Y953606D01*
X-1075265Y954761D01*
X-1075698Y955627D01*
X-1076348Y956348D01*
X-1077214Y956637D01*
G01X-1068553Y947687D02*
X-1068770Y947832D01*
Y948120D01*
X-1068553Y948265D01*
X-1068336Y948120D01*
Y947832D01*
X-1068553Y947687D01*
G01X-1059892Y956637D02*
X-1060758Y956348D01*
X-1061408Y955627D01*
X-1061841Y954761D01*
X-1062166Y953606D01*
X-1062274Y952306D01*
X-1062166Y951007D01*
X-1061841Y949852D01*
X-1061408Y948986D01*
X-1060758Y948265D01*
X-1059892Y947976D01*
X-1059026Y948265D01*
X-1058376Y948986D01*
X-1057943Y949852D01*
X-1057618Y951007D01*
X-1057510Y952306D01*
X-1057618Y953606D01*
X-1057943Y954761D01*
X-1058376Y955627D01*
X-1059026Y956348D01*
X-1059892Y956637D01*
G01X-1051231D02*
X-1052097Y956348D01*
X-1052747Y955627D01*
X-1053180Y954761D01*
X-1053505Y953606D01*
X-1053613Y952306D01*
X-1053505Y951007D01*
X-1053180Y949852D01*
X-1052747Y948986D01*
X-1052097Y948265D01*
X-1051231Y947976D01*
X-1050365Y948265D01*
X-1049715Y948986D01*
X-1049282Y949852D01*
X-1048957Y951007D01*
X-1048849Y952306D01*
X-1048957Y953606D01*
X-1049282Y954761D01*
X-1049715Y955627D01*
X-1050365Y956348D01*
X-1051231Y956637D01*
G01X-1127434Y1081834D02*
Y1090495D01*
X-1128733Y1088763D01*
G01Y1081834D02*
X-1126135D01*
G01X-1121155Y1083133D02*
X-1120505Y1082411D01*
X-1119747Y1081978D01*
X-1118773Y1081834D01*
X-1117799Y1082123D01*
X-1117041Y1082700D01*
X-1116499Y1083710D01*
X-1116391Y1084865D01*
X-1116608Y1086020D01*
X-1117149Y1086742D01*
X-1117907Y1087319D01*
X-1118665Y1087464D01*
X-1119423Y1087319D01*
X-1120397Y1086742D01*
X-1120072Y1090495D01*
X-1117149D01*
G01X-1108813Y1081834D02*
Y1090495D01*
X-1112819Y1084288D01*
X-1107405D01*
G01X-1101451Y1081545D02*
X-1101668Y1081690D01*
Y1081978D01*
X-1101451Y1082123D01*
X-1101234Y1081978D01*
Y1081690D01*
X-1101451Y1081545D01*
G01X-1092790Y1090495D02*
X-1093656Y1090206D01*
X-1094306Y1089485D01*
X-1094739Y1088619D01*
X-1095064Y1087464D01*
X-1095172Y1086164D01*
X-1095064Y1084865D01*
X-1094739Y1083710D01*
X-1094306Y1082844D01*
X-1093656Y1082123D01*
X-1092790Y1081834D01*
X-1091924Y1082123D01*
X-1091274Y1082844D01*
X-1090841Y1083710D01*
X-1090516Y1084865D01*
X-1090408Y1086164D01*
X-1090516Y1087464D01*
X-1090841Y1088619D01*
X-1091274Y1089485D01*
X-1091924Y1090206D01*
X-1092790Y1090495D01*
G01X-1084129D02*
X-1084995Y1090206D01*
X-1085645Y1089485D01*
X-1086078Y1088619D01*
X-1086403Y1087464D01*
X-1086511Y1086164D01*
X-1086403Y1084865D01*
X-1086078Y1083710D01*
X-1085645Y1082844D01*
X-1084995Y1082123D01*
X-1084129Y1081834D01*
X-1083263Y1082123D01*
X-1082613Y1082844D01*
X-1082180Y1083710D01*
X-1081855Y1084865D01*
X-1081747Y1086164D01*
X-1081855Y1087464D01*
X-1082180Y1088619D01*
X-1082613Y1089485D01*
X-1083263Y1090206D01*
X-1084129Y1090495D01*
G01X-1105726Y1248944D02*
X-1106809Y1250388D01*
X-1107350Y1251831D01*
Y1257605D01*
X-1106809Y1259049D01*
X-1105726Y1260492D01*
G01X-1098689Y1251831D02*
Y1260492D01*
X-1096091D01*
X-1095225Y1260059D01*
X-1094575Y1259049D01*
X-1094359Y1257894D01*
X-1094575Y1256739D01*
X-1095117Y1255873D01*
X-1096091Y1255440D01*
X-1098689D01*
G01X-1087863Y1260492D02*
Y1251831D01*
G01X-1090353Y1260492D02*
X-1085373D01*
G01X-1081476Y1251831D02*
Y1260492D01*
G01X-1076928D02*
Y1251831D01*
G01Y1256161D02*
X-1081476D01*
G01X-1070000Y1248944D02*
X-1068917Y1250388D01*
X-1068376Y1251831D01*
Y1257605D01*
X-1068917Y1259049D01*
X-1070000Y1260492D01*
G01X-1138748Y1253563D02*
X-1138098Y1252553D01*
X-1137232Y1251975D01*
X-1136258Y1251831D01*
X-1135392Y1251975D01*
X-1134525Y1252697D01*
X-1133984Y1253563D01*
X-1133876Y1254429D01*
X-1134092Y1255440D01*
X-1134850Y1256161D01*
X-1135608Y1256450D01*
X-1136583D01*
G01X-1135608D02*
X-1134959Y1256883D01*
X-1134417Y1257605D01*
X-1134201Y1258471D01*
X-1134417Y1259337D01*
X-1134959Y1260059D01*
X-1135933Y1260492D01*
X-1136907Y1260348D01*
X-1137882Y1259770D01*
G01X-1127705Y1251542D02*
X-1127922Y1251687D01*
Y1251975D01*
X-1127705Y1252120D01*
X-1127488Y1251975D01*
Y1251687D01*
X-1127705Y1251542D01*
G01X-1121426Y1253130D02*
X-1120776Y1252408D01*
X-1120018Y1251975D01*
X-1119044Y1251831D01*
X-1118070Y1252120D01*
X-1117312Y1252697D01*
X-1116770Y1253707D01*
X-1116662Y1254862D01*
X-1116879Y1256017D01*
X-1117420Y1256739D01*
X-1118178Y1257316D01*
X-1118936Y1257461D01*
X-1119694Y1257316D01*
X-1120668Y1256739D01*
X-1120343Y1260492D01*
X-1117420D01*
G01X-1110383D02*
X-1111249Y1260203D01*
X-1111899Y1259482D01*
X-1112332Y1258616D01*
X-1112657Y1257461D01*
X-1112765Y1256161D01*
X-1112657Y1254862D01*
X-1112332Y1253707D01*
X-1111899Y1252841D01*
X-1111249Y1252120D01*
X-1110383Y1251831D01*
X-1109517Y1252120D01*
X-1108867Y1252841D01*
X-1108434Y1253707D01*
X-1108109Y1254862D01*
X-1108001Y1256161D01*
X-1108109Y1257461D01*
X-1108434Y1258616D01*
X-1108867Y1259482D01*
X-1109517Y1260203D01*
X-1110383Y1260492D01*
G01X-1149756Y1251831D02*
Y1257605D01*
G01Y1256161D02*
X-1149322Y1256883D01*
X-1148673Y1257461D01*
X-1147807Y1257605D01*
X-1147049Y1257461D01*
X-1146399Y1256883D01*
X-1146074Y1255873D01*
Y1251831D01*
G01X-1124295Y1350797D02*
X-1125378Y1352241D01*
X-1125919Y1353684D01*
Y1359458D01*
X-1125378Y1360902D01*
X-1124295Y1362345D01*
G01X-1117258Y1353684D02*
Y1362345D01*
X-1114660D01*
X-1113794Y1361912D01*
X-1113144Y1360902D01*
X-1112928Y1359747D01*
X-1113144Y1358592D01*
X-1113686Y1357726D01*
X-1114660Y1357293D01*
X-1117258D01*
G01X-1109139Y1353684D02*
X-1106432Y1362345D01*
X-1103725Y1353684D01*
G01X-1104700Y1356715D02*
X-1108164D01*
G01X-1100153Y1353684D02*
Y1362345D01*
X-1097988D01*
X-1097121Y1361912D01*
X-1096472Y1361335D01*
X-1095930Y1360469D01*
X-1095497Y1359458D01*
X-1095389Y1358014D01*
X-1095497Y1356571D01*
X-1095930Y1355560D01*
X-1096472Y1354694D01*
X-1097121Y1354117D01*
X-1097988Y1353684D01*
X-1100153D01*
G01X-1088569Y1350797D02*
X-1087486Y1352241D01*
X-1086945Y1353684D01*
Y1359458D01*
X-1087486Y1360902D01*
X-1088569Y1362345D01*
G01X-1080990Y1350797D02*
X-1082073Y1352241D01*
X-1082614Y1353684D01*
Y1359458D01*
X-1082073Y1360902D01*
X-1080990Y1362345D01*
G01X-1074278Y1353684D02*
Y1362345D01*
X-1069298Y1353684D01*
Y1362345D01*
G01X-1063127Y1353684D02*
X-1063993Y1353828D01*
X-1064751Y1354406D01*
X-1065401Y1355272D01*
X-1065834Y1356282D01*
X-1066050Y1357437D01*
Y1358592D01*
X-1065834Y1359747D01*
X-1065401Y1360757D01*
X-1064751Y1361623D01*
X-1063993Y1362201D01*
X-1063127Y1362345D01*
X-1062261Y1362201D01*
X-1061503Y1361623D01*
X-1060853Y1360757D01*
X-1060420Y1359747D01*
X-1060204Y1358592D01*
Y1357437D01*
X-1060420Y1356282D01*
X-1060853Y1355272D01*
X-1061503Y1354406D01*
X-1062261Y1353828D01*
X-1063127Y1353684D01*
G01X-1045805Y1362345D02*
Y1353684D01*
G01X-1048295Y1362345D02*
X-1043315D01*
G01X-1039309Y1353684D02*
Y1362345D01*
X-1036603D01*
X-1035737Y1361912D01*
X-1035195Y1361335D01*
X-1034979Y1360180D01*
X-1035195Y1359025D01*
X-1035845Y1358303D01*
X-1036603Y1357870D01*
X-1039309D01*
G01X-1036603D02*
X-1034979Y1353684D01*
G01X-1031190D02*
X-1028483Y1362345D01*
X-1025776Y1353684D01*
G01X-1026751Y1356715D02*
X-1030215D01*
G01X-1017440Y1361623D02*
X-1018090Y1362056D01*
X-1018848Y1362345D01*
X-1019714D01*
X-1020688Y1361912D01*
X-1021446Y1361190D01*
X-1021987Y1360324D01*
X-1022421Y1358881D01*
X-1022529Y1357581D01*
X-1022312Y1356282D01*
X-1021987Y1355416D01*
X-1021338Y1354550D01*
X-1020580Y1353973D01*
X-1019822Y1353684D01*
X-1019064D01*
X-1018306Y1353973D01*
X-1017657Y1354406D01*
X-1017115Y1354983D01*
G01X-1008996Y1353684D02*
X-1013326D01*
Y1362345D01*
X-1008996D01*
G01X-1010728Y1358159D02*
X-1013326D01*
G01X-996546Y1353684D02*
X-993839Y1362345D01*
X-991132Y1353684D01*
G01X-992107Y1356715D02*
X-995571D01*
G01X-985178Y1362345D02*
Y1353684D01*
G01X-987668Y1362345D02*
X-982688D01*
G01X-970563Y1353684D02*
X-967856Y1362345D01*
X-965149Y1353684D01*
G01X-966124Y1356715D02*
X-969588D01*
G01X-961360Y1362345D02*
Y1353684D01*
X-957030D01*
G01X-952699Y1362345D02*
Y1353684D01*
X-948369D01*
G01X-935377Y1362345D02*
Y1353684D01*
X-931047D01*
G01X-927258D02*
X-924551Y1362345D01*
X-921844Y1353684D01*
G01X-922819Y1356715D02*
X-926283D01*
G01X-915890Y1353684D02*
Y1357581D01*
X-918055Y1362345D01*
G01X-913725D02*
X-915890Y1357581D01*
G01X-905064Y1353684D02*
X-909394D01*
Y1362345D01*
X-905064D01*
G01X-906796Y1358159D02*
X-909394D01*
G01X-900733Y1353684D02*
Y1362345D01*
X-898027D01*
X-897161Y1361912D01*
X-896619Y1361335D01*
X-896403Y1360180D01*
X-896619Y1359025D01*
X-897269Y1358303D01*
X-898027Y1357870D01*
X-900733D01*
G01X-898027D02*
X-896403Y1353684D01*
G01X-892181Y1354839D02*
X-891314Y1354117D01*
X-890340Y1353684D01*
X-889474D01*
X-888608Y1354117D01*
X-887958Y1354839D01*
X-887633Y1355849D01*
X-887850Y1356860D01*
X-888391Y1357726D01*
X-889366Y1358303D01*
X-890665Y1358592D01*
X-891423Y1359169D01*
X-891748Y1360180D01*
X-891531Y1361190D01*
X-890990Y1361912D01*
X-890232Y1362345D01*
X-889474D01*
X-888716Y1362056D01*
X-888066Y1361335D01*
G01X-880705Y1350797D02*
X-879622Y1352241D01*
X-879081Y1353684D01*
Y1359458D01*
X-879622Y1360902D01*
X-880705Y1362345D01*
G01X-1126310Y1448141D02*
Y1459503D01*
X-1131565Y1451360D01*
X-1124463D01*
G01X-1029399Y-446283D02*
X-1028749Y-445418D01*
X-1027992Y-444984D01*
X-1027125Y-444840D01*
X-1026043Y-445129D01*
X-1025285Y-445850D01*
X-1025068Y-446716D01*
X-1025177Y-447583D01*
X-1025610Y-448304D01*
X-1027775Y-449748D01*
X-1028749Y-450758D01*
X-1029399Y-452202D01*
X-1029616Y-453501D01*
X-1025068D01*
G01X-1018681Y-453790D02*
X-1018898Y-453645D01*
Y-453357D01*
X-1018681Y-453212D01*
X-1018464Y-453357D01*
Y-453645D01*
X-1018681Y-453790D01*
G01X-1012402Y-452202D02*
X-1011752Y-452924D01*
X-1010994Y-453357D01*
X-1010020Y-453501D01*
X-1009046Y-453212D01*
X-1008288Y-452635D01*
X-1007746Y-451625D01*
X-1007638Y-450470D01*
X-1007855Y-449315D01*
X-1008396Y-448593D01*
X-1009154Y-448016D01*
X-1009912Y-447871D01*
X-1010670Y-448016D01*
X-1011644Y-448593D01*
X-1011319Y-444840D01*
X-1008396D01*
G01X-1003741Y-452202D02*
X-1003091Y-452924D01*
X-1002333Y-453357D01*
X-1001359Y-453501D01*
X-1000385Y-453212D01*
X-999627Y-452635D01*
X-999085Y-451625D01*
X-998977Y-450470D01*
X-999194Y-449315D01*
X-999735Y-448593D01*
X-1000493Y-448016D01*
X-1001251Y-447871D01*
X-1002009Y-448016D01*
X-1002983Y-448593D01*
X-1002658Y-444840D01*
X-999735D01*
G01X-1040731Y-453501D02*
Y-447727D01*
G01Y-449171D02*
X-1040297Y-448449D01*
X-1039648Y-447871D01*
X-1038782Y-447727D01*
X-1038024Y-447871D01*
X-1037374Y-448449D01*
X-1037049Y-449459D01*
Y-453501D01*
G01X-1008581Y-378980D02*
X-1009664Y-377536D01*
X-1010205Y-376093D01*
Y-370319D01*
X-1009664Y-368875D01*
X-1008581Y-367432D01*
G01X-1001869Y-376093D02*
Y-367432D01*
X-996889Y-376093D01*
Y-367432D01*
G01X-992883Y-376093D02*
Y-367432D01*
X-990285D01*
X-989419Y-367865D01*
X-988769Y-368875D01*
X-988553Y-370030D01*
X-988769Y-371185D01*
X-989311Y-372051D01*
X-990285Y-372484D01*
X-992883D01*
G01X-982057Y-367432D02*
Y-376093D01*
G01X-984547Y-367432D02*
X-979567D01*
G01X-975670Y-376093D02*
Y-367432D01*
G01X-971122D02*
Y-376093D01*
G01Y-371763D02*
X-975670D01*
G01X-964194Y-378980D02*
X-963111Y-377536D01*
X-962570Y-376093D01*
Y-370319D01*
X-963111Y-368875D01*
X-964194Y-367432D01*
G01X-1041279Y-368875D02*
X-1040629Y-368010D01*
X-1039872Y-367576D01*
X-1039005Y-367432D01*
X-1037923Y-367721D01*
X-1037165Y-368442D01*
X-1036948Y-369308D01*
X-1037057Y-370175D01*
X-1037490Y-370896D01*
X-1039655Y-372340D01*
X-1040629Y-373350D01*
X-1041279Y-374794D01*
X-1041496Y-376093D01*
X-1036948D01*
G01X-1030561Y-376382D02*
X-1030778Y-376237D01*
Y-375949D01*
X-1030561Y-375804D01*
X-1030344Y-375949D01*
Y-376237D01*
X-1030561Y-376382D01*
G01X-1020601Y-376093D02*
Y-367432D01*
X-1024607Y-373639D01*
X-1019193D01*
G01X-1013239Y-376093D02*
Y-367432D01*
X-1014538Y-369164D01*
G01Y-376093D02*
X-1011940D01*
G01X-1052611D02*
Y-370319D01*
G01Y-371763D02*
X-1052177Y-371041D01*
X-1051528Y-370463D01*
X-1050662Y-370319D01*
X-1049904Y-370463D01*
X-1049254Y-371041D01*
X-1048929Y-372051D01*
Y-376093D01*
G01X-1049452Y514905D02*
Y523566D01*
X-1050751Y521834D01*
G01Y514905D02*
X-1048153D01*
G01X-1040791Y523566D02*
X-1041657Y523277D01*
X-1042307Y522556D01*
X-1042740Y521690D01*
X-1043065Y520535D01*
X-1043173Y519235D01*
X-1043065Y517936D01*
X-1042740Y516781D01*
X-1042307Y515915D01*
X-1041657Y515194D01*
X-1040791Y514905D01*
X-1039925Y515194D01*
X-1039275Y515915D01*
X-1038842Y516781D01*
X-1038517Y517936D01*
X-1038409Y519235D01*
X-1038517Y520535D01*
X-1038842Y521690D01*
X-1039275Y522556D01*
X-1039925Y523277D01*
X-1040791Y523566D01*
G01X-1032130Y514616D02*
X-1032347Y514761D01*
Y515049D01*
X-1032130Y515194D01*
X-1031913Y515049D01*
Y514761D01*
X-1032130Y514616D01*
G01X-1023469Y523566D02*
X-1024335Y523277D01*
X-1024985Y522556D01*
X-1025418Y521690D01*
X-1025743Y520535D01*
X-1025851Y519235D01*
X-1025743Y517936D01*
X-1025418Y516781D01*
X-1024985Y515915D01*
X-1024335Y515194D01*
X-1023469Y514905D01*
X-1022603Y515194D01*
X-1021953Y515915D01*
X-1021520Y516781D01*
X-1021195Y517936D01*
X-1021087Y519235D01*
X-1021195Y520535D01*
X-1021520Y521690D01*
X-1021953Y522556D01*
X-1022603Y523277D01*
X-1023469Y523566D01*
G01X-1014808D02*
X-1015674Y523277D01*
X-1016324Y522556D01*
X-1016757Y521690D01*
X-1017082Y520535D01*
X-1017190Y519235D01*
X-1017082Y517936D01*
X-1016757Y516781D01*
X-1016324Y515915D01*
X-1015674Y515194D01*
X-1014808Y514905D01*
X-1013942Y515194D01*
X-1013292Y515915D01*
X-1012859Y516781D01*
X-1012534Y517936D01*
X-1012426Y519235D01*
X-1012534Y520535D01*
X-1012859Y521690D01*
X-1013292Y522556D01*
X-1013942Y523277D01*
X-1014808Y523566D01*
G01X-1031424Y723090D02*
X-1030557Y722368D01*
X-1029583Y721935D01*
X-1028717D01*
X-1027851Y722368D01*
X-1027201Y723090D01*
X-1026876Y724100D01*
X-1027093Y725111D01*
X-1027634Y725977D01*
X-1028609Y726554D01*
X-1029908Y726843D01*
X-1030666Y727420D01*
X-1030991Y728431D01*
X-1030774Y729441D01*
X-1030233Y730163D01*
X-1029475Y730596D01*
X-1028717D01*
X-1027959Y730307D01*
X-1027309Y729586D01*
G01X-1018324Y721935D02*
X-1022654D01*
Y730596D01*
X-1018324D01*
G01X-1020056Y726410D02*
X-1022654D01*
G01X-1009663Y721935D02*
X-1013993D01*
Y730596D01*
X-1009663D01*
G01X-1011395Y726410D02*
X-1013993D01*
G01X-996888Y721935D02*
Y730596D01*
X-994723D01*
X-993856Y730163D01*
X-993207Y729586D01*
X-992665Y728720D01*
X-992232Y727709D01*
X-992124Y726265D01*
X-992232Y724822D01*
X-992665Y723811D01*
X-993207Y722945D01*
X-993856Y722368D01*
X-994723Y721935D01*
X-996888D01*
G01X-983680D02*
X-988010D01*
Y730596D01*
X-983680D01*
G01X-985412Y726410D02*
X-988010D01*
G01X-977184Y730596D02*
Y721935D01*
G01X-979674Y730596D02*
X-974694D01*
G01X-971230Y721935D02*
X-968523Y730596D01*
X-965816Y721935D01*
G01X-966791Y724966D02*
X-970255D01*
G01X-961161Y730596D02*
X-958563D01*
G01X-959862D02*
Y721935D01*
G01X-961161D02*
X-958563D01*
G01X-953366Y730596D02*
Y721935D01*
X-949036D01*
G01X-1012523Y815062D02*
X-1021184D01*
X-1019452Y813763D01*
G01X-1012523D02*
Y816361D01*
G01Y825022D02*
X-1021184D01*
X-1014977Y821016D01*
Y826430D01*
G01X-1013533Y830543D02*
X-1012812Y831301D01*
X-1012523Y832167D01*
X-1012812Y833034D01*
X-1013678Y833791D01*
X-1014977Y834333D01*
X-1016276Y834549D01*
X-1017864D01*
X-1019163Y834333D01*
X-1020318Y833791D01*
X-1020895Y833142D01*
X-1021184Y832384D01*
X-1020895Y831518D01*
X-1020318Y830868D01*
X-1019452Y830435D01*
X-1018297Y830219D01*
X-1017287Y830435D01*
X-1016276Y830977D01*
X-1015699Y831626D01*
X-1015554Y832384D01*
X-1015843Y833250D01*
X-1016565Y833900D01*
X-1017864Y834549D01*
G01X-1012234Y841045D02*
X-1012379Y840828D01*
X-1012667D01*
X-1012812Y841045D01*
X-1012667Y841262D01*
X-1012379D01*
X-1012234Y841045D01*
G01X-1014255Y847324D02*
X-1013245Y847974D01*
X-1012667Y848840D01*
X-1012523Y849814D01*
X-1012667Y850680D01*
X-1013389Y851547D01*
X-1014255Y852088D01*
X-1015121Y852196D01*
X-1016132Y851980D01*
X-1016853Y851222D01*
X-1017142Y850464D01*
Y849489D01*
G01Y850464D02*
X-1017575Y851113D01*
X-1018297Y851655D01*
X-1019163Y851871D01*
X-1020029Y851655D01*
X-1020751Y851113D01*
X-1021184Y850139D01*
X-1021040Y849165D01*
X-1020462Y848190D01*
G01X-1021184Y858367D02*
X-1020895Y857501D01*
X-1020174Y856851D01*
X-1019308Y856418D01*
X-1018153Y856093D01*
X-1016853Y855985D01*
X-1015554Y856093D01*
X-1014399Y856418D01*
X-1013533Y856851D01*
X-1012812Y857501D01*
X-1012523Y858367D01*
X-1012812Y859233D01*
X-1013533Y859883D01*
X-1014399Y860316D01*
X-1015554Y860641D01*
X-1016853Y860749D01*
X-1018153Y860641D01*
X-1019308Y860316D01*
X-1020174Y859883D01*
X-1020895Y859233D01*
X-1021184Y858367D01*
G01X-1009767Y864761D02*
X-1018428D01*
X-1016696Y863462D01*
G01X-1009767D02*
Y866060D01*
G01X-1011066Y871040D02*
X-1010344Y871690D01*
X-1009911Y872448D01*
X-1009767Y873422D01*
X-1010056Y874396D01*
X-1010633Y875154D01*
X-1011643Y875696D01*
X-1012798Y875804D01*
X-1013953Y875587D01*
X-1014675Y875046D01*
X-1015252Y874288D01*
X-1015397Y873530D01*
X-1015252Y872772D01*
X-1014675Y871798D01*
X-1018428Y872123D01*
Y875046D01*
G01Y882083D02*
X-1018139Y881217D01*
X-1017418Y880567D01*
X-1016552Y880134D01*
X-1015397Y879809D01*
X-1014097Y879701D01*
X-1012798Y879809D01*
X-1011643Y880134D01*
X-1010777Y880567D01*
X-1010056Y881217D01*
X-1009767Y882083D01*
X-1010056Y882949D01*
X-1010777Y883599D01*
X-1011643Y884032D01*
X-1012798Y884357D01*
X-1014097Y884465D01*
X-1015397Y884357D01*
X-1016552Y884032D01*
X-1017418Y883599D01*
X-1018139Y882949D01*
X-1018428Y882083D01*
G01X-1009478Y890744D02*
X-1009623Y890527D01*
X-1009911D01*
X-1010056Y890744D01*
X-1009911Y890961D01*
X-1009623D01*
X-1009478Y890744D01*
G01X-1018428Y899405D02*
X-1018139Y898539D01*
X-1017418Y897889D01*
X-1016552Y897456D01*
X-1015397Y897131D01*
X-1014097Y897023D01*
X-1012798Y897131D01*
X-1011643Y897456D01*
X-1010777Y897889D01*
X-1010056Y898539D01*
X-1009767Y899405D01*
X-1010056Y900271D01*
X-1010777Y900921D01*
X-1011643Y901354D01*
X-1012798Y901679D01*
X-1014097Y901787D01*
X-1015397Y901679D01*
X-1016552Y901354D01*
X-1017418Y900921D01*
X-1018139Y900271D01*
X-1018428Y899405D01*
G01Y908066D02*
X-1018139Y907200D01*
X-1017418Y906550D01*
X-1016552Y906117D01*
X-1015397Y905792D01*
X-1014097Y905684D01*
X-1012798Y905792D01*
X-1011643Y906117D01*
X-1010777Y906550D01*
X-1010056Y907200D01*
X-1009767Y908066D01*
X-1010056Y908932D01*
X-1010777Y909582D01*
X-1011643Y910015D01*
X-1012798Y910340D01*
X-1014097Y910448D01*
X-1015397Y910340D01*
X-1016552Y910015D01*
X-1017418Y909582D01*
X-1018139Y908932D01*
X-1018428Y908066D01*
G01X-1032208Y1279767D02*
X-1040869D01*
X-1039137Y1278468D01*
G01X-1032208D02*
Y1281066D01*
G01Y1289727D02*
X-1040869D01*
X-1034662Y1285721D01*
Y1291135D01*
G01X-1032208Y1298388D02*
X-1040869D01*
X-1034662Y1294382D01*
Y1299796D01*
G01X-1031919Y1305750D02*
X-1032064Y1305533D01*
X-1032352D01*
X-1032497Y1305750D01*
X-1032352Y1305967D01*
X-1032064D01*
X-1031919Y1305750D01*
G01X-1033940Y1312029D02*
X-1032930Y1312679D01*
X-1032352Y1313545D01*
X-1032208Y1314519D01*
X-1032352Y1315385D01*
X-1033074Y1316252D01*
X-1033940Y1316793D01*
X-1034806Y1316901D01*
X-1035817Y1316685D01*
X-1036538Y1315927D01*
X-1036827Y1315169D01*
Y1314194D01*
G01Y1315169D02*
X-1037260Y1315818D01*
X-1037982Y1316360D01*
X-1038848Y1316576D01*
X-1039714Y1316360D01*
X-1040436Y1315818D01*
X-1040869Y1314844D01*
X-1040725Y1313870D01*
X-1040147Y1312895D01*
G01X-1040869Y1323072D02*
X-1040580Y1322206D01*
X-1039859Y1321556D01*
X-1038993Y1321123D01*
X-1037838Y1320798D01*
X-1036538Y1320690D01*
X-1035239Y1320798D01*
X-1034084Y1321123D01*
X-1033218Y1321556D01*
X-1032497Y1322206D01*
X-1032208Y1323072D01*
X-1032497Y1323938D01*
X-1033218Y1324588D01*
X-1034084Y1325021D01*
X-1035239Y1325346D01*
X-1036538Y1325454D01*
X-1037838Y1325346D01*
X-1038993Y1325021D01*
X-1039859Y1324588D01*
X-1040580Y1323938D01*
X-1040869Y1323072D01*
G01X-941163Y-644427D02*
X-942246Y-642983D01*
X-942787Y-641540D01*
Y-635766D01*
X-942246Y-634322D01*
X-941163Y-632879D01*
G01X-934451Y-641540D02*
Y-632879D01*
X-929471Y-641540D01*
Y-632879D01*
G01X-923300Y-641540D02*
X-924166Y-641396D01*
X-924924Y-640818D01*
X-925574Y-639952D01*
X-926007Y-638942D01*
X-926223Y-637787D01*
Y-636632D01*
X-926007Y-635477D01*
X-925574Y-634467D01*
X-924924Y-633601D01*
X-924166Y-633023D01*
X-923300Y-632879D01*
X-922434Y-633023D01*
X-921676Y-633601D01*
X-921026Y-634467D01*
X-920593Y-635477D01*
X-920377Y-636632D01*
Y-637787D01*
X-920593Y-638942D01*
X-921026Y-639952D01*
X-921676Y-640818D01*
X-922434Y-641396D01*
X-923300Y-641540D01*
G01X-905978Y-632879D02*
Y-641540D01*
G01X-908468Y-632879D02*
X-903488D01*
G01X-899482Y-641540D02*
Y-632879D01*
X-896776D01*
X-895910Y-633312D01*
X-895368Y-633889D01*
X-895152Y-635044D01*
X-895368Y-636199D01*
X-896018Y-636921D01*
X-896776Y-637354D01*
X-899482D01*
G01X-896776D02*
X-895152Y-641540D01*
G01X-891363D02*
X-888656Y-632879D01*
X-885949Y-641540D01*
G01X-886924Y-638509D02*
X-890388D01*
G01X-877613Y-633601D02*
X-878263Y-633168D01*
X-879021Y-632879D01*
X-879887D01*
X-880861Y-633312D01*
X-881619Y-634034D01*
X-882160Y-634900D01*
X-882594Y-636343D01*
X-882702Y-637643D01*
X-882485Y-638942D01*
X-882160Y-639808D01*
X-881511Y-640674D01*
X-880753Y-641251D01*
X-879995Y-641540D01*
X-879237D01*
X-878479Y-641251D01*
X-877830Y-640818D01*
X-877288Y-640241D01*
G01X-869169Y-641540D02*
X-873499D01*
Y-632879D01*
X-869169D01*
G01X-870901Y-637065D02*
X-873499D01*
G01X-856719Y-641540D02*
X-854012Y-632879D01*
X-851305Y-641540D01*
G01X-852280Y-638509D02*
X-855744D01*
G01X-845351Y-632879D02*
Y-641540D01*
G01X-847841Y-632879D02*
X-842861D01*
G01X-830736Y-641540D02*
X-828029Y-632879D01*
X-825322Y-641540D01*
G01X-826297Y-638509D02*
X-829761D01*
G01X-821533Y-632879D02*
Y-641540D01*
X-817203D01*
G01X-812872Y-632879D02*
Y-641540D01*
X-808542D01*
G01X-795550Y-632879D02*
Y-641540D01*
X-791220D01*
G01X-787431D02*
X-784724Y-632879D01*
X-782017Y-641540D01*
G01X-782992Y-638509D02*
X-786456D01*
G01X-776063Y-641540D02*
Y-637643D01*
X-778228Y-632879D01*
G01X-773898D02*
X-776063Y-637643D01*
G01X-765237Y-641540D02*
X-769567D01*
Y-632879D01*
X-765237D01*
G01X-766969Y-637065D02*
X-769567D01*
G01X-760906Y-641540D02*
Y-632879D01*
X-758200D01*
X-757334Y-633312D01*
X-756792Y-633889D01*
X-756576Y-635044D01*
X-756792Y-636199D01*
X-757442Y-636921D01*
X-758200Y-637354D01*
X-760906D01*
G01X-758200D02*
X-756576Y-641540D01*
G01X-752354Y-640385D02*
X-751487Y-641107D01*
X-750513Y-641540D01*
X-749647D01*
X-748781Y-641107D01*
X-748131Y-640385D01*
X-747806Y-639375D01*
X-748023Y-638364D01*
X-748564Y-637498D01*
X-749539Y-636921D01*
X-750838Y-636632D01*
X-751596Y-636055D01*
X-751921Y-635044D01*
X-751704Y-634034D01*
X-751163Y-633312D01*
X-750405Y-632879D01*
X-749647D01*
X-748889Y-633168D01*
X-748239Y-633889D01*
G01X-730593Y-641540D02*
X-734923D01*
Y-632879D01*
X-730593D01*
G01X-732325Y-637065D02*
X-734923D01*
G01X-726371Y-641540D02*
X-721823Y-632879D01*
G01X-726371D02*
X-721823Y-641540D01*
G01X-713054Y-633601D02*
X-713704Y-633168D01*
X-714462Y-632879D01*
X-715328D01*
X-716302Y-633312D01*
X-717060Y-634034D01*
X-717601Y-634900D01*
X-718035Y-636343D01*
X-718143Y-637643D01*
X-717926Y-638942D01*
X-717601Y-639808D01*
X-716952Y-640674D01*
X-716194Y-641251D01*
X-715436Y-641540D01*
X-714678D01*
X-713920Y-641251D01*
X-713271Y-640818D01*
X-712729Y-640241D01*
G01X-704610Y-641540D02*
X-708940D01*
Y-632879D01*
X-704610D01*
G01X-706342Y-637065D02*
X-708940D01*
G01X-700279Y-641540D02*
Y-632879D01*
X-697681D01*
X-696815Y-633312D01*
X-696165Y-634322D01*
X-695949Y-635477D01*
X-696165Y-636632D01*
X-696707Y-637498D01*
X-697681Y-637931D01*
X-700279D01*
G01X-689453Y-632879D02*
Y-641540D01*
G01X-691943Y-632879D02*
X-686963D01*
G01X-671481Y-637210D02*
X-669316D01*
Y-639808D01*
X-669966Y-640674D01*
X-670724Y-641251D01*
X-671806Y-641540D01*
X-672889Y-641251D01*
X-673647Y-640674D01*
X-674296Y-639808D01*
X-674730Y-638797D01*
X-674946Y-637643D01*
Y-636632D01*
X-674730Y-635766D01*
X-674296Y-634755D01*
X-673647Y-633889D01*
X-672997Y-633312D01*
X-672131Y-632879D01*
X-671373D01*
X-670507Y-633168D01*
X-669857Y-633745D01*
G01X-665960Y-641540D02*
Y-632879D01*
X-660980Y-641540D01*
Y-632879D01*
G01X-657191Y-641540D02*
Y-632879D01*
X-655026D01*
X-654159Y-633312D01*
X-653510Y-633889D01*
X-652968Y-634755D01*
X-652535Y-635766D01*
X-652427Y-637210D01*
X-652535Y-638653D01*
X-652968Y-639664D01*
X-653510Y-640530D01*
X-654159Y-641107D01*
X-655026Y-641540D01*
X-657191D01*
G01X-645607Y-644427D02*
X-644524Y-642983D01*
X-643983Y-641540D01*
Y-635766D01*
X-644524Y-634322D01*
X-645607Y-632879D01*
G01X-973860Y-637931D02*
X-973102Y-636921D01*
X-972453Y-636343D01*
X-971586Y-636055D01*
X-970829Y-636343D01*
X-970287Y-636921D01*
X-969854Y-637787D01*
X-969746Y-638797D01*
X-969854Y-639664D01*
X-970287Y-640530D01*
X-970937Y-641251D01*
X-971695Y-641540D01*
X-972561Y-641251D01*
X-973319Y-640385D01*
X-973752Y-639086D01*
X-973860Y-637643D01*
X-973644Y-635766D01*
X-973319Y-634755D01*
X-972777Y-633745D01*
X-972020Y-633023D01*
X-971262Y-632879D01*
X-970504Y-633168D01*
X-969962Y-633889D01*
G01X-963142Y-641829D02*
X-963359Y-641684D01*
Y-641396D01*
X-963142Y-641251D01*
X-962925Y-641396D01*
Y-641684D01*
X-963142Y-641829D01*
G01X-954481Y-632879D02*
X-955347Y-633168D01*
X-955997Y-633889D01*
X-956430Y-634755D01*
X-956755Y-635910D01*
X-956863Y-637210D01*
X-956755Y-638509D01*
X-956430Y-639664D01*
X-955997Y-640530D01*
X-955347Y-641251D01*
X-954481Y-641540D01*
X-953615Y-641251D01*
X-952965Y-640530D01*
X-952532Y-639664D01*
X-952207Y-638509D01*
X-952099Y-637210D01*
X-952207Y-635910D01*
X-952532Y-634755D01*
X-952965Y-633889D01*
X-953615Y-633168D01*
X-954481Y-632879D01*
G01X-945820D02*
X-946686Y-633168D01*
X-947336Y-633889D01*
X-947769Y-634755D01*
X-948094Y-635910D01*
X-948202Y-637210D01*
X-948094Y-638509D01*
X-947769Y-639664D01*
X-947336Y-640530D01*
X-946686Y-641251D01*
X-945820Y-641540D01*
X-944954Y-641251D01*
X-944304Y-640530D01*
X-943871Y-639664D01*
X-943546Y-638509D01*
X-943438Y-637210D01*
X-943546Y-635910D01*
X-943871Y-634755D01*
X-944304Y-633889D01*
X-944954Y-633168D01*
X-945820Y-632879D01*
G01X-985192Y-641540D02*
Y-635766D01*
G01Y-637210D02*
X-984758Y-636488D01*
X-984109Y-635910D01*
X-983243Y-635766D01*
X-982485Y-635910D01*
X-981835Y-636488D01*
X-981510Y-637498D01*
Y-641540D01*
G01X-996702Y-456388D02*
X-997785Y-454944D01*
X-998326Y-453501D01*
Y-447727D01*
X-997785Y-446283D01*
X-996702Y-444840D01*
G01X-989990Y-453501D02*
Y-444840D01*
X-985010Y-453501D01*
Y-444840D01*
G01X-981004Y-453501D02*
Y-444840D01*
X-978406D01*
X-977540Y-445273D01*
X-976890Y-446283D01*
X-976674Y-447438D01*
X-976890Y-448593D01*
X-977432Y-449459D01*
X-978406Y-449892D01*
X-981004D01*
G01X-970178Y-444840D02*
Y-453501D01*
G01X-972668Y-444840D02*
X-967688D01*
G01X-963791Y-453501D02*
Y-444840D01*
G01X-959243D02*
Y-453501D01*
G01Y-449171D02*
X-963791D01*
G01X-952315Y-456388D02*
X-951232Y-454944D01*
X-950691Y-453501D01*
Y-447727D01*
X-951232Y-446283D01*
X-952315Y-444840D01*
G01X-979571Y782621D02*
X-979354Y784497D01*
X-979029Y786085D01*
X-978596Y787529D01*
X-978055Y789117D01*
X-977189Y791282D01*
X-981519D01*
G01X-970693Y782621D02*
X-969935Y782765D01*
X-969069Y783198D01*
X-968528Y783920D01*
X-968311Y784931D01*
X-968528Y785941D01*
X-969177Y786807D01*
X-970152Y787240D01*
X-971234D01*
X-971884Y787529D01*
X-972425Y788251D01*
X-972642Y789261D01*
X-972317Y790272D01*
X-971559Y790993D01*
X-970693Y791282D01*
X-969827Y790993D01*
X-969069Y790272D01*
X-968744Y789261D01*
X-968961Y788251D01*
X-969502Y787529D01*
X-970152Y787240D01*
X-971234D01*
X-972209Y786807D01*
X-972858Y785941D01*
X-973075Y784931D01*
X-972858Y783920D01*
X-972317Y783198D01*
X-971451Y782765D01*
X-970693Y782621D01*
G01X-962032Y782332D02*
X-962249Y782477D01*
Y782765D01*
X-962032Y782910D01*
X-961815Y782765D01*
Y782477D01*
X-962032Y782332D01*
G01X-953371Y791282D02*
X-954237Y790993D01*
X-954887Y790272D01*
X-955320Y789406D01*
X-955645Y788251D01*
X-955753Y786951D01*
X-955645Y785652D01*
X-955320Y784497D01*
X-954887Y783631D01*
X-954237Y782910D01*
X-953371Y782621D01*
X-952505Y782910D01*
X-951855Y783631D01*
X-951422Y784497D01*
X-951097Y785652D01*
X-950989Y786951D01*
X-951097Y788251D01*
X-951422Y789406D01*
X-951855Y790272D01*
X-952505Y790993D01*
X-953371Y791282D01*
G01X-944710D02*
X-945576Y790993D01*
X-946226Y790272D01*
X-946659Y789406D01*
X-946984Y788251D01*
X-947092Y786951D01*
X-946984Y785652D01*
X-946659Y784497D01*
X-946226Y783631D01*
X-945576Y782910D01*
X-944710Y782621D01*
X-943844Y782910D01*
X-943194Y783631D01*
X-942761Y784497D01*
X-942436Y785652D01*
X-942328Y786951D01*
X-942436Y788251D01*
X-942761Y789406D01*
X-943194Y790272D01*
X-943844Y790993D01*
X-944710Y791282D01*
G01X-942540Y726554D02*
X-942107Y726987D01*
X-941782Y727709D01*
X-941565Y728720D01*
X-941782Y729586D01*
X-942215Y730163D01*
X-942973Y730596D01*
X-945896D01*
Y721935D01*
X-942323D01*
X-941565Y722512D01*
X-941132Y723378D01*
X-940916Y724389D01*
X-941132Y725399D01*
X-941782Y726265D01*
X-942540Y726554D01*
X-945896D01*
G01X-988113Y1279767D02*
X-996774D01*
X-995042Y1278468D01*
G01X-988113D02*
Y1281066D01*
G01X-989412Y1286046D02*
X-988690Y1286696D01*
X-988257Y1287454D01*
X-988113Y1288428D01*
X-988402Y1289402D01*
X-988979Y1290160D01*
X-989989Y1290702D01*
X-991144Y1290810D01*
X-992299Y1290593D01*
X-993021Y1290052D01*
X-993598Y1289294D01*
X-993743Y1288536D01*
X-993598Y1287778D01*
X-993021Y1286804D01*
X-996774Y1287129D01*
Y1290052D01*
G01X-989412Y1294707D02*
X-988690Y1295357D01*
X-988257Y1296115D01*
X-988113Y1297089D01*
X-988402Y1298063D01*
X-988979Y1298821D01*
X-989989Y1299363D01*
X-991144Y1299471D01*
X-992299Y1299254D01*
X-993021Y1298713D01*
X-993598Y1297955D01*
X-993743Y1297197D01*
X-993598Y1296439D01*
X-993021Y1295465D01*
X-996774Y1295790D01*
Y1298713D01*
G01X-987824Y1305750D02*
X-987969Y1305533D01*
X-988257D01*
X-988402Y1305750D01*
X-988257Y1305967D01*
X-987969D01*
X-987824Y1305750D01*
G01X-989412Y1312029D02*
X-988690Y1312679D01*
X-988257Y1313437D01*
X-988113Y1314411D01*
X-988402Y1315385D01*
X-988979Y1316143D01*
X-989989Y1316685D01*
X-991144Y1316793D01*
X-992299Y1316576D01*
X-993021Y1316035D01*
X-993598Y1315277D01*
X-993743Y1314519D01*
X-993598Y1313761D01*
X-993021Y1312787D01*
X-996774Y1313112D01*
Y1316035D01*
G01Y1323072D02*
X-996485Y1322206D01*
X-995764Y1321556D01*
X-994898Y1321123D01*
X-993743Y1320798D01*
X-992443Y1320690D01*
X-991144Y1320798D01*
X-989989Y1321123D01*
X-989123Y1321556D01*
X-988402Y1322206D01*
X-988113Y1323072D01*
X-988402Y1323938D01*
X-989123Y1324588D01*
X-989989Y1325021D01*
X-991144Y1325346D01*
X-992443Y1325454D01*
X-993743Y1325346D01*
X-994898Y1325021D01*
X-995764Y1324588D01*
X-996485Y1323938D01*
X-996774Y1323072D01*
G01X-911469Y-727911D02*
X-910617Y-728858D01*
X-909622Y-729426D01*
X-908344Y-729615D01*
X-907066Y-729236D01*
X-906072Y-728479D01*
X-905361Y-727153D01*
X-905219Y-725638D01*
X-905503Y-724123D01*
X-906214Y-723177D01*
X-907208Y-722419D01*
X-908202Y-722230D01*
X-909196Y-722419D01*
X-910474Y-723177D01*
X-910048Y-718253D01*
X-906214D01*
G01X-863027Y575060D02*
X-872698Y571172D01*
X-862274Y571196D01*
X-863027Y575060D01*
G01X-922980Y713439D02*
X-916042Y705660D01*
X-919600Y715458D01*
X-922980Y713439D01*
G01X-894019Y818088D02*
X-902680D01*
X-900948Y816789D01*
G01X-894019D02*
Y819387D01*
G01Y826532D02*
X-895895Y826749D01*
X-897483Y827074D01*
X-898927Y827507D01*
X-900515Y828048D01*
X-902680Y828914D01*
Y824584D01*
G01X-895029Y833569D02*
X-894308Y834327D01*
X-894019Y835193D01*
X-894308Y836060D01*
X-895174Y836817D01*
X-896473Y837359D01*
X-897772Y837575D01*
X-899360D01*
X-900659Y837359D01*
X-901814Y836817D01*
X-902391Y836168D01*
X-902680Y835410D01*
X-902391Y834544D01*
X-901814Y833894D01*
X-900948Y833461D01*
X-899793Y833245D01*
X-898783Y833461D01*
X-897772Y834003D01*
X-897195Y834652D01*
X-897050Y835410D01*
X-897339Y836276D01*
X-898061Y836926D01*
X-899360Y837575D01*
G01X-893730Y844071D02*
X-893875Y843854D01*
X-894163D01*
X-894308Y844071D01*
X-894163Y844288D01*
X-893875D01*
X-893730Y844071D01*
G01X-894019Y854031D02*
X-902680D01*
X-896473Y850025D01*
Y855439D01*
G01X-902680Y861393D02*
X-902391Y860527D01*
X-901670Y859877D01*
X-900804Y859444D01*
X-899649Y859119D01*
X-898349Y859011D01*
X-897050Y859119D01*
X-895895Y859444D01*
X-895029Y859877D01*
X-894308Y860527D01*
X-894019Y861393D01*
X-894308Y862259D01*
X-895029Y862909D01*
X-895895Y863342D01*
X-897050Y863667D01*
X-898349Y863775D01*
X-899649Y863667D01*
X-900804Y863342D01*
X-901670Y862909D01*
X-902391Y862259D01*
X-902680Y861393D01*
G01X-901237Y800441D02*
X-902102Y801091D01*
X-902536Y801848D01*
X-902680Y802715D01*
X-902391Y803797D01*
X-901670Y804555D01*
X-900804Y804772D01*
X-899937Y804663D01*
X-899216Y804230D01*
X-897772Y802065D01*
X-896762Y801091D01*
X-895318Y800441D01*
X-894019Y800224D01*
Y804772D01*
G01X-896906Y809752D02*
Y812566D01*
G01X-911469Y1449845D02*
X-910617Y1448898D01*
X-909622Y1448330D01*
X-908344Y1448141D01*
X-907066Y1448520D01*
X-906072Y1449277D01*
X-905361Y1450603D01*
X-905219Y1452118D01*
X-905503Y1453633D01*
X-906214Y1454579D01*
X-907208Y1455337D01*
X-908202Y1455526D01*
X-909196Y1455337D01*
X-910474Y1454579D01*
X-910048Y1459503D01*
X-906214D01*
G01X-802812Y814545D02*
X-803677Y815195D01*
X-804111Y815952D01*
X-804255Y816819D01*
X-803966Y817901D01*
X-803245Y818659D01*
X-802379Y818876D01*
X-801512Y818767D01*
X-800791Y818334D01*
X-799347Y816169D01*
X-798337Y815195D01*
X-796893Y814545D01*
X-795594Y814328D01*
Y818876D01*
G01X-804255Y825263D02*
X-803966Y824397D01*
X-803245Y823747D01*
X-802379Y823314D01*
X-801224Y822989D01*
X-799924Y822881D01*
X-798625Y822989D01*
X-797470Y823314D01*
X-796604Y823747D01*
X-795883Y824397D01*
X-795594Y825263D01*
X-795883Y826129D01*
X-796604Y826779D01*
X-797470Y827212D01*
X-798625Y827537D01*
X-799924Y827645D01*
X-801224Y827537D01*
X-802379Y827212D01*
X-803245Y826779D01*
X-803966Y826129D01*
X-804255Y825263D01*
G01X-795594Y835223D02*
X-804255D01*
X-798048Y831217D01*
Y836631D01*
G01X-795305Y842585D02*
X-795450Y842368D01*
X-795738D01*
X-795883Y842585D01*
X-795738Y842802D01*
X-795450D01*
X-795305Y842585D01*
G01X-795594Y852545D02*
X-804255D01*
X-798048Y848539D01*
Y853953D01*
G01X-804255Y859907D02*
X-803966Y859041D01*
X-803245Y858391D01*
X-802379Y857958D01*
X-801224Y857633D01*
X-799924Y857525D01*
X-798625Y857633D01*
X-797470Y857958D01*
X-796604Y858391D01*
X-795883Y859041D01*
X-795594Y859907D01*
X-795883Y860773D01*
X-796604Y861423D01*
X-797470Y861856D01*
X-798625Y862181D01*
X-799924Y862289D01*
X-801224Y862181D01*
X-802379Y861856D01*
X-803245Y861423D01*
X-803966Y860773D01*
X-804255Y859907D01*
G01X-802812Y798954D02*
X-803677Y799604D01*
X-804111Y800361D01*
X-804255Y801228D01*
X-803966Y802310D01*
X-803245Y803068D01*
X-802379Y803285D01*
X-801512Y803176D01*
X-800791Y802743D01*
X-799347Y800578D01*
X-798337Y799604D01*
X-796893Y798954D01*
X-795594Y798737D01*
Y803285D01*
G01X-798481Y808265D02*
Y811079D01*
G01X-767017Y566170D02*
X-775736Y560457D01*
X-765520Y562529D01*
X-767017Y566170D01*
G01X-767324Y647739D02*
X-777742Y648080D01*
X-768194Y643899D01*
X-767324Y647739D01*
G01X-726066Y1277385D02*
X-725056Y1278035D01*
X-724478Y1278901D01*
X-724334Y1279875D01*
X-724478Y1280741D01*
X-725200Y1281608D01*
X-726066Y1282149D01*
X-726932Y1282257D01*
X-727943Y1282041D01*
X-728664Y1281283D01*
X-728953Y1280525D01*
Y1279550D01*
G01Y1280525D02*
X-729386Y1281174D01*
X-730108Y1281716D01*
X-730974Y1281932D01*
X-731840Y1281716D01*
X-732562Y1281174D01*
X-732995Y1280200D01*
X-732851Y1279226D01*
X-732273Y1278251D01*
G01X-727221Y1287021D02*
Y1289835D01*
G01X-761079Y1277710D02*
X-761944Y1278360D01*
X-762378Y1279117D01*
X-762522Y1279984D01*
X-762233Y1281066D01*
X-761512Y1281824D01*
X-760646Y1282041D01*
X-759779Y1281932D01*
X-759058Y1281499D01*
X-757614Y1279334D01*
X-756604Y1278360D01*
X-755160Y1277710D01*
X-753861Y1277493D01*
Y1282041D01*
G01Y1288428D02*
X-762522D01*
X-760790Y1287129D01*
G01X-753861D02*
Y1289727D01*
G01X-755160Y1294707D02*
X-754438Y1295357D01*
X-754005Y1296115D01*
X-753861Y1297089D01*
X-754150Y1298063D01*
X-754727Y1298821D01*
X-755737Y1299363D01*
X-756892Y1299471D01*
X-758047Y1299254D01*
X-758769Y1298713D01*
X-759346Y1297955D01*
X-759491Y1297197D01*
X-759346Y1296439D01*
X-758769Y1295465D01*
X-762522Y1295790D01*
Y1298713D01*
G01X-753572Y1305750D02*
X-753717Y1305533D01*
X-754005D01*
X-754150Y1305750D01*
X-754005Y1305967D01*
X-753717D01*
X-753572Y1305750D01*
G01X-762522Y1314411D02*
X-762233Y1313545D01*
X-761512Y1312895D01*
X-760646Y1312462D01*
X-759491Y1312137D01*
X-758191Y1312029D01*
X-756892Y1312137D01*
X-755737Y1312462D01*
X-754871Y1312895D01*
X-754150Y1313545D01*
X-753861Y1314411D01*
X-754150Y1315277D01*
X-754871Y1315927D01*
X-755737Y1316360D01*
X-756892Y1316685D01*
X-758191Y1316793D01*
X-759491Y1316685D01*
X-760646Y1316360D01*
X-761512Y1315927D01*
X-762233Y1315277D01*
X-762522Y1314411D01*
G01Y1323072D02*
X-762233Y1322206D01*
X-761512Y1321556D01*
X-760646Y1321123D01*
X-759491Y1320798D01*
X-758191Y1320690D01*
X-756892Y1320798D01*
X-755737Y1321123D01*
X-754871Y1321556D01*
X-754150Y1322206D01*
X-753861Y1323072D01*
X-754150Y1323938D01*
X-754871Y1324588D01*
X-755737Y1325021D01*
X-756892Y1325346D01*
X-758191Y1325454D01*
X-759491Y1325346D01*
X-760646Y1325021D01*
X-761512Y1324588D01*
X-762233Y1323938D01*
X-762522Y1323072D01*
G01X-731552Y1293301D02*
X-732417Y1293951D01*
X-732851Y1294708D01*
X-732995Y1295575D01*
X-732706Y1296657D01*
X-731985Y1297415D01*
X-731119Y1297632D01*
X-730252Y1297523D01*
X-729531Y1297090D01*
X-728087Y1294925D01*
X-727077Y1293951D01*
X-725633Y1293301D01*
X-724334Y1293084D01*
Y1297632D01*
G01X-731552Y1301962D02*
X-732417Y1302612D01*
X-732851Y1303369D01*
X-732995Y1304236D01*
X-732706Y1305318D01*
X-731985Y1306076D01*
X-731119Y1306293D01*
X-730252Y1306184D01*
X-729531Y1305751D01*
X-728087Y1303586D01*
X-727077Y1302612D01*
X-725633Y1301962D01*
X-724334Y1301745D01*
Y1306293D01*
G01X-731552Y1310623D02*
X-732417Y1311273D01*
X-732851Y1312030D01*
X-732995Y1312897D01*
X-732706Y1313979D01*
X-731985Y1314737D01*
X-731119Y1314954D01*
X-730252Y1314845D01*
X-729531Y1314412D01*
X-728087Y1312247D01*
X-727077Y1311273D01*
X-725633Y1310623D01*
X-724334Y1310406D01*
Y1314954D01*
G01X-724045Y1321341D02*
X-724190Y1321124D01*
X-724478D01*
X-724623Y1321341D01*
X-724478Y1321558D01*
X-724190D01*
X-724045Y1321341D01*
G01X-725633Y1327620D02*
X-724911Y1328270D01*
X-724478Y1329028D01*
X-724334Y1330002D01*
X-724623Y1330976D01*
X-725200Y1331734D01*
X-726210Y1332276D01*
X-727365Y1332384D01*
X-728520Y1332167D01*
X-729242Y1331626D01*
X-729819Y1330868D01*
X-729964Y1330110D01*
X-729819Y1329352D01*
X-729242Y1328378D01*
X-732995Y1328703D01*
Y1331626D01*
G01Y1338663D02*
X-732706Y1337797D01*
X-731985Y1337147D01*
X-731119Y1336714D01*
X-729964Y1336389D01*
X-728664Y1336281D01*
X-727365Y1336389D01*
X-726210Y1336714D01*
X-725344Y1337147D01*
X-724623Y1337797D01*
X-724334Y1338663D01*
X-724623Y1339529D01*
X-725344Y1340179D01*
X-726210Y1340612D01*
X-727365Y1340937D01*
X-728664Y1341045D01*
X-729964Y1340937D01*
X-731119Y1340612D01*
X-731985Y1340179D01*
X-732706Y1339529D01*
X-732995Y1338663D01*
G01X-691374Y-724881D02*
X-690379Y-723555D01*
X-689527Y-722798D01*
X-688391Y-722419D01*
X-687397Y-722798D01*
X-686687Y-723555D01*
X-686118Y-724691D01*
X-685976Y-726017D01*
X-686118Y-727153D01*
X-686687Y-728290D01*
X-687539Y-729236D01*
X-688533Y-729615D01*
X-689669Y-729236D01*
X-690663Y-728100D01*
X-691232Y-726396D01*
X-691374Y-724502D01*
X-691090Y-722041D01*
X-690663Y-720715D01*
X-689953Y-719389D01*
X-688959Y-718442D01*
X-687965Y-718253D01*
X-686971Y-718632D01*
X-686260Y-719579D01*
G01X-711928Y-512081D02*
X-706793Y-521152D01*
X-703794Y-518600D01*
X-711928Y-512081D01*
G01X-682339Y379169D02*
X-683204Y379819D01*
X-683638Y380576D01*
X-683782Y381443D01*
X-683493Y382525D01*
X-682772Y383283D01*
X-681906Y383500D01*
X-681039Y383391D01*
X-680318Y382958D01*
X-678874Y380793D01*
X-677864Y379819D01*
X-676420Y379169D01*
X-675121Y378952D01*
Y383500D01*
G01X-676853Y387505D02*
X-675843Y388155D01*
X-675265Y389021D01*
X-675121Y389995D01*
X-675265Y390861D01*
X-675987Y391728D01*
X-676853Y392269D01*
X-677719Y392377D01*
X-678730Y392161D01*
X-679451Y391403D01*
X-679740Y390645D01*
Y389670D01*
G01Y390645D02*
X-680173Y391294D01*
X-680895Y391836D01*
X-681761Y392052D01*
X-682627Y391836D01*
X-683349Y391294D01*
X-683782Y390320D01*
X-683638Y389346D01*
X-683060Y388371D01*
G01X-676420Y396166D02*
X-675698Y396816D01*
X-675265Y397574D01*
X-675121Y398548D01*
X-675410Y399522D01*
X-675987Y400280D01*
X-676997Y400822D01*
X-678152Y400930D01*
X-679307Y400713D01*
X-680029Y400172D01*
X-680606Y399414D01*
X-680751Y398656D01*
X-680606Y397898D01*
X-680029Y396924D01*
X-683782Y397249D01*
Y400172D01*
G01X-674832Y407209D02*
X-674977Y406992D01*
X-675265D01*
X-675410Y407209D01*
X-675265Y407426D01*
X-674977D01*
X-674832Y407209D01*
G01X-683782Y415870D02*
X-683493Y415004D01*
X-682772Y414354D01*
X-681906Y413921D01*
X-680751Y413596D01*
X-679451Y413488D01*
X-678152Y413596D01*
X-676997Y413921D01*
X-676131Y414354D01*
X-675410Y415004D01*
X-675121Y415870D01*
X-675410Y416736D01*
X-676131Y417386D01*
X-676997Y417819D01*
X-678152Y418144D01*
X-679451Y418252D01*
X-680751Y418144D01*
X-681906Y417819D01*
X-682772Y417386D01*
X-683493Y416736D01*
X-683782Y415870D01*
G01Y424531D02*
X-683493Y423665D01*
X-682772Y423015D01*
X-681906Y422582D01*
X-680751Y422257D01*
X-679451Y422149D01*
X-678152Y422257D01*
X-676997Y422582D01*
X-676131Y423015D01*
X-675410Y423665D01*
X-675121Y424531D01*
X-675410Y425397D01*
X-676131Y426047D01*
X-676997Y426480D01*
X-678152Y426805D01*
X-679451Y426913D01*
X-680751Y426805D01*
X-681906Y426480D01*
X-682772Y426047D01*
X-683493Y425397D01*
X-683782Y424531D01*
G01X-711153Y489753D02*
X-706715Y480321D01*
X-703533Y482640D01*
X-711153Y489753D01*
G01X-716033Y499930D02*
X-709291Y491980D01*
X-706823Y495048D01*
X-716033Y499930D01*
G01X-691374Y1452875D02*
X-690379Y1454201D01*
X-689527Y1454958D01*
X-688391Y1455337D01*
X-687397Y1454958D01*
X-686687Y1454201D01*
X-686118Y1453065D01*
X-685976Y1451739D01*
X-686118Y1450603D01*
X-686687Y1449466D01*
X-687539Y1448520D01*
X-688533Y1448141D01*
X-689669Y1448520D01*
X-690663Y1449656D01*
X-691232Y1451360D01*
X-691374Y1453254D01*
X-691090Y1455715D01*
X-690663Y1457041D01*
X-689953Y1458367D01*
X-688959Y1459314D01*
X-687965Y1459503D01*
X-686971Y1459124D01*
X-686260Y1458177D01*
G01X-600869Y-610299D02*
X-600111Y-611020D01*
X-599245Y-611309D01*
X-598378Y-611020D01*
X-597621Y-610154D01*
X-597079Y-608855D01*
X-596863Y-607556D01*
Y-605968D01*
X-597079Y-604669D01*
X-597621Y-603514D01*
X-598270Y-602937D01*
X-599028Y-602648D01*
X-599894Y-602937D01*
X-600544Y-603514D01*
X-600977Y-604380D01*
X-601193Y-605535D01*
X-600977Y-606545D01*
X-600435Y-607556D01*
X-599786Y-608133D01*
X-599028Y-608278D01*
X-598162Y-607989D01*
X-597512Y-607267D01*
X-596863Y-605968D01*
G01X-590367Y-611598D02*
X-590584Y-611453D01*
Y-611165D01*
X-590367Y-611020D01*
X-590150Y-611165D01*
Y-611453D01*
X-590367Y-611598D01*
G01X-584088Y-610010D02*
X-583438Y-610732D01*
X-582680Y-611165D01*
X-581706Y-611309D01*
X-580732Y-611020D01*
X-579974Y-610443D01*
X-579432Y-609433D01*
X-579324Y-608278D01*
X-579541Y-607123D01*
X-580082Y-606401D01*
X-580840Y-605824D01*
X-581598Y-605679D01*
X-582356Y-605824D01*
X-583330Y-606401D01*
X-583005Y-602648D01*
X-580082D01*
G01X-573045D02*
X-573911Y-602937D01*
X-574561Y-603658D01*
X-574994Y-604524D01*
X-575319Y-605679D01*
X-575427Y-606979D01*
X-575319Y-608278D01*
X-574994Y-609433D01*
X-574561Y-610299D01*
X-573911Y-611020D01*
X-573045Y-611309D01*
X-572179Y-611020D01*
X-571529Y-610299D01*
X-571096Y-609433D01*
X-570771Y-608278D01*
X-570663Y-606979D01*
X-570771Y-605679D01*
X-571096Y-604524D01*
X-571529Y-603658D01*
X-572179Y-602937D01*
X-573045Y-602648D01*
G01X-612417Y-611309D02*
Y-605535D01*
G01Y-606979D02*
X-611983Y-606257D01*
X-611334Y-605679D01*
X-610468Y-605535D01*
X-609710Y-605679D01*
X-609060Y-606257D01*
X-608735Y-607267D01*
Y-611309D01*
G01X-598693Y413280D02*
X-599776Y414724D01*
X-600317Y416167D01*
Y421941D01*
X-599776Y423385D01*
X-598693Y424828D01*
G01X-591656Y416167D02*
Y424828D01*
X-589058D01*
X-588192Y424395D01*
X-587542Y423385D01*
X-587326Y422230D01*
X-587542Y421075D01*
X-588084Y420209D01*
X-589058Y419776D01*
X-591656D01*
G01X-583537Y416167D02*
X-580830Y424828D01*
X-578123Y416167D01*
G01X-579098Y419198D02*
X-582562D01*
G01X-574551Y416167D02*
Y424828D01*
X-572386D01*
X-571519Y424395D01*
X-570870Y423818D01*
X-570328Y422952D01*
X-569895Y421941D01*
X-569787Y420497D01*
X-569895Y419054D01*
X-570328Y418043D01*
X-570870Y417177D01*
X-571519Y416600D01*
X-572386Y416167D01*
X-574551D01*
G01X-562967Y413280D02*
X-561884Y414724D01*
X-561343Y416167D01*
Y421941D01*
X-561884Y423385D01*
X-562967Y424828D01*
G01X-555388Y413280D02*
X-556471Y414724D01*
X-557012Y416167D01*
Y421941D01*
X-556471Y423385D01*
X-555388Y424828D01*
G01X-548676Y416167D02*
Y424828D01*
X-543696Y416167D01*
Y424828D01*
G01X-537525Y416167D02*
X-538391Y416311D01*
X-539149Y416889D01*
X-539799Y417755D01*
X-540232Y418765D01*
X-540448Y419920D01*
Y421075D01*
X-540232Y422230D01*
X-539799Y423240D01*
X-539149Y424106D01*
X-538391Y424684D01*
X-537525Y424828D01*
X-536659Y424684D01*
X-535901Y424106D01*
X-535251Y423240D01*
X-534818Y422230D01*
X-534602Y421075D01*
Y419920D01*
X-534818Y418765D01*
X-535251Y417755D01*
X-535901Y416889D01*
X-536659Y416311D01*
X-537525Y416167D01*
G01X-520203Y424828D02*
Y416167D01*
G01X-522693Y424828D02*
X-517713D01*
G01X-513707Y416167D02*
Y424828D01*
X-511001D01*
X-510135Y424395D01*
X-509593Y423818D01*
X-509377Y422663D01*
X-509593Y421508D01*
X-510243Y420786D01*
X-511001Y420353D01*
X-513707D01*
G01X-511001D02*
X-509377Y416167D01*
G01X-505588D02*
X-502881Y424828D01*
X-500174Y416167D01*
G01X-501149Y419198D02*
X-504613D01*
G01X-491838Y424106D02*
X-492488Y424539D01*
X-493246Y424828D01*
X-494112D01*
X-495086Y424395D01*
X-495844Y423673D01*
X-496385Y422807D01*
X-496819Y421364D01*
X-496927Y420064D01*
X-496710Y418765D01*
X-496385Y417899D01*
X-495736Y417033D01*
X-494978Y416456D01*
X-494220Y416167D01*
X-493462D01*
X-492704Y416456D01*
X-492055Y416889D01*
X-491513Y417466D01*
G01X-483394Y416167D02*
X-487724D01*
Y424828D01*
X-483394D01*
G01X-485126Y420642D02*
X-487724D01*
G01X-470944Y416167D02*
X-468237Y424828D01*
X-465530Y416167D01*
G01X-466505Y419198D02*
X-469969D01*
G01X-459576Y424828D02*
Y416167D01*
G01X-462066Y424828D02*
X-457086D01*
G01X-444961Y416167D02*
X-442254Y424828D01*
X-439547Y416167D01*
G01X-440522Y419198D02*
X-443986D01*
G01X-435758Y424828D02*
Y416167D01*
X-431428D01*
G01X-427097Y424828D02*
Y416167D01*
X-422767D01*
G01X-409775Y424828D02*
Y416167D01*
X-405445D01*
G01X-401656D02*
X-398949Y424828D01*
X-396242Y416167D01*
G01X-397217Y419198D02*
X-400681D01*
G01X-390288Y416167D02*
Y420064D01*
X-392453Y424828D01*
G01X-388123D02*
X-390288Y420064D01*
G01X-379462Y416167D02*
X-383792D01*
Y424828D01*
X-379462D01*
G01X-381194Y420642D02*
X-383792D01*
G01X-375131Y416167D02*
Y424828D01*
X-372425D01*
X-371559Y424395D01*
X-371017Y423818D01*
X-370801Y422663D01*
X-371017Y421508D01*
X-371667Y420786D01*
X-372425Y420353D01*
X-375131D01*
G01X-372425D02*
X-370801Y416167D01*
G01X-366579Y417322D02*
X-365712Y416600D01*
X-364738Y416167D01*
X-363872D01*
X-363006Y416600D01*
X-362356Y417322D01*
X-362031Y418332D01*
X-362248Y419343D01*
X-362789Y420209D01*
X-363764Y420786D01*
X-365063Y421075D01*
X-365821Y421652D01*
X-366146Y422663D01*
X-365929Y423673D01*
X-365388Y424395D01*
X-364630Y424828D01*
X-363872D01*
X-363114Y424539D01*
X-362464Y423818D01*
G01X-355103Y413280D02*
X-354020Y414724D01*
X-353479Y416167D01*
Y421941D01*
X-354020Y423385D01*
X-355103Y424828D01*
G01X-631175Y417177D02*
X-630417Y416456D01*
X-629551Y416167D01*
X-628684Y416456D01*
X-627927Y417322D01*
X-627385Y418621D01*
X-627169Y419920D01*
Y421508D01*
X-627385Y422807D01*
X-627927Y423962D01*
X-628576Y424539D01*
X-629334Y424828D01*
X-630200Y424539D01*
X-630850Y423962D01*
X-631283Y423096D01*
X-631499Y421941D01*
X-631283Y420931D01*
X-630741Y419920D01*
X-630092Y419343D01*
X-629334Y419198D01*
X-628468Y419487D01*
X-627818Y420209D01*
X-627169Y421508D01*
G01X-620673Y415878D02*
X-620890Y416023D01*
Y416311D01*
X-620673Y416456D01*
X-620456Y416311D01*
Y416023D01*
X-620673Y415878D01*
G01X-614394Y417466D02*
X-613744Y416744D01*
X-612986Y416311D01*
X-612012Y416167D01*
X-611038Y416456D01*
X-610280Y417033D01*
X-609738Y418043D01*
X-609630Y419198D01*
X-609847Y420353D01*
X-610388Y421075D01*
X-611146Y421652D01*
X-611904Y421797D01*
X-612662Y421652D01*
X-613636Y421075D01*
X-613311Y424828D01*
X-610388D01*
G01X-603351D02*
X-604217Y424539D01*
X-604867Y423818D01*
X-605300Y422952D01*
X-605625Y421797D01*
X-605733Y420497D01*
X-605625Y419198D01*
X-605300Y418043D01*
X-604867Y417177D01*
X-604217Y416456D01*
X-603351Y416167D01*
X-602485Y416456D01*
X-601835Y417177D01*
X-601402Y418043D01*
X-601077Y419198D01*
X-600969Y420497D01*
X-601077Y421797D01*
X-601402Y422952D01*
X-601835Y423818D01*
X-602485Y424539D01*
X-603351Y424828D01*
G01X-642723Y416167D02*
Y421941D01*
G01Y420497D02*
X-642289Y421219D01*
X-641640Y421797D01*
X-640774Y421941D01*
X-640016Y421797D01*
X-639366Y421219D01*
X-639041Y420209D01*
Y416167D01*
G01X-590850Y444561D02*
X-591933Y446005D01*
X-592474Y447448D01*
Y453222D01*
X-591933Y454666D01*
X-590850Y456109D01*
G01X-583813Y447448D02*
Y456109D01*
X-581215D01*
X-580349Y455676D01*
X-579699Y454666D01*
X-579483Y453511D01*
X-579699Y452356D01*
X-580241Y451490D01*
X-581215Y451057D01*
X-583813D01*
G01X-572987Y456109D02*
Y447448D01*
G01X-575477Y456109D02*
X-570497D01*
G01X-566600Y447448D02*
Y456109D01*
G01X-562052D02*
Y447448D01*
G01Y451778D02*
X-566600D01*
G01X-555124Y444561D02*
X-554041Y446005D01*
X-553500Y447448D01*
Y453222D01*
X-554041Y454666D01*
X-555124Y456109D01*
G01X-620191Y447448D02*
Y456109D01*
X-624197Y449902D01*
X-618783D01*
G01X-612829Y447159D02*
X-613046Y447304D01*
Y447592D01*
X-612829Y447737D01*
X-612612Y447592D01*
Y447304D01*
X-612829Y447159D01*
G01X-604168Y456109D02*
X-605034Y455820D01*
X-605684Y455099D01*
X-606117Y454233D01*
X-606442Y453078D01*
X-606550Y451778D01*
X-606442Y450479D01*
X-606117Y449324D01*
X-605684Y448458D01*
X-605034Y447737D01*
X-604168Y447448D01*
X-603302Y447737D01*
X-602652Y448458D01*
X-602219Y449324D01*
X-601894Y450479D01*
X-601786Y451778D01*
X-601894Y453078D01*
X-602219Y454233D01*
X-602652Y455099D01*
X-603302Y455820D01*
X-604168Y456109D01*
G01X-595507D02*
X-596373Y455820D01*
X-597023Y455099D01*
X-597456Y454233D01*
X-597781Y453078D01*
X-597889Y451778D01*
X-597781Y450479D01*
X-597456Y449324D01*
X-597023Y448458D01*
X-596373Y447737D01*
X-595507Y447448D01*
X-594641Y447737D01*
X-593991Y448458D01*
X-593558Y449324D01*
X-593233Y450479D01*
X-593125Y451778D01*
X-593233Y453078D01*
X-593558Y454233D01*
X-593991Y455099D01*
X-594641Y455820D01*
X-595507Y456109D01*
G01X-634879Y447448D02*
Y453222D01*
G01Y451778D02*
X-634445Y452500D01*
X-633796Y453078D01*
X-632930Y453222D01*
X-632172Y453078D01*
X-631522Y452500D01*
X-631197Y451490D01*
Y447448D01*
G01X-630338Y507031D02*
X-629580Y507175D01*
X-628714Y507608D01*
X-628173Y508330D01*
X-627956Y509341D01*
X-628173Y510351D01*
X-628822Y511217D01*
X-629797Y511650D01*
X-630879D01*
X-631529Y511939D01*
X-632070Y512661D01*
X-632287Y513671D01*
X-631962Y514682D01*
X-631204Y515403D01*
X-630338Y515692D01*
X-629472Y515403D01*
X-628714Y514682D01*
X-628389Y513671D01*
X-628606Y512661D01*
X-629147Y511939D01*
X-629797Y511650D01*
X-630879D01*
X-631854Y511217D01*
X-632503Y510351D01*
X-632720Y509341D01*
X-632503Y508330D01*
X-631962Y507608D01*
X-631096Y507175D01*
X-630338Y507031D01*
G01X-621677Y506742D02*
X-621894Y506887D01*
Y507175D01*
X-621677Y507320D01*
X-621460Y507175D01*
Y506887D01*
X-621677Y506742D01*
G01X-613016Y515692D02*
X-613882Y515403D01*
X-614532Y514682D01*
X-614965Y513816D01*
X-615290Y512661D01*
X-615398Y511361D01*
X-615290Y510062D01*
X-614965Y508907D01*
X-614532Y508041D01*
X-613882Y507320D01*
X-613016Y507031D01*
X-612150Y507320D01*
X-611500Y508041D01*
X-611067Y508907D01*
X-610742Y510062D01*
X-610634Y511361D01*
X-610742Y512661D01*
X-611067Y513816D01*
X-611500Y514682D01*
X-612150Y515403D01*
X-613016Y515692D01*
G01X-604355D02*
X-605221Y515403D01*
X-605871Y514682D01*
X-606304Y513816D01*
X-606629Y512661D01*
X-606737Y511361D01*
X-606629Y510062D01*
X-606304Y508907D01*
X-605871Y508041D01*
X-605221Y507320D01*
X-604355Y507031D01*
X-603489Y507320D01*
X-602839Y508041D01*
X-602406Y508907D01*
X-602081Y510062D01*
X-601973Y511361D01*
X-602081Y512661D01*
X-602406Y513816D01*
X-602839Y514682D01*
X-603489Y515403D01*
X-604355Y515692D01*
G01X-616804Y566414D02*
X-616154Y567279D01*
X-615397Y567713D01*
X-614530Y567857D01*
X-613448Y567568D01*
X-612690Y566847D01*
X-612473Y565981D01*
X-612582Y565114D01*
X-613015Y564393D01*
X-615180Y562949D01*
X-616154Y561939D01*
X-616804Y560495D01*
X-617021Y559196D01*
X-612473D01*
G01X-606086D02*
Y567857D01*
X-607385Y566125D01*
G01Y559196D02*
X-604787D01*
G01X-597425Y558907D02*
X-597642Y559052D01*
Y559340D01*
X-597425Y559485D01*
X-597208Y559340D01*
Y559052D01*
X-597425Y558907D01*
G01X-590821Y566414D02*
X-590171Y567279D01*
X-589414Y567713D01*
X-588547Y567857D01*
X-587465Y567568D01*
X-586707Y566847D01*
X-586490Y565981D01*
X-586599Y565114D01*
X-587032Y564393D01*
X-589197Y562949D01*
X-590171Y561939D01*
X-590821Y560495D01*
X-591038Y559196D01*
X-586490D01*
G01X-582485Y560495D02*
X-581835Y559773D01*
X-581077Y559340D01*
X-580103Y559196D01*
X-579129Y559485D01*
X-578371Y560062D01*
X-577829Y561072D01*
X-577721Y562227D01*
X-577938Y563382D01*
X-578479Y564104D01*
X-579237Y564681D01*
X-579995Y564826D01*
X-580753Y564681D01*
X-581727Y564104D01*
X-581402Y567857D01*
X-578479D01*
G01X-632395Y566414D02*
X-631745Y567279D01*
X-630988Y567713D01*
X-630121Y567857D01*
X-629039Y567568D01*
X-628281Y566847D01*
X-628064Y565981D01*
X-628173Y565114D01*
X-628606Y564393D01*
X-630771Y562949D01*
X-631745Y561939D01*
X-632395Y560495D01*
X-632612Y559196D01*
X-628064D01*
G01X-623084Y562083D02*
X-620270D01*
G01X-626252Y613486D02*
X-625385Y612764D01*
X-624411Y612331D01*
X-623545D01*
X-622679Y612764D01*
X-622029Y613486D01*
X-621704Y614496D01*
X-621921Y615507D01*
X-622462Y616373D01*
X-623437Y616950D01*
X-624736Y617239D01*
X-625494Y617816D01*
X-625819Y618827D01*
X-625602Y619837D01*
X-625061Y620559D01*
X-624303Y620992D01*
X-623545D01*
X-622787Y620703D01*
X-622137Y619982D01*
G01X-613152Y612331D02*
X-617482D01*
Y620992D01*
X-613152D01*
G01X-614884Y616806D02*
X-617482D01*
G01X-604491Y612331D02*
X-608821D01*
Y620992D01*
X-604491D01*
G01X-606223Y616806D02*
X-608821D01*
G01X-591716Y612331D02*
Y620992D01*
X-589551D01*
X-588684Y620559D01*
X-588035Y619982D01*
X-587493Y619116D01*
X-587060Y618105D01*
X-586952Y616661D01*
X-587060Y615218D01*
X-587493Y614207D01*
X-588035Y613341D01*
X-588684Y612764D01*
X-589551Y612331D01*
X-591716D01*
G01X-578508D02*
X-582838D01*
Y620992D01*
X-578508D01*
G01X-580240Y616806D02*
X-582838D01*
G01X-572012Y620992D02*
Y612331D01*
G01X-574502Y620992D02*
X-569522D01*
G01X-566058Y612331D02*
X-563351Y620992D01*
X-560644Y612331D01*
G01X-561619Y615362D02*
X-565083D01*
G01X-555989Y620992D02*
X-553391D01*
G01X-554690D02*
Y612331D01*
G01X-555989D02*
X-553391D01*
G01X-548194Y620992D02*
Y612331D01*
X-543864D01*
G01X-527841Y616950D02*
X-527408Y617383D01*
X-527083Y618105D01*
X-526866Y619116D01*
X-527083Y619982D01*
X-527516Y620559D01*
X-528274Y620992D01*
X-531197D01*
Y612331D01*
X-527624D01*
X-526866Y612908D01*
X-526433Y613774D01*
X-526217Y614785D01*
X-526433Y615795D01*
X-527083Y616661D01*
X-527841Y616950D01*
X-531197D01*
G01X-617129Y678605D02*
X-616479Y677883D01*
X-615721Y677450D01*
X-614747Y677306D01*
X-613773Y677595D01*
X-613015Y678172D01*
X-612473Y679182D01*
X-612365Y680337D01*
X-612582Y681492D01*
X-613123Y682214D01*
X-613881Y682791D01*
X-614639Y682936D01*
X-615397Y682791D01*
X-616371Y682214D01*
X-616046Y685967D01*
X-613123D01*
G01X-606086Y677306D02*
Y685967D01*
X-607385Y684235D01*
G01Y677306D02*
X-604787D01*
G01X-597425Y677017D02*
X-597642Y677162D01*
Y677450D01*
X-597425Y677595D01*
X-597208Y677450D01*
Y677162D01*
X-597425Y677017D01*
G01X-590821Y684524D02*
X-590171Y685389D01*
X-589414Y685823D01*
X-588547Y685967D01*
X-587465Y685678D01*
X-586707Y684957D01*
X-586490Y684091D01*
X-586599Y683224D01*
X-587032Y682503D01*
X-589197Y681059D01*
X-590171Y680049D01*
X-590821Y678605D01*
X-591038Y677306D01*
X-586490D01*
G01X-582485Y678605D02*
X-581835Y677883D01*
X-581077Y677450D01*
X-580103Y677306D01*
X-579129Y677595D01*
X-578371Y678172D01*
X-577829Y679182D01*
X-577721Y680337D01*
X-577938Y681492D01*
X-578479Y682214D01*
X-579237Y682791D01*
X-579995Y682936D01*
X-580753Y682791D01*
X-581727Y682214D01*
X-581402Y685967D01*
X-578479D01*
G01X-632395Y684524D02*
X-631745Y685389D01*
X-630988Y685823D01*
X-630121Y685967D01*
X-629039Y685678D01*
X-628281Y684957D01*
X-628064Y684091D01*
X-628173Y683224D01*
X-628606Y682503D01*
X-630771Y681059D01*
X-631745Y680049D01*
X-632395Y678605D01*
X-632612Y677306D01*
X-628064D01*
G01X-623084Y680193D02*
X-620270D01*
G01X-630338Y947976D02*
Y956637D01*
X-631637Y954905D01*
G01Y947976D02*
X-629039D01*
G01X-623734Y955194D02*
X-623084Y956059D01*
X-622327Y956493D01*
X-621460Y956637D01*
X-620378Y956348D01*
X-619620Y955627D01*
X-619403Y954761D01*
X-619512Y953894D01*
X-619945Y953173D01*
X-622110Y951729D01*
X-623084Y950719D01*
X-623734Y949275D01*
X-623951Y947976D01*
X-619403D01*
G01X-613016Y956637D02*
X-613882Y956348D01*
X-614532Y955627D01*
X-614965Y954761D01*
X-615290Y953606D01*
X-615398Y952306D01*
X-615290Y951007D01*
X-614965Y949852D01*
X-614532Y948986D01*
X-613882Y948265D01*
X-613016Y947976D01*
X-612150Y948265D01*
X-611500Y948986D01*
X-611067Y949852D01*
X-610742Y951007D01*
X-610634Y952306D01*
X-610742Y953606D01*
X-611067Y954761D01*
X-611500Y955627D01*
X-612150Y956348D01*
X-613016Y956637D01*
G01X-604355Y947687D02*
X-604572Y947832D01*
Y948120D01*
X-604355Y948265D01*
X-604138Y948120D01*
Y947832D01*
X-604355Y947687D01*
G01X-595694Y956637D02*
X-596560Y956348D01*
X-597210Y955627D01*
X-597643Y954761D01*
X-597968Y953606D01*
X-598076Y952306D01*
X-597968Y951007D01*
X-597643Y949852D01*
X-597210Y948986D01*
X-596560Y948265D01*
X-595694Y947976D01*
X-594828Y948265D01*
X-594178Y948986D01*
X-593745Y949852D01*
X-593420Y951007D01*
X-593312Y952306D01*
X-593420Y953606D01*
X-593745Y954761D01*
X-594178Y955627D01*
X-594828Y956348D01*
X-595694Y956637D01*
G01X-587033D02*
X-587899Y956348D01*
X-588549Y955627D01*
X-588982Y954761D01*
X-589307Y953606D01*
X-589415Y952306D01*
X-589307Y951007D01*
X-588982Y949852D01*
X-588549Y948986D01*
X-587899Y948265D01*
X-587033Y947976D01*
X-586167Y948265D01*
X-585517Y948986D01*
X-585084Y949852D01*
X-584759Y951007D01*
X-584651Y952306D01*
X-584759Y953606D01*
X-585084Y954761D01*
X-585517Y955627D01*
X-586167Y956348D01*
X-587033Y956637D01*
G01X-630338Y1105456D02*
Y1114117D01*
X-631637Y1112385D01*
G01Y1105456D02*
X-629039D01*
G01X-623734Y1109065D02*
X-622976Y1110075D01*
X-622327Y1110653D01*
X-621460Y1110941D01*
X-620703Y1110653D01*
X-620161Y1110075D01*
X-619728Y1109209D01*
X-619620Y1108199D01*
X-619728Y1107332D01*
X-620161Y1106466D01*
X-620811Y1105745D01*
X-621569Y1105456D01*
X-622435Y1105745D01*
X-623193Y1106611D01*
X-623626Y1107910D01*
X-623734Y1109353D01*
X-623518Y1111230D01*
X-623193Y1112241D01*
X-622651Y1113251D01*
X-621894Y1113973D01*
X-621136Y1114117D01*
X-620378Y1113828D01*
X-619836Y1113107D01*
G01X-613016Y1114117D02*
X-613882Y1113828D01*
X-614532Y1113107D01*
X-614965Y1112241D01*
X-615290Y1111086D01*
X-615398Y1109786D01*
X-615290Y1108487D01*
X-614965Y1107332D01*
X-614532Y1106466D01*
X-613882Y1105745D01*
X-613016Y1105456D01*
X-612150Y1105745D01*
X-611500Y1106466D01*
X-611067Y1107332D01*
X-610742Y1108487D01*
X-610634Y1109786D01*
X-610742Y1111086D01*
X-611067Y1112241D01*
X-611500Y1113107D01*
X-612150Y1113828D01*
X-613016Y1114117D01*
G01X-604355Y1105167D02*
X-604572Y1105312D01*
Y1105600D01*
X-604355Y1105745D01*
X-604138Y1105600D01*
Y1105312D01*
X-604355Y1105167D01*
G01X-595694Y1114117D02*
X-596560Y1113828D01*
X-597210Y1113107D01*
X-597643Y1112241D01*
X-597968Y1111086D01*
X-598076Y1109786D01*
X-597968Y1108487D01*
X-597643Y1107332D01*
X-597210Y1106466D01*
X-596560Y1105745D01*
X-595694Y1105456D01*
X-594828Y1105745D01*
X-594178Y1106466D01*
X-593745Y1107332D01*
X-593420Y1108487D01*
X-593312Y1109786D01*
X-593420Y1111086D01*
X-593745Y1112241D01*
X-594178Y1113107D01*
X-594828Y1113828D01*
X-595694Y1114117D01*
G01X-587033D02*
X-587899Y1113828D01*
X-588549Y1113107D01*
X-588982Y1112241D01*
X-589307Y1111086D01*
X-589415Y1109786D01*
X-589307Y1108487D01*
X-588982Y1107332D01*
X-588549Y1106466D01*
X-587899Y1105745D01*
X-587033Y1105456D01*
X-586167Y1105745D01*
X-585517Y1106466D01*
X-585084Y1107332D01*
X-584759Y1108487D01*
X-584651Y1109786D01*
X-584759Y1111086D01*
X-585084Y1112241D01*
X-585517Y1113107D01*
X-586167Y1113828D01*
X-587033Y1114117D01*
G01X-630338Y1081834D02*
Y1090495D01*
X-631637Y1088763D01*
G01Y1081834D02*
X-629039D01*
G01X-624059Y1083133D02*
X-623409Y1082411D01*
X-622651Y1081978D01*
X-621677Y1081834D01*
X-620703Y1082123D01*
X-619945Y1082700D01*
X-619403Y1083710D01*
X-619295Y1084865D01*
X-619512Y1086020D01*
X-620053Y1086742D01*
X-620811Y1087319D01*
X-621569Y1087464D01*
X-622327Y1087319D01*
X-623301Y1086742D01*
X-622976Y1090495D01*
X-620053D01*
G01X-611717Y1081834D02*
Y1090495D01*
X-615723Y1084288D01*
X-610309D01*
G01X-604355Y1081545D02*
X-604572Y1081690D01*
Y1081978D01*
X-604355Y1082123D01*
X-604138Y1081978D01*
Y1081690D01*
X-604355Y1081545D01*
G01X-595694Y1090495D02*
X-596560Y1090206D01*
X-597210Y1089485D01*
X-597643Y1088619D01*
X-597968Y1087464D01*
X-598076Y1086164D01*
X-597968Y1084865D01*
X-597643Y1083710D01*
X-597210Y1082844D01*
X-596560Y1082123D01*
X-595694Y1081834D01*
X-594828Y1082123D01*
X-594178Y1082844D01*
X-593745Y1083710D01*
X-593420Y1084865D01*
X-593312Y1086164D01*
X-593420Y1087464D01*
X-593745Y1088619D01*
X-594178Y1089485D01*
X-594828Y1090206D01*
X-595694Y1090495D01*
G01X-587033D02*
X-587899Y1090206D01*
X-588549Y1089485D01*
X-588982Y1088619D01*
X-589307Y1087464D01*
X-589415Y1086164D01*
X-589307Y1084865D01*
X-588982Y1083710D01*
X-588549Y1082844D01*
X-587899Y1082123D01*
X-587033Y1081834D01*
X-586167Y1082123D01*
X-585517Y1082844D01*
X-585084Y1083710D01*
X-584759Y1084865D01*
X-584651Y1086164D01*
X-584759Y1087464D01*
X-585084Y1088619D01*
X-585517Y1089485D01*
X-586167Y1090206D01*
X-587033Y1090495D01*
G01X-628059Y1215692D02*
Y1224353D01*
X-629358Y1222621D01*
G01Y1215692D02*
X-626760D01*
G01X-619398D02*
X-618640Y1215836D01*
X-617774Y1216269D01*
X-617233Y1216991D01*
X-617016Y1218002D01*
X-617233Y1219012D01*
X-617882Y1219878D01*
X-618857Y1220311D01*
X-619939D01*
X-620589Y1220600D01*
X-621130Y1221322D01*
X-621347Y1222332D01*
X-621022Y1223343D01*
X-620264Y1224064D01*
X-619398Y1224353D01*
X-618532Y1224064D01*
X-617774Y1223343D01*
X-617449Y1222332D01*
X-617666Y1221322D01*
X-618207Y1220600D01*
X-618857Y1220311D01*
X-619939D01*
X-620914Y1219878D01*
X-621563Y1219012D01*
X-621780Y1218002D01*
X-621563Y1216991D01*
X-621022Y1216269D01*
X-620156Y1215836D01*
X-619398Y1215692D01*
G01X-610737D02*
X-609979Y1215836D01*
X-609113Y1216269D01*
X-608572Y1216991D01*
X-608355Y1218002D01*
X-608572Y1219012D01*
X-609221Y1219878D01*
X-610196Y1220311D01*
X-611278D01*
X-611928Y1220600D01*
X-612469Y1221322D01*
X-612686Y1222332D01*
X-612361Y1223343D01*
X-611603Y1224064D01*
X-610737Y1224353D01*
X-609871Y1224064D01*
X-609113Y1223343D01*
X-608788Y1222332D01*
X-609005Y1221322D01*
X-609546Y1220600D01*
X-610196Y1220311D01*
X-611278D01*
X-612253Y1219878D01*
X-612902Y1219012D01*
X-613119Y1218002D01*
X-612902Y1216991D01*
X-612361Y1216269D01*
X-611495Y1215836D01*
X-610737Y1215692D01*
G01X-602076Y1215403D02*
X-602293Y1215548D01*
Y1215836D01*
X-602076Y1215981D01*
X-601859Y1215836D01*
Y1215548D01*
X-602076Y1215403D01*
G01X-593415Y1224353D02*
X-594281Y1224064D01*
X-594931Y1223343D01*
X-595364Y1222477D01*
X-595689Y1221322D01*
X-595797Y1220022D01*
X-595689Y1218723D01*
X-595364Y1217568D01*
X-594931Y1216702D01*
X-594281Y1215981D01*
X-593415Y1215692D01*
X-592549Y1215981D01*
X-591899Y1216702D01*
X-591466Y1217568D01*
X-591141Y1218723D01*
X-591033Y1220022D01*
X-591141Y1221322D01*
X-591466Y1222477D01*
X-591899Y1223343D01*
X-592549Y1224064D01*
X-593415Y1224353D01*
G01X-584754D02*
X-585620Y1224064D01*
X-586270Y1223343D01*
X-586703Y1222477D01*
X-587028Y1221322D01*
X-587136Y1220022D01*
X-587028Y1218723D01*
X-586703Y1217568D01*
X-586270Y1216702D01*
X-585620Y1215981D01*
X-584754Y1215692D01*
X-583888Y1215981D01*
X-583238Y1216702D01*
X-582805Y1217568D01*
X-582480Y1218723D01*
X-582372Y1220022D01*
X-582480Y1221322D01*
X-582805Y1222477D01*
X-583238Y1223343D01*
X-583888Y1224064D01*
X-584754Y1224353D01*
G01X-568388Y-614196D02*
X-569471Y-612752D01*
X-570012Y-611309D01*
Y-605535D01*
X-569471Y-604091D01*
X-568388Y-602648D01*
G01X-561351Y-611309D02*
Y-602648D01*
X-558753D01*
X-557887Y-603081D01*
X-557237Y-604091D01*
X-557021Y-605246D01*
X-557237Y-606401D01*
X-557779Y-607267D01*
X-558753Y-607700D01*
X-561351D01*
G01X-553232Y-611309D02*
X-550525Y-602648D01*
X-547818Y-611309D01*
G01X-548793Y-608278D02*
X-552257D01*
G01X-544246Y-611309D02*
Y-602648D01*
X-542081D01*
X-541214Y-603081D01*
X-540565Y-603658D01*
X-540023Y-604524D01*
X-539590Y-605535D01*
X-539482Y-606979D01*
X-539590Y-608422D01*
X-540023Y-609433D01*
X-540565Y-610299D01*
X-541214Y-610876D01*
X-542081Y-611309D01*
X-544246D01*
G01X-532662Y-614196D02*
X-531579Y-612752D01*
X-531038Y-611309D01*
Y-605535D01*
X-531579Y-604091D01*
X-532662Y-602648D01*
G01X-525083Y-614196D02*
X-526166Y-612752D01*
X-526707Y-611309D01*
Y-605535D01*
X-526166Y-604091D01*
X-525083Y-602648D01*
G01X-518371Y-611309D02*
Y-602648D01*
X-513391Y-611309D01*
Y-602648D01*
G01X-507220Y-611309D02*
X-508086Y-611165D01*
X-508844Y-610587D01*
X-509494Y-609721D01*
X-509927Y-608711D01*
X-510143Y-607556D01*
Y-606401D01*
X-509927Y-605246D01*
X-509494Y-604236D01*
X-508844Y-603370D01*
X-508086Y-602792D01*
X-507220Y-602648D01*
X-506354Y-602792D01*
X-505596Y-603370D01*
X-504946Y-604236D01*
X-504513Y-605246D01*
X-504297Y-606401D01*
Y-607556D01*
X-504513Y-608711D01*
X-504946Y-609721D01*
X-505596Y-610587D01*
X-506354Y-611165D01*
X-507220Y-611309D01*
G01X-489898Y-602648D02*
Y-611309D01*
G01X-492388Y-602648D02*
X-487408D01*
G01X-483402Y-611309D02*
Y-602648D01*
X-480696D01*
X-479830Y-603081D01*
X-479288Y-603658D01*
X-479072Y-604813D01*
X-479288Y-605968D01*
X-479938Y-606690D01*
X-480696Y-607123D01*
X-483402D01*
G01X-480696D02*
X-479072Y-611309D01*
G01X-475283D02*
X-472576Y-602648D01*
X-469869Y-611309D01*
G01X-470844Y-608278D02*
X-474308D01*
G01X-461533Y-603370D02*
X-462183Y-602937D01*
X-462941Y-602648D01*
X-463807D01*
X-464781Y-603081D01*
X-465539Y-603803D01*
X-466080Y-604669D01*
X-466514Y-606112D01*
X-466622Y-607412D01*
X-466405Y-608711D01*
X-466080Y-609577D01*
X-465431Y-610443D01*
X-464673Y-611020D01*
X-463915Y-611309D01*
X-463157D01*
X-462399Y-611020D01*
X-461750Y-610587D01*
X-461208Y-610010D01*
G01X-453089Y-611309D02*
X-457419D01*
Y-602648D01*
X-453089D01*
G01X-454821Y-606834D02*
X-457419D01*
G01X-440639Y-611309D02*
X-437932Y-602648D01*
X-435225Y-611309D01*
G01X-436200Y-608278D02*
X-439664D01*
G01X-429271Y-602648D02*
Y-611309D01*
G01X-431761Y-602648D02*
X-426781D01*
G01X-414656Y-611309D02*
X-411949Y-602648D01*
X-409242Y-611309D01*
G01X-410217Y-608278D02*
X-413681D01*
G01X-405453Y-602648D02*
Y-611309D01*
X-401123D01*
G01X-396792Y-602648D02*
Y-611309D01*
X-392462D01*
G01X-379470Y-602648D02*
Y-611309D01*
X-375140D01*
G01X-371351D02*
X-368644Y-602648D01*
X-365937Y-611309D01*
G01X-366912Y-608278D02*
X-370376D01*
G01X-359983Y-611309D02*
Y-607412D01*
X-362148Y-602648D01*
G01X-357818D02*
X-359983Y-607412D01*
G01X-349157Y-611309D02*
X-353487D01*
Y-602648D01*
X-349157D01*
G01X-350889Y-606834D02*
X-353487D01*
G01X-344826Y-611309D02*
Y-602648D01*
X-342120D01*
X-341254Y-603081D01*
X-340712Y-603658D01*
X-340496Y-604813D01*
X-340712Y-605968D01*
X-341362Y-606690D01*
X-342120Y-607123D01*
X-344826D01*
G01X-342120D02*
X-340496Y-611309D01*
G01X-336274Y-610154D02*
X-335407Y-610876D01*
X-334433Y-611309D01*
X-333567D01*
X-332701Y-610876D01*
X-332051Y-610154D01*
X-331726Y-609144D01*
X-331943Y-608133D01*
X-332484Y-607267D01*
X-333459Y-606690D01*
X-334758Y-606401D01*
X-335516Y-605824D01*
X-335841Y-604813D01*
X-335624Y-603803D01*
X-335083Y-603081D01*
X-334325Y-602648D01*
X-333567D01*
X-332809Y-602937D01*
X-332159Y-603658D01*
G01X-324798Y-614196D02*
X-323715Y-612752D01*
X-323174Y-611309D01*
Y-605535D01*
X-323715Y-604091D01*
X-324798Y-602648D01*
G01X-469290Y-729615D02*
X-469006Y-727153D01*
X-468580Y-725070D01*
X-468012Y-723177D01*
X-467302Y-721094D01*
X-466165Y-718253D01*
X-471847D01*
G01X-469290Y1448141D02*
X-469006Y1450603D01*
X-468580Y1452686D01*
X-468012Y1454579D01*
X-467302Y1456662D01*
X-466165Y1459503D01*
X-471847D01*
G01X-249336Y-729615D02*
X-248342Y-729426D01*
X-247206Y-728858D01*
X-246495Y-727911D01*
X-246211Y-726585D01*
X-246495Y-725260D01*
X-247348Y-724123D01*
X-248626Y-723555D01*
X-250046D01*
X-250898Y-723177D01*
X-251609Y-722230D01*
X-251893Y-720904D01*
X-251466Y-719579D01*
X-250472Y-718632D01*
X-249336Y-718253D01*
X-248200Y-718632D01*
X-247206Y-719579D01*
X-246779Y-720904D01*
X-247064Y-722230D01*
X-247774Y-723177D01*
X-248626Y-723555D01*
X-250046D01*
X-251324Y-724123D01*
X-252177Y-725260D01*
X-252461Y-726585D01*
X-252177Y-727911D01*
X-251466Y-728858D01*
X-250330Y-729426D01*
X-249336Y-729615D01*
G01Y1448141D02*
X-248342Y1448330D01*
X-247206Y1448898D01*
X-246495Y1449845D01*
X-246211Y1451171D01*
X-246495Y1452496D01*
X-247348Y1453633D01*
X-248626Y1454201D01*
X-250046D01*
X-250898Y1454579D01*
X-251609Y1455526D01*
X-251893Y1456852D01*
X-251466Y1458177D01*
X-250472Y1459124D01*
X-249336Y1459503D01*
X-248200Y1459124D01*
X-247206Y1458177D01*
X-246779Y1456852D01*
X-247064Y1455526D01*
X-247774Y1454579D01*
X-248626Y1454201D01*
X-250046D01*
X-251324Y1453633D01*
X-252177Y1452496D01*
X-252461Y1451171D01*
X-252177Y1449845D01*
X-251466Y1448898D01*
X-250330Y1448330D01*
X-249336Y1448141D01*
G01X-81259Y4212D02*
X-82047Y3950D01*
X-82637Y3293D01*
X-83031Y2506D01*
X-83326Y1456D01*
X-83425Y275D01*
X-83326Y-906D01*
X-83031Y-1956D01*
X-82637Y-2744D01*
X-82047Y-3400D01*
X-81259Y-3662D01*
X-80472Y-3400D01*
X-79881Y-2744D01*
X-79487Y-1956D01*
X-79192Y-906D01*
X-79093Y275D01*
X-79192Y1456D01*
X-79487Y2506D01*
X-79881Y3293D01*
X-80472Y3950D01*
X-81259Y4212D01*
G01X-73384Y-3924D02*
X-73581Y-3793D01*
Y-3531D01*
X-73384Y-3400D01*
X-73187Y-3531D01*
Y-3793D01*
X-73384Y-3924D01*
G01X-65509Y4212D02*
X-66297Y3950D01*
X-66887Y3293D01*
X-67281Y2506D01*
X-67576Y1456D01*
X-67675Y275D01*
X-67576Y-906D01*
X-67281Y-1956D01*
X-66887Y-2744D01*
X-66297Y-3400D01*
X-65509Y-3662D01*
X-64722Y-3400D01*
X-64131Y-2744D01*
X-63737Y-1956D01*
X-63442Y-906D01*
X-63343Y275D01*
X-63442Y1456D01*
X-63737Y2506D01*
X-64131Y3293D01*
X-64722Y3950D01*
X-65509Y4212D01*
G01X-57634D02*
X-58422Y3950D01*
X-59012Y3293D01*
X-59406Y2506D01*
X-59701Y1456D01*
X-59800Y275D01*
X-59701Y-906D01*
X-59406Y-1956D01*
X-59012Y-2744D01*
X-58422Y-3400D01*
X-57634Y-3662D01*
X-56847Y-3400D01*
X-56256Y-2744D01*
X-55862Y-1956D01*
X-55567Y-906D01*
X-55468Y275D01*
X-55567Y1456D01*
X-55862Y2506D01*
X-56256Y3293D01*
X-56847Y3950D01*
X-57634Y4212D01*
G01X-97122Y759281D02*
Y767155D01*
X-98303Y765580D01*
G01Y759281D02*
X-95941D01*
G01X-90920Y760199D02*
X-90231Y759543D01*
X-89444Y759281D01*
X-88656Y759543D01*
X-87967Y760331D01*
X-87475Y761512D01*
X-87278Y762693D01*
Y764137D01*
X-87475Y765318D01*
X-87967Y766368D01*
X-88558Y766893D01*
X-89247Y767155D01*
X-90035Y766893D01*
X-90625Y766368D01*
X-91019Y765580D01*
X-91216Y764530D01*
X-91019Y763612D01*
X-90527Y762693D01*
X-89936Y762168D01*
X-89247Y762037D01*
X-88460Y762299D01*
X-87869Y762955D01*
X-87278Y764137D01*
G01X-80191Y759281D02*
Y767155D01*
X-83833Y761512D01*
X-78911D01*
G01X-73497Y759019D02*
X-73694Y759150D01*
Y759412D01*
X-73497Y759543D01*
X-73300Y759412D01*
Y759150D01*
X-73497Y759019D01*
G01X-65622Y767155D02*
X-66410Y766893D01*
X-67000Y766236D01*
X-67394Y765449D01*
X-67689Y764399D01*
X-67788Y763218D01*
X-67689Y762037D01*
X-67394Y760987D01*
X-67000Y760199D01*
X-66410Y759543D01*
X-65622Y759281D01*
X-64835Y759543D01*
X-64244Y760199D01*
X-63850Y760987D01*
X-63555Y762037D01*
X-63456Y763218D01*
X-63555Y764399D01*
X-63850Y765449D01*
X-64244Y766236D01*
X-64835Y766893D01*
X-65622Y767155D01*
G01X-57747D02*
X-58535Y766893D01*
X-59125Y766236D01*
X-59519Y765449D01*
X-59814Y764399D01*
X-59913Y763218D01*
X-59814Y762037D01*
X-59519Y760987D01*
X-59125Y760199D01*
X-58535Y759543D01*
X-57747Y759281D01*
X-56960Y759543D01*
X-56369Y760199D01*
X-55975Y760987D01*
X-55680Y762037D01*
X-55581Y763218D01*
X-55680Y764399D01*
X-55975Y765449D01*
X-56369Y766236D01*
X-56960Y766893D01*
X-57747Y767155D01*
G01X-32082Y-728290D02*
X-31087Y-729236D01*
X-29951Y-729615D01*
X-28815Y-729236D01*
X-27821Y-728100D01*
X-27110Y-726396D01*
X-26826Y-724691D01*
Y-722609D01*
X-27110Y-720904D01*
X-27821Y-719389D01*
X-28673Y-718632D01*
X-29667Y-718253D01*
X-30803Y-718632D01*
X-31655Y-719389D01*
X-32224Y-720525D01*
X-32508Y-722041D01*
X-32224Y-723366D01*
X-31513Y-724691D01*
X-30661Y-725449D01*
X-29667Y-725638D01*
X-28531Y-725260D01*
X-27679Y-724313D01*
X-26826Y-722609D01*
G01X-3937Y811076D02*
X-3675Y810288D01*
X-3018Y809698D01*
X-2231Y809304D01*
X-1181Y809009D01*
X0Y808910D01*
X1181Y809009D01*
X2231Y809304D01*
X3019Y809698D01*
X3675Y810288D01*
X3937Y811076D01*
X3675Y811863D01*
X3019Y812454D01*
X2231Y812848D01*
X1181Y813143D01*
X0Y813242D01*
X-1181Y813143D01*
X-2231Y812848D01*
X-3018Y812454D01*
X-3675Y811863D01*
X-3937Y811076D01*
G01X4199Y818951D02*
X4068Y818754D01*
X3806D01*
X3675Y818951D01*
X3806Y819148D01*
X4068D01*
X4199Y818951D01*
G01X-3937Y826826D02*
X-3675Y826038D01*
X-3018Y825448D01*
X-2231Y825054D01*
X-1181Y824759D01*
X0Y824660D01*
X1181Y824759D01*
X2231Y825054D01*
X3019Y825448D01*
X3675Y826038D01*
X3937Y826826D01*
X3675Y827613D01*
X3019Y828204D01*
X2231Y828598D01*
X1181Y828893D01*
X0Y828992D01*
X-1181Y828893D01*
X-2231Y828598D01*
X-3018Y828204D01*
X-3675Y827613D01*
X-3937Y826826D01*
G01Y834701D02*
X-3675Y833913D01*
X-3018Y833323D01*
X-2231Y832929D01*
X-1181Y832634D01*
X0Y832535D01*
X1181Y832634D01*
X2231Y832929D01*
X3019Y833323D01*
X3675Y833913D01*
X3937Y834701D01*
X3675Y835488D01*
X3019Y836079D01*
X2231Y836473D01*
X1181Y836768D01*
X0Y836867D01*
X-1181Y836768D01*
X-2231Y836473D01*
X-3018Y836079D01*
X-3675Y835488D01*
X-3937Y834701D01*
G01X-32082Y1449466D02*
X-31087Y1448520D01*
X-29951Y1448141D01*
X-28815Y1448520D01*
X-27821Y1449656D01*
X-27110Y1451360D01*
X-26826Y1453065D01*
Y1455147D01*
X-27110Y1456852D01*
X-27821Y1458367D01*
X-28673Y1459124D01*
X-29667Y1459503D01*
X-30803Y1459124D01*
X-31655Y1458367D01*
X-32224Y1457231D01*
X-32508Y1455715D01*
X-32224Y1454390D01*
X-31513Y1453065D01*
X-30661Y1452307D01*
X-29667Y1452118D01*
X-28531Y1452496D01*
X-27679Y1453443D01*
X-26826Y1455147D01*
G01X187351Y-729615D02*
Y-718253D01*
X185647Y-720525D01*
G01Y-729615D02*
X189055D01*
G01X198714Y-718253D02*
X197578Y-718632D01*
X196726Y-719579D01*
X196157Y-720715D01*
X195731Y-722230D01*
X195589Y-723934D01*
X195731Y-725638D01*
X196157Y-727153D01*
X196726Y-728290D01*
X197578Y-729236D01*
X198714Y-729615D01*
X199850Y-729236D01*
X200702Y-728290D01*
X201271Y-727153D01*
X201697Y-725638D01*
X201839Y-723934D01*
X201697Y-722230D01*
X201271Y-720715D01*
X200702Y-719579D01*
X199850Y-718632D01*
X198714Y-718253D01*
G01X187351Y1448141D02*
Y1459503D01*
X185647Y1457231D01*
G01Y1448141D02*
X189055D01*
G01X198714Y1459503D02*
X197578Y1459124D01*
X196726Y1458177D01*
X196157Y1457041D01*
X195731Y1455526D01*
X195589Y1453822D01*
X195731Y1452118D01*
X196157Y1450603D01*
X196726Y1449466D01*
X197578Y1448520D01*
X198714Y1448141D01*
X199850Y1448520D01*
X200702Y1449466D01*
X201271Y1450603D01*
X201697Y1452118D01*
X201839Y1453822D01*
X201697Y1455526D01*
X201271Y1457041D01*
X200702Y1458177D01*
X199850Y1459124D01*
X198714Y1459503D01*
G01X228640Y-587433D02*
X227140Y-586433D01*
X225390Y-585766D01*
X223390D01*
X221140Y-586766D01*
X219390Y-588433D01*
X218140Y-590433D01*
X217140Y-593766D01*
X216890Y-596766D01*
X217390Y-599766D01*
X218140Y-601766D01*
X219640Y-603766D01*
X221390Y-605099D01*
X223140Y-605766D01*
X224890D01*
X226640Y-605099D01*
X228140Y-604100D01*
X229390Y-602767D01*
G01X239640Y-605766D02*
Y-592433D01*
G01Y-595099D02*
X240890Y-593766D01*
X242140Y-592766D01*
X243890Y-592433D01*
X245140Y-592766D01*
X246640Y-593766D01*
G01X259390Y-596766D02*
X267390D01*
X266640Y-594433D01*
X265390Y-593100D01*
X263640Y-592433D01*
X261890Y-592766D01*
X260390Y-593766D01*
X259390Y-596100D01*
X258890Y-598100D01*
Y-600099D01*
X259390Y-602100D01*
X260640Y-604100D01*
X262140Y-605433D01*
X263890Y-605766D01*
X265640Y-605099D01*
X267390Y-603100D01*
G01X287640Y-605766D02*
Y-592433D01*
G01Y-594766D02*
X286640Y-593433D01*
X285140Y-592766D01*
X283390Y-592433D01*
X281640Y-593100D01*
X280140Y-594433D01*
X279140Y-596433D01*
X278640Y-599100D01*
X279140Y-601766D01*
X280140Y-603766D01*
X281640Y-605099D01*
X283390Y-605766D01*
X285140Y-605433D01*
X286640Y-604433D01*
X287640Y-603100D01*
G01X303140Y-585766D02*
Y-605766D01*
G01X299640Y-592433D02*
X306640D01*
G01X319390Y-596766D02*
X327390D01*
X326640Y-594433D01*
X325390Y-593100D01*
X323640Y-592433D01*
X321890Y-592766D01*
X320390Y-593766D01*
X319390Y-596100D01*
X318890Y-598100D01*
Y-600099D01*
X319390Y-602100D01*
X320640Y-604100D01*
X322140Y-605433D01*
X323890Y-605766D01*
X325640Y-605099D01*
X327390Y-603100D01*
G01X347640Y-585766D02*
Y-605766D01*
G01Y-602767D02*
X346640Y-604433D01*
X345140Y-605433D01*
X343390Y-605766D01*
X341390Y-605099D01*
X339890Y-603433D01*
X338890Y-601433D01*
X338640Y-599100D01*
X338890Y-596766D01*
X339890Y-594766D01*
X341390Y-593100D01*
X343390Y-592433D01*
X345140Y-592766D01*
X346390Y-593433D01*
X347640Y-594766D01*
G01X214188Y-536858D02*
X220438Y-556858D01*
X226688Y-536858D01*
G01X236688Y-547858D02*
X244688D01*
X243938Y-545525D01*
X242688Y-544192D01*
X240938Y-543525D01*
X239188Y-543858D01*
X237688Y-544858D01*
X236688Y-547192D01*
X236188Y-549192D01*
Y-551191D01*
X236688Y-553192D01*
X237938Y-555192D01*
X239438Y-556525D01*
X241188Y-556858D01*
X242938Y-556191D01*
X244688Y-554192D01*
G01X256938Y-556858D02*
Y-543525D01*
G01Y-546191D02*
X258188Y-544858D01*
X259438Y-543858D01*
X261188Y-543525D01*
X262438Y-543858D01*
X263938Y-544858D01*
G01X276688Y-554525D02*
X277938Y-555858D01*
X279688Y-556858D01*
X281188D01*
X282688Y-556191D01*
X283688Y-555192D01*
X284188Y-553859D01*
X283938Y-551858D01*
X282938Y-550858D01*
X278438Y-548858D01*
X277438Y-546524D01*
X277938Y-544858D01*
X278938Y-543858D01*
X280438Y-543525D01*
X281938Y-543858D01*
X283438Y-544858D01*
G01X300438Y-543525D02*
Y-556858D01*
G01Y-538192D02*
X299938Y-537858D01*
Y-537191D01*
X300438Y-536858D01*
X300938Y-537191D01*
Y-537858D01*
X300438Y-538192D01*
G01X320438Y-556858D02*
X318938Y-556525D01*
X317438Y-555192D01*
X316438Y-552858D01*
X315938Y-550192D01*
X316438Y-547525D01*
X317438Y-545191D01*
X318938Y-543858D01*
X320438Y-543525D01*
X321938Y-543858D01*
X323438Y-545191D01*
X324438Y-547525D01*
X324688Y-550192D01*
X324438Y-552858D01*
X323438Y-555192D01*
X321938Y-556525D01*
X320438Y-556858D01*
G01X336188D02*
Y-543525D01*
G01Y-546858D02*
X337188Y-545191D01*
X338688Y-543858D01*
X340688Y-543525D01*
X342438Y-543858D01*
X343938Y-545191D01*
X344688Y-547525D01*
Y-556858D01*
G01X218140Y-512845D02*
Y-492845D01*
X224140D01*
X226140Y-493845D01*
X227640Y-496178D01*
X228140Y-498845D01*
X227640Y-501512D01*
X226390Y-503512D01*
X224140Y-504512D01*
X218140D01*
G01X248640Y-494512D02*
X247140Y-493512D01*
X245390Y-492845D01*
X243390D01*
X241140Y-493845D01*
X239390Y-495512D01*
X238140Y-497512D01*
X237140Y-500845D01*
X236890Y-503845D01*
X237390Y-506845D01*
X238140Y-508845D01*
X239640Y-510845D01*
X241390Y-512178D01*
X243140Y-512845D01*
X244890D01*
X246640Y-512178D01*
X248140Y-511179D01*
X249390Y-509846D01*
G01X265140Y-502178D02*
X266140Y-501178D01*
X266890Y-499512D01*
X267390Y-497178D01*
X266890Y-495178D01*
X265890Y-493845D01*
X264140Y-492845D01*
X257390D01*
Y-512845D01*
X265640D01*
X267390Y-511512D01*
X268390Y-509512D01*
X268890Y-507178D01*
X268390Y-504845D01*
X266890Y-502845D01*
X265140Y-502178D01*
X257390D01*
G01X297390Y-512845D02*
Y-492845D01*
X308890Y-512845D01*
Y-492845D01*
G01X323140Y-512845D02*
X321640Y-512512D01*
X320140Y-511179D01*
X319140Y-508845D01*
X318640Y-506179D01*
X319140Y-503512D01*
X320140Y-501178D01*
X321640Y-499845D01*
X323140Y-499512D01*
X324640Y-499845D01*
X326140Y-501178D01*
X327140Y-503512D01*
X327390Y-506179D01*
X327140Y-508845D01*
X326140Y-511179D01*
X324640Y-512512D01*
X323140Y-512845D01*
G01X343140Y-513512D02*
X342640Y-513178D01*
Y-512512D01*
X343140Y-512178D01*
X343640Y-512512D01*
Y-513178D01*
X343140Y-513512D01*
G01X226585Y-468632D02*
Y-443632D01*
X234775Y-464465D01*
X242965Y-443632D01*
Y-468632D01*
G01X259975D02*
X258085Y-468215D01*
X256195Y-466549D01*
X254935Y-463632D01*
X254305Y-460299D01*
X254935Y-456966D01*
X256195Y-454049D01*
X258085Y-452382D01*
X259975Y-451966D01*
X261865Y-452382D01*
X263755Y-454049D01*
X265015Y-456966D01*
X265330Y-460299D01*
X265015Y-463632D01*
X263755Y-466549D01*
X261865Y-468215D01*
X259975Y-468632D01*
G01X290845Y-443632D02*
Y-468632D01*
G01Y-464883D02*
X289585Y-466966D01*
X287695Y-468215D01*
X285490Y-468632D01*
X282970Y-467799D01*
X281080Y-465716D01*
X279820Y-463216D01*
X279505Y-460299D01*
X279820Y-457382D01*
X281080Y-454882D01*
X282970Y-452799D01*
X285490Y-451966D01*
X287695Y-452382D01*
X289270Y-453216D01*
X290845Y-454882D01*
G01X305650Y-457382D02*
X315730D01*
X314785Y-454465D01*
X313210Y-452799D01*
X311005Y-451966D01*
X308800Y-452382D01*
X306910Y-453632D01*
X305650Y-456549D01*
X305020Y-459049D01*
Y-461549D01*
X305650Y-464049D01*
X307225Y-466549D01*
X309115Y-468215D01*
X311320Y-468632D01*
X313525Y-467799D01*
X315730Y-465299D01*
G01X335575Y-468632D02*
Y-443632D01*
G01X306729Y594073D02*
Y578473D01*
G01X302244Y594073D02*
X311214D01*
G01X407778Y-729615D02*
Y-718253D01*
X406074Y-720525D01*
G01Y-729615D02*
X409482D01*
G01X419141D02*
Y-718253D01*
X417437Y-720525D01*
G01Y-729615D02*
X420845D01*
G01X396319Y-637301D02*
X400729Y-662301D01*
X405769Y-637301D01*
X410809Y-662301D01*
X415219Y-637301D01*
G01X430969Y-645635D02*
Y-662301D01*
G01Y-638968D02*
X430339Y-638551D01*
Y-637718D01*
X430969Y-637301D01*
X431599Y-637718D01*
Y-638551D01*
X430969Y-638968D01*
G01X451444Y-659385D02*
X453019Y-661051D01*
X455224Y-662301D01*
X457114D01*
X459004Y-661468D01*
X460264Y-660218D01*
X460894Y-658552D01*
X460579Y-656051D01*
X459319Y-654801D01*
X453649Y-652302D01*
X452389Y-649384D01*
X453019Y-647301D01*
X454279Y-646051D01*
X456169Y-645635D01*
X458059Y-646051D01*
X459949Y-647301D01*
G01X481369Y-637301D02*
Y-662301D01*
G01X476959Y-645635D02*
X485779D01*
G01X502159Y-662301D02*
Y-645635D01*
G01Y-648967D02*
X503734Y-647301D01*
X505309Y-646051D01*
X507514Y-645635D01*
X509089Y-646051D01*
X510979Y-647301D01*
G01X531769Y-662301D02*
X529879Y-661884D01*
X527989Y-660218D01*
X526729Y-657301D01*
X526099Y-653968D01*
X526729Y-650635D01*
X527989Y-647718D01*
X529879Y-646051D01*
X531769Y-645635D01*
X533659Y-646051D01*
X535549Y-647718D01*
X536809Y-650635D01*
X537124Y-653968D01*
X536809Y-657301D01*
X535549Y-660218D01*
X533659Y-661884D01*
X531769Y-662301D01*
G01X551614D02*
Y-645635D01*
G01Y-649801D02*
X552874Y-647718D01*
X554764Y-646051D01*
X557284Y-645635D01*
X559489Y-646051D01*
X561379Y-647718D01*
X562324Y-650635D01*
Y-662301D01*
G01X614299Y-639385D02*
X612409Y-638134D01*
X610204Y-637301D01*
X607684D01*
X604849Y-638551D01*
X602644Y-640634D01*
X601069Y-643135D01*
X599809Y-647301D01*
X599494Y-651051D01*
X600124Y-654801D01*
X601069Y-657301D01*
X602959Y-659802D01*
X605164Y-661468D01*
X607369Y-662301D01*
X609574D01*
X611779Y-661468D01*
X613669Y-660218D01*
X615244Y-658552D01*
G01X632569Y-662301D02*
X630679Y-661884D01*
X628789Y-660218D01*
X627529Y-657301D01*
X626899Y-653968D01*
X627529Y-650635D01*
X628789Y-647718D01*
X630679Y-646051D01*
X632569Y-645635D01*
X634459Y-646051D01*
X636349Y-647718D01*
X637609Y-650635D01*
X637924Y-653968D01*
X637609Y-657301D01*
X636349Y-660218D01*
X634459Y-661884D01*
X632569Y-662301D01*
G01X653359D02*
Y-645635D01*
G01Y-648967D02*
X654934Y-647301D01*
X656509Y-646051D01*
X658714Y-645635D01*
X660289Y-646051D01*
X662179Y-647301D01*
G01X677299Y-670634D02*
Y-645635D01*
G01Y-649384D02*
X678874Y-647301D01*
X680449Y-646051D01*
X682969Y-645635D01*
X685174Y-646051D01*
X687379Y-648134D01*
X688324Y-651051D01*
X688639Y-653968D01*
X688324Y-656885D01*
X687379Y-659802D01*
X685489Y-661468D01*
X682969Y-662301D01*
X680764Y-661884D01*
X678559Y-660635D01*
X677299Y-658968D01*
G01X708169Y-662301D02*
X706279Y-661884D01*
X704389Y-660218D01*
X703129Y-657301D01*
X702499Y-653968D01*
X703129Y-650635D01*
X704389Y-647718D01*
X706279Y-646051D01*
X708169Y-645635D01*
X710059Y-646051D01*
X711949Y-647718D01*
X713209Y-650635D01*
X713524Y-653968D01*
X713209Y-657301D01*
X711949Y-660218D01*
X710059Y-661884D01*
X708169Y-662301D01*
G01X728959D02*
Y-645635D01*
G01Y-648967D02*
X730534Y-647301D01*
X732109Y-646051D01*
X734314Y-645635D01*
X735889Y-646051D01*
X737779Y-647301D01*
G01X764239Y-662301D02*
Y-645635D01*
G01Y-648551D02*
X762979Y-646885D01*
X761089Y-646051D01*
X758884Y-645635D01*
X756679Y-646468D01*
X754789Y-648134D01*
X753529Y-650635D01*
X752899Y-653968D01*
X753529Y-657301D01*
X754789Y-659802D01*
X756679Y-661468D01*
X758884Y-662301D01*
X761089Y-661884D01*
X762979Y-660635D01*
X764239Y-658968D01*
G01X783769Y-637301D02*
Y-662301D01*
G01X779359Y-645635D02*
X788179D01*
G01X808969D02*
Y-662301D01*
G01Y-638968D02*
X808339Y-638551D01*
Y-637718D01*
X808969Y-637301D01*
X809599Y-637718D01*
Y-638551D01*
X808969Y-638968D01*
G01X834169Y-662301D02*
X832279Y-661884D01*
X830389Y-660218D01*
X829129Y-657301D01*
X828499Y-653968D01*
X829129Y-650635D01*
X830389Y-647718D01*
X832279Y-646051D01*
X834169Y-645635D01*
X836059Y-646051D01*
X837949Y-647718D01*
X839209Y-650635D01*
X839524Y-653968D01*
X839209Y-657301D01*
X837949Y-660218D01*
X836059Y-661884D01*
X834169Y-662301D01*
G01X854014D02*
Y-645635D01*
G01Y-649801D02*
X855274Y-647718D01*
X857164Y-646051D01*
X859684Y-645635D01*
X861889Y-646051D01*
X863779Y-647718D01*
X864724Y-650635D01*
Y-662301D01*
G01X419344Y-583791D02*
X425594Y-603791D01*
X431844Y-583791D01*
G01X445594Y-590458D02*
Y-603791D01*
G01Y-585125D02*
X445094Y-584791D01*
Y-584124D01*
X445594Y-583791D01*
X446094Y-584124D01*
Y-584791D01*
X445594Y-585125D01*
G01X465594Y-603791D02*
Y-583791D01*
G01X481844Y-594791D02*
X489844D01*
X489094Y-592458D01*
X487844Y-591125D01*
X486094Y-590458D01*
X484344Y-590791D01*
X482844Y-591791D01*
X481844Y-594125D01*
X481344Y-596125D01*
Y-598124D01*
X481844Y-600125D01*
X483094Y-602125D01*
X484594Y-603458D01*
X486344Y-603791D01*
X488094Y-603124D01*
X489844Y-601125D01*
G01X510094Y-603791D02*
Y-590458D01*
G01Y-592791D02*
X509094Y-591458D01*
X507594Y-590791D01*
X505844Y-590458D01*
X504094Y-591125D01*
X502594Y-592458D01*
X501594Y-594458D01*
X501094Y-597125D01*
X501594Y-599791D01*
X502594Y-601791D01*
X504094Y-603124D01*
X505844Y-603791D01*
X507594Y-603458D01*
X509094Y-602458D01*
X510094Y-601125D01*
G01X521344Y-603791D02*
Y-590458D01*
G01Y-593791D02*
X522344Y-592124D01*
X523844Y-590791D01*
X525844Y-590458D01*
X527594Y-590791D01*
X529094Y-592124D01*
X529844Y-594458D01*
Y-603791D01*
G01X560594Y-583791D02*
Y-603791D01*
X570594D01*
G01X585594Y-590458D02*
Y-603791D01*
G01Y-585125D02*
X585094Y-584791D01*
Y-584124D01*
X585594Y-583791D01*
X586094Y-584124D01*
Y-584791D01*
X585594Y-585125D01*
G01X431342Y-510870D02*
Y-490870D01*
X428342Y-494870D01*
G01Y-510870D02*
X434342D01*
G01X446592Y-502537D02*
X448342Y-500203D01*
X449842Y-498870D01*
X451842Y-498204D01*
X453592Y-498870D01*
X454842Y-500203D01*
X455842Y-502203D01*
X456092Y-504537D01*
X455842Y-506537D01*
X454842Y-508537D01*
X453342Y-510203D01*
X451592Y-510870D01*
X449592Y-510203D01*
X447842Y-508204D01*
X446842Y-505203D01*
X446592Y-501870D01*
X447092Y-497537D01*
X447842Y-495203D01*
X449092Y-492870D01*
X450842Y-491203D01*
X452592Y-490870D01*
X454342Y-491537D01*
X455592Y-493203D01*
G01X465842Y-506870D02*
X467342Y-509204D01*
X469342Y-510537D01*
X471592Y-510870D01*
X473592Y-510537D01*
X475592Y-508870D01*
X476842Y-506870D01*
X477092Y-504870D01*
X476592Y-502537D01*
X474842Y-500870D01*
X473092Y-500203D01*
X470842D01*
G01X473092D02*
X474592Y-499203D01*
X475842Y-497537D01*
X476342Y-495537D01*
X475842Y-493537D01*
X474592Y-491870D01*
X472342Y-490870D01*
X470092Y-491203D01*
X467842Y-492537D01*
G01X494342Y-510870D02*
Y-490870D01*
X485092Y-505203D01*
X497592D01*
G01X506592Y-494203D02*
X508092Y-492204D01*
X509842Y-491203D01*
X511842Y-490870D01*
X514342Y-491537D01*
X516092Y-493203D01*
X516592Y-495203D01*
X516342Y-497204D01*
X515342Y-498870D01*
X510342Y-502203D01*
X508092Y-504537D01*
X506592Y-507871D01*
X506092Y-510870D01*
X516592D01*
G01X402986Y-452299D02*
X404246Y-451050D01*
X405191Y-448967D01*
X405821Y-446049D01*
X405191Y-443550D01*
X403931Y-441883D01*
X401726Y-440633D01*
X393221D01*
Y-465633D01*
X403616D01*
X405821Y-463967D01*
X407081Y-461466D01*
X407711Y-458550D01*
X407081Y-455634D01*
X405191Y-453133D01*
X402986Y-452299D01*
X393221D01*
G01X421256Y-465633D02*
Y-448967D01*
G01Y-452299D02*
X422831Y-450633D01*
X424406Y-449383D01*
X426611Y-448967D01*
X428186Y-449383D01*
X430076Y-450633D01*
G01X444251Y-473133D02*
X446141Y-473966D01*
X448661Y-473133D01*
X450236Y-471467D01*
X451496Y-469383D01*
X453386Y-462717D01*
X457481Y-448967D01*
G01X447401D02*
X453386Y-462717D01*
G01X481106Y-451050D02*
X478901Y-449383D01*
X477011Y-448967D01*
X474491Y-449800D01*
X472601Y-451466D01*
X471341Y-454383D01*
X471026Y-457300D01*
X471341Y-460217D01*
X472601Y-462717D01*
X474491Y-464800D01*
X477011Y-465633D01*
X479216Y-464800D01*
X481106Y-463134D01*
G01X496541Y-454383D02*
X506621D01*
X505676Y-451466D01*
X504101Y-449800D01*
X501896Y-448967D01*
X499691Y-449383D01*
X497801Y-450633D01*
X496541Y-453550D01*
X495911Y-456050D01*
Y-458550D01*
X496541Y-461050D01*
X498116Y-463550D01*
X500006Y-465216D01*
X502211Y-465633D01*
X504416Y-464800D01*
X506621Y-462300D01*
G01X558596Y-442717D02*
X556706Y-441466D01*
X554501Y-440633D01*
X551981D01*
X549146Y-441883D01*
X546941Y-443966D01*
X545366Y-446467D01*
X544106Y-450633D01*
X543791Y-454383D01*
X544421Y-458133D01*
X545366Y-460633D01*
X547256Y-463134D01*
X549461Y-464800D01*
X551666Y-465633D01*
X553871D01*
X556076Y-464800D01*
X557966Y-463550D01*
X559541Y-461884D01*
G01X582536Y-465633D02*
Y-448967D01*
G01Y-451883D02*
X581276Y-450217D01*
X579386Y-449383D01*
X577181Y-448967D01*
X574976Y-449800D01*
X573086Y-451466D01*
X571826Y-453967D01*
X571196Y-457300D01*
X571826Y-460633D01*
X573086Y-463134D01*
X574976Y-464800D01*
X577181Y-465633D01*
X579386Y-465216D01*
X581276Y-463967D01*
X582536Y-462300D01*
G01X596711Y-465633D02*
Y-448967D01*
G01Y-453133D02*
X597971Y-451050D01*
X599861Y-449383D01*
X602381Y-448967D01*
X604586Y-449383D01*
X606476Y-451050D01*
X607421Y-453967D01*
Y-465633D01*
G01X620651Y-473133D02*
X622541Y-473966D01*
X625061Y-473133D01*
X626636Y-471467D01*
X627896Y-469383D01*
X629786Y-462717D01*
X633881Y-448967D01*
G01X623801D02*
X629786Y-462717D01*
G01X652466Y-465633D02*
X650576Y-465216D01*
X648686Y-463550D01*
X647426Y-460633D01*
X646796Y-457300D01*
X647426Y-453967D01*
X648686Y-451050D01*
X650576Y-449383D01*
X652466Y-448967D01*
X654356Y-449383D01*
X656246Y-451050D01*
X657506Y-453967D01*
X657821Y-457300D01*
X657506Y-460633D01*
X656246Y-463550D01*
X654356Y-465216D01*
X652466Y-465633D01*
G01X672311D02*
Y-448967D01*
G01Y-453133D02*
X673571Y-451050D01*
X675461Y-449383D01*
X677981Y-448967D01*
X680186Y-449383D01*
X682076Y-451050D01*
X683021Y-453967D01*
Y-465633D01*
G01X724286Y-440633D02*
X731845D01*
G01X728066D02*
Y-465633D01*
G01X724286D02*
X731845D01*
G01X753266D02*
X750746Y-465216D01*
X748541Y-463550D01*
X746651Y-461050D01*
X745391Y-458133D01*
X744761Y-454800D01*
Y-451466D01*
X745391Y-448133D01*
X746651Y-445216D01*
X748541Y-442717D01*
X750746Y-441050D01*
X753266Y-440633D01*
X755786Y-441050D01*
X757991Y-442717D01*
X759881Y-445216D01*
X761141Y-448133D01*
X761771Y-451466D01*
Y-454800D01*
X761141Y-458133D01*
X759881Y-461050D01*
X757991Y-463550D01*
X755786Y-465216D01*
X753266Y-465633D01*
G01X770276D02*
Y-440633D01*
X778466Y-461466D01*
X786656Y-440633D01*
Y-465633D01*
G01X827291Y-473966D02*
X824141Y-469800D01*
X822566Y-465633D01*
Y-448967D01*
X824141Y-444800D01*
X827291Y-440633D01*
G01X845876Y-465633D02*
Y-440633D01*
X854066Y-461466D01*
X862256Y-440633D01*
Y-465633D01*
G01X879266Y-466466D02*
X878636Y-466050D01*
Y-465216D01*
X879266Y-464800D01*
X879896Y-465216D01*
Y-466050D01*
X879266Y-466466D01*
G01X898481Y-444800D02*
X900371Y-442300D01*
X902576Y-441050D01*
X905096Y-440633D01*
X908246Y-441466D01*
X910451Y-443550D01*
X911081Y-446049D01*
X910766Y-448550D01*
X909506Y-450633D01*
X903206Y-454800D01*
X900371Y-457716D01*
X898481Y-461884D01*
X897851Y-465633D01*
X911081D01*
G01X954866D02*
X952976Y-465216D01*
X951086Y-463550D01*
X949826Y-460633D01*
X949196Y-457300D01*
X949826Y-453967D01*
X951086Y-451050D01*
X952976Y-449383D01*
X954866Y-448967D01*
X956756Y-449383D01*
X958646Y-451050D01*
X959906Y-453967D01*
X960221Y-457300D01*
X959906Y-460633D01*
X958646Y-463550D01*
X956756Y-465216D01*
X954866Y-465633D01*
G01X974711D02*
Y-448967D01*
G01Y-453133D02*
X975971Y-451050D01*
X977861Y-449383D01*
X980381Y-448967D01*
X982586Y-449383D01*
X984476Y-451050D01*
X985421Y-453967D01*
Y-465633D01*
G01X1005266D02*
Y-440633D01*
G01X1023851Y-473133D02*
X1025741Y-473966D01*
X1028261Y-473133D01*
X1029836Y-471467D01*
X1031096Y-469383D01*
X1032986Y-462717D01*
X1037081Y-448967D01*
G01X1027001D02*
X1032986Y-462717D01*
G01X1057241Y-473966D02*
X1060391Y-469800D01*
X1061966Y-465633D01*
Y-448967D01*
X1060391Y-444800D01*
X1057241Y-440633D01*
G01X407778Y1448141D02*
Y1459503D01*
X406074Y1457231D01*
G01Y1448141D02*
X409482D01*
G01X419141D02*
Y1459503D01*
X417437Y1457231D01*
G01Y1448141D02*
X420845D01*
G01X440122Y-559086D02*
X442122Y-560752D01*
X444372Y-561752D01*
X446372D01*
X448372Y-560752D01*
X449872Y-559086D01*
X450622Y-556752D01*
X450122Y-554419D01*
X448872Y-552419D01*
X446622Y-551085D01*
X443622Y-550419D01*
X441872Y-549086D01*
X441122Y-546752D01*
X441622Y-544419D01*
X442872Y-542752D01*
X444622Y-541752D01*
X446372D01*
X448122Y-542419D01*
X449622Y-544085D01*
G01X459872Y-561752D02*
Y-541752D01*
X464872D01*
X466872Y-542752D01*
X468372Y-544085D01*
X469622Y-546085D01*
X470622Y-548419D01*
X470872Y-551752D01*
X470622Y-555086D01*
X469622Y-557419D01*
X468372Y-559419D01*
X466872Y-560752D01*
X464872Y-561752D01*
X459872D01*
G01X625553Y-729615D02*
Y-718253D01*
X623849Y-720525D01*
G01Y-729615D02*
X627257D01*
G01X634217Y-720147D02*
X635070Y-719011D01*
X636064Y-718442D01*
X637200Y-718253D01*
X638620Y-718632D01*
X639615Y-719579D01*
X639899Y-720715D01*
X639757Y-721851D01*
X639188Y-722798D01*
X636348Y-724691D01*
X635070Y-726017D01*
X634217Y-727911D01*
X633933Y-729615D01*
X639899D01*
G01X625553Y1448141D02*
Y1459503D01*
X623849Y1457231D01*
G01Y1448141D02*
X627257D01*
G01X634217Y1457609D02*
X635070Y1458745D01*
X636064Y1459314D01*
X637200Y1459503D01*
X638620Y1459124D01*
X639615Y1458177D01*
X639899Y1457041D01*
X639757Y1455905D01*
X639188Y1454958D01*
X636348Y1453065D01*
X635070Y1451739D01*
X634217Y1449845D01*
X633933Y1448141D01*
X639899D01*
G01X780878Y-605766D02*
Y-585766D01*
X785878D01*
X787878Y-586766D01*
X789378Y-588099D01*
X790628Y-590099D01*
X791628Y-592433D01*
X791878Y-595766D01*
X791628Y-599100D01*
X790628Y-601433D01*
X789378Y-603433D01*
X787878Y-604766D01*
X785878Y-605766D01*
X780878D01*
G01X810878D02*
Y-592433D01*
G01Y-594766D02*
X809878Y-593433D01*
X808378Y-592766D01*
X806628Y-592433D01*
X804878Y-593100D01*
X803378Y-594433D01*
X802378Y-596433D01*
X801878Y-599100D01*
X802378Y-601766D01*
X803378Y-603766D01*
X804878Y-605099D01*
X806628Y-605766D01*
X808378Y-605433D01*
X809878Y-604433D01*
X810878Y-603100D01*
G01X826378Y-585766D02*
Y-605766D01*
G01X822878Y-592433D02*
X829878D01*
G01X842628Y-596766D02*
X850628D01*
X849878Y-594433D01*
X848628Y-593100D01*
X846878Y-592433D01*
X845128Y-592766D01*
X843628Y-593766D01*
X842628Y-596100D01*
X842128Y-598100D01*
Y-600099D01*
X842628Y-602100D01*
X843878Y-604100D01*
X845378Y-605433D01*
X847128Y-605766D01*
X848878Y-605099D01*
X850628Y-603100D01*
G01X735840Y-538688D02*
Y-558688D01*
G01X730090Y-538688D02*
X741590D01*
G01X751590Y-558688D02*
Y-538688D01*
G01Y-548354D02*
X752840Y-546688D01*
X754090Y-545688D01*
X756090Y-545355D01*
X757590Y-545688D01*
X759340Y-547021D01*
X760090Y-549022D01*
Y-558688D01*
G01X775840Y-545355D02*
Y-558688D01*
G01Y-540022D02*
X775340Y-539688D01*
Y-539021D01*
X775840Y-538688D01*
X776340Y-539021D01*
Y-539688D01*
X775840Y-540022D01*
G01X799840Y-547021D02*
X798090Y-545688D01*
X796590Y-545355D01*
X794590Y-546022D01*
X793090Y-547355D01*
X792090Y-549688D01*
X791840Y-552022D01*
X792090Y-554355D01*
X793090Y-556355D01*
X794590Y-558021D01*
X796590Y-558688D01*
X798340Y-558021D01*
X799840Y-556688D01*
G01X811590Y-558688D02*
Y-538688D01*
G01X819590Y-545355D02*
X811590Y-553021D01*
G01X814840Y-550021D02*
X820090Y-558688D01*
G01X831590D02*
Y-545355D01*
G01Y-548688D02*
X832590Y-547021D01*
X834090Y-545688D01*
X836090Y-545355D01*
X837840Y-545688D01*
X839340Y-547021D01*
X840090Y-549355D01*
Y-558688D01*
G01X852090Y-549688D02*
X860090D01*
X859340Y-547355D01*
X858090Y-546022D01*
X856340Y-545355D01*
X854590Y-545688D01*
X853090Y-546688D01*
X852090Y-549022D01*
X851590Y-551022D01*
Y-553021D01*
X852090Y-555022D01*
X853340Y-557022D01*
X854840Y-558355D01*
X856590Y-558688D01*
X858340Y-558021D01*
X860090Y-556022D01*
G01X872090Y-556355D02*
X873340Y-557688D01*
X875090Y-558688D01*
X876590D01*
X878090Y-558021D01*
X879090Y-557022D01*
X879590Y-555689D01*
X879340Y-553688D01*
X878340Y-552688D01*
X873840Y-550688D01*
X872840Y-548354D01*
X873340Y-546688D01*
X874340Y-545688D01*
X875840Y-545355D01*
X877340Y-545688D01*
X878840Y-546688D01*
G01X892090Y-556355D02*
X893340Y-557688D01*
X895090Y-558688D01*
X896590D01*
X898090Y-558021D01*
X899090Y-557022D01*
X899590Y-555689D01*
X899340Y-553688D01*
X898340Y-552688D01*
X893840Y-550688D01*
X892840Y-548354D01*
X893340Y-546688D01*
X894340Y-545688D01*
X895840Y-545355D01*
X897340Y-545688D01*
X898840Y-546688D01*
G01X845223Y-729615D02*
Y-718253D01*
X843519Y-720525D01*
G01Y-729615D02*
X846927D01*
G01X853461Y-727343D02*
X854313Y-728668D01*
X855450Y-729426D01*
X856728Y-729615D01*
X857864Y-729426D01*
X859001Y-728479D01*
X859711Y-727343D01*
X859853Y-726206D01*
X859569Y-724881D01*
X858574Y-723934D01*
X857580Y-723555D01*
X856302D01*
G01X857580D02*
X858432Y-722987D01*
X859143Y-722041D01*
X859427Y-720904D01*
X859143Y-719768D01*
X858432Y-718821D01*
X857154Y-718253D01*
X855876Y-718442D01*
X854598Y-719200D01*
G01X845223Y1448141D02*
Y1459503D01*
X843519Y1457231D01*
G01Y1448141D02*
X846927D01*
G01X853461Y1450413D02*
X854313Y1449088D01*
X855450Y1448330D01*
X856728Y1448141D01*
X857864Y1448330D01*
X859001Y1449277D01*
X859711Y1450413D01*
X859853Y1451550D01*
X859569Y1452875D01*
X858574Y1453822D01*
X857580Y1454201D01*
X856302D01*
G01X857580D02*
X858432Y1454769D01*
X859143Y1455715D01*
X859427Y1456852D01*
X859143Y1457988D01*
X858432Y1458935D01*
X857154Y1459503D01*
X855876Y1459314D01*
X854598Y1458556D01*
G01X929361Y-589077D02*
X930861Y-587078D01*
X932611Y-586077D01*
X934611Y-585744D01*
X937111Y-586411D01*
X938861Y-588077D01*
X939361Y-590077D01*
X939111Y-592078D01*
X938111Y-593744D01*
X933111Y-597077D01*
X930861Y-599411D01*
X929361Y-602745D01*
X928861Y-605744D01*
X939361D01*
G01X954111Y-585744D02*
X952111Y-586411D01*
X950611Y-588077D01*
X949611Y-590077D01*
X948861Y-592744D01*
X948611Y-595744D01*
X948861Y-598744D01*
X949611Y-601411D01*
X950611Y-603411D01*
X952111Y-605077D01*
X954111Y-605744D01*
X956111Y-605077D01*
X957611Y-603411D01*
X958611Y-601411D01*
X959361Y-598744D01*
X959611Y-595744D01*
X959361Y-592744D01*
X958611Y-590077D01*
X957611Y-588077D01*
X956111Y-586411D01*
X954111Y-585744D01*
G01X974111Y-605744D02*
Y-585744D01*
X971111Y-589744D01*
G01Y-605744D02*
X977111D01*
G01X993611D02*
X994111Y-601411D01*
X994861Y-597744D01*
X995861Y-594411D01*
X997111Y-590744D01*
X999111Y-585744D01*
X989111D01*
G01X1010861Y-599078D02*
X1017361D01*
G01X1034111Y-585744D02*
X1032111Y-586411D01*
X1030611Y-588077D01*
X1029611Y-590077D01*
X1028861Y-592744D01*
X1028611Y-595744D01*
X1028861Y-598744D01*
X1029611Y-601411D01*
X1030611Y-603411D01*
X1032111Y-605077D01*
X1034111Y-605744D01*
X1036111Y-605077D01*
X1037611Y-603411D01*
X1038611Y-601411D01*
X1039361Y-598744D01*
X1039611Y-595744D01*
X1039361Y-592744D01*
X1038611Y-590077D01*
X1037611Y-588077D01*
X1036111Y-586411D01*
X1034111Y-585744D01*
G01X1048611Y-601744D02*
X1050111Y-604078D01*
X1052111Y-605411D01*
X1054361Y-605744D01*
X1056361Y-605411D01*
X1058361Y-603744D01*
X1059611Y-601744D01*
X1059861Y-599744D01*
X1059361Y-597411D01*
X1057611Y-595744D01*
X1055861Y-595077D01*
X1053611D01*
G01X1055861D02*
X1057361Y-594077D01*
X1058611Y-592411D01*
X1059111Y-590411D01*
X1058611Y-588411D01*
X1057361Y-586744D01*
X1055111Y-585744D01*
X1052861Y-586077D01*
X1050611Y-587411D01*
G01X1070861Y-599078D02*
X1077361D01*
G01X1094111Y-585744D02*
X1092111Y-586411D01*
X1090611Y-588077D01*
X1089611Y-590077D01*
X1088861Y-592744D01*
X1088611Y-595744D01*
X1088861Y-598744D01*
X1089611Y-601411D01*
X1090611Y-603411D01*
X1092111Y-605077D01*
X1094111Y-605744D01*
X1096111Y-605077D01*
X1097611Y-603411D01*
X1098611Y-601411D01*
X1099361Y-598744D01*
X1099611Y-595744D01*
X1099361Y-592744D01*
X1098611Y-590077D01*
X1097611Y-588077D01*
X1096111Y-586411D01*
X1094111Y-585744D01*
G01X1109361Y-589077D02*
X1110861Y-587078D01*
X1112611Y-586077D01*
X1114611Y-585744D01*
X1117111Y-586411D01*
X1118861Y-588077D01*
X1119361Y-590077D01*
X1119111Y-592078D01*
X1118111Y-593744D01*
X1113111Y-597077D01*
X1110861Y-599411D01*
X1109361Y-602745D01*
X1108861Y-605744D01*
X1119361D01*
G01X922572Y809206D02*
X921785Y809796D01*
X921391Y810485D01*
X921260Y811273D01*
X921522Y812257D01*
X922179Y812946D01*
X922966Y813143D01*
X923754Y813045D01*
X924410Y812651D01*
X925722Y810682D01*
X926641Y809796D01*
X927953Y809206D01*
X929134Y809009D01*
Y813143D01*
G01X927559Y816785D02*
X928478Y817376D01*
X929003Y818163D01*
X929134Y819050D01*
X929003Y819837D01*
X928347Y820624D01*
X927559Y821117D01*
X926772Y821215D01*
X925853Y821018D01*
X925197Y820329D01*
X924934Y819640D01*
Y818754D01*
G01Y819640D02*
X924541Y820231D01*
X923885Y820723D01*
X923097Y820920D01*
X922310Y820723D01*
X921654Y820231D01*
X921260Y819345D01*
X921391Y818459D01*
X921916Y817573D01*
G01X927953Y824660D02*
X928609Y825251D01*
X929003Y825940D01*
X929134Y826826D01*
X928872Y827712D01*
X928347Y828401D01*
X927428Y828893D01*
X926378Y828992D01*
X925328Y828795D01*
X924672Y828302D01*
X924147Y827613D01*
X924016Y826925D01*
X924147Y826235D01*
X924672Y825350D01*
X921260Y825645D01*
Y828302D01*
G01X929396Y834701D02*
X929265Y834504D01*
X929003D01*
X928872Y834701D01*
X929003Y834898D01*
X929265D01*
X929396Y834701D01*
G01X921260Y842576D02*
X921522Y841788D01*
X922179Y841198D01*
X922966Y840804D01*
X924016Y840509D01*
X925197Y840410D01*
X926378Y840509D01*
X927428Y840804D01*
X928216Y841198D01*
X928872Y841788D01*
X929134Y842576D01*
X928872Y843363D01*
X928216Y843954D01*
X927428Y844348D01*
X926378Y844643D01*
X925197Y844742D01*
X924016Y844643D01*
X922966Y844348D01*
X922179Y843954D01*
X921522Y843363D01*
X921260Y842576D01*
G01Y850451D02*
X921522Y849663D01*
X922179Y849073D01*
X922966Y848679D01*
X924016Y848384D01*
X925197Y848285D01*
X926378Y848384D01*
X927428Y848679D01*
X928216Y849073D01*
X928872Y849663D01*
X929134Y850451D01*
X928872Y851238D01*
X928216Y851829D01*
X927428Y852223D01*
X926378Y852518D01*
X925197Y852617D01*
X924016Y852518D01*
X922966Y852223D01*
X922179Y851829D01*
X921522Y851238D01*
X921260Y850451D01*
G01X961690Y-555083D02*
Y-535083D01*
X958690Y-539083D01*
G01Y-555083D02*
X964690D01*
G01X981690Y-555750D02*
X981190Y-555416D01*
Y-554750D01*
X981690Y-554416D01*
X982190Y-554750D01*
Y-555416D01*
X981690Y-555750D01*
G01X996940Y-546750D02*
X998690Y-544416D01*
X1000190Y-543083D01*
X1002190Y-542417D01*
X1003940Y-543083D01*
X1005190Y-544416D01*
X1006190Y-546416D01*
X1006440Y-548750D01*
X1006190Y-550750D01*
X1005190Y-552750D01*
X1003690Y-554416D01*
X1001940Y-555083D01*
X999940Y-554416D01*
X998190Y-552417D01*
X997190Y-549416D01*
X996940Y-546083D01*
X997440Y-541750D01*
X998190Y-539416D01*
X999440Y-537083D01*
X1001190Y-535416D01*
X1002940Y-535083D01*
X1004690Y-535750D01*
X1005940Y-537416D01*
G01X1014190Y-555083D02*
Y-541750D01*
G01Y-545417D02*
X1014940Y-543750D01*
X1016190Y-542417D01*
X1017940Y-541750D01*
X1019690Y-542417D01*
X1020940Y-543750D01*
X1021690Y-545417D01*
Y-555083D01*
G01Y-545417D02*
X1022440Y-543750D01*
X1023690Y-542417D01*
X1025440Y-541750D01*
X1027190Y-542417D01*
X1028440Y-543750D01*
X1029190Y-545750D01*
Y-555083D01*
G01X1034190D02*
Y-541750D01*
G01Y-545417D02*
X1034940Y-543750D01*
X1036190Y-542417D01*
X1037940Y-541750D01*
X1039690Y-542417D01*
X1040940Y-543750D01*
X1041690Y-545417D01*
Y-555083D01*
G01Y-545417D02*
X1042440Y-543750D01*
X1043690Y-542417D01*
X1045440Y-541750D01*
X1047190Y-542417D01*
X1048440Y-543750D01*
X1049190Y-545750D01*
Y-555083D01*
G01X1064892Y-729615D02*
Y-718253D01*
X1063188Y-720525D01*
G01Y-729615D02*
X1066596D01*
G01X1077959D02*
Y-718253D01*
X1072704Y-726396D01*
X1079806D01*
G01X1064892Y1448141D02*
Y1459503D01*
X1063188Y1457231D01*
G01Y1448141D02*
X1066596D01*
G01X1077959D02*
Y1459503D01*
X1072704Y1451360D01*
X1079806D01*
G01X1190633Y-609933D02*
X1191344Y-611069D01*
X1192196Y-611826D01*
X1193190Y-612205D01*
X1194326Y-611826D01*
X1195178Y-611069D01*
X1196031Y-609933D01*
X1196315Y-608418D01*
Y-600843D01*
G01X1191770Y-384961D02*
X1195178D01*
G01X1193474D02*
Y-396323D01*
G01X1191770D02*
X1195178D01*
G01X1190491Y-180631D02*
Y-169269D01*
G01X1196457D02*
Y-180631D01*
G01Y-174950D02*
X1190491D01*
G01X1194326Y40932D02*
X1197167D01*
Y37523D01*
X1196315Y36387D01*
X1195320Y35630D01*
X1193900Y35251D01*
X1192480Y35630D01*
X1191486Y36387D01*
X1190633Y37523D01*
X1190065Y38849D01*
X1189781Y40364D01*
Y41689D01*
X1190065Y42825D01*
X1190633Y44151D01*
X1191486Y45287D01*
X1192338Y46045D01*
X1193474Y46613D01*
X1194468D01*
X1195604Y46234D01*
X1196457Y45477D01*
G01X1190396Y251323D02*
Y262685D01*
X1195794D01*
G01X1193805Y257193D02*
X1190396D01*
G01X1196315Y467394D02*
X1190633D01*
Y478756D01*
X1196315D01*
G01X1194042Y473264D02*
X1190633D01*
G01X1190349Y683086D02*
Y694448D01*
X1193190D01*
X1194326Y693880D01*
X1195178Y693122D01*
X1195889Y691986D01*
X1196457Y690660D01*
X1196599Y688767D01*
X1196457Y686873D01*
X1195889Y685548D01*
X1195178Y684411D01*
X1194326Y683654D01*
X1193190Y683086D01*
X1190349D01*
G01X1196599Y909573D02*
X1195746Y910141D01*
X1194752Y910520D01*
X1193616D01*
X1192338Y909952D01*
X1191344Y909005D01*
X1190633Y907869D01*
X1190065Y905975D01*
X1189923Y904271D01*
X1190207Y902567D01*
X1190633Y901430D01*
X1191486Y900294D01*
X1192480Y899537D01*
X1193474Y899158D01*
X1194468D01*
X1195462Y899537D01*
X1196315Y900105D01*
X1197025Y900862D01*
G01X1194610Y1120910D02*
X1195178Y1121478D01*
X1195604Y1122424D01*
X1195889Y1123750D01*
X1195604Y1124886D01*
X1195036Y1125644D01*
X1194042Y1126212D01*
X1190207D01*
Y1114850D01*
X1194894D01*
X1195889Y1115607D01*
X1196457Y1116744D01*
X1196741Y1118069D01*
X1196457Y1119395D01*
X1195604Y1120531D01*
X1194610Y1120910D01*
X1190207D01*
G01X1189923Y1330732D02*
X1193474Y1342094D01*
X1197025Y1330732D01*
G01X1195746Y1334709D02*
X1191201D01*
G01X-1921948Y-733402D02*
Y1463291D01*
G01X1202658Y-733402D02*
X-1921948D01*
G01X-1903011Y-714465D02*
Y1444354D01*
G01X1183721Y-714465D02*
X-1903011D01*
G01X-1921948Y-498583D02*
X-1903011D01*
G01X-1921948Y-282701D02*
X-1903011D01*
G01X-1921948D02*
X-1903011D01*
G01X-1921948Y-66819D02*
X-1903011D01*
G01X-1921948D02*
X-1903011D01*
G01X-1921948Y149063D02*
X-1903011D01*
G01X-1921948D02*
X-1903011D01*
G01X-1921948Y364945D02*
X-1903011D01*
G01X-1921948D02*
X-1903011D01*
G01X-1921948D02*
X-1903011D01*
G01X-1921948Y580826D02*
X-1903011D01*
G01X-1921948D02*
X-1903011D01*
G01X-1921948Y796708D02*
X-1903011D01*
G01X-1921948D02*
X-1903011D01*
G01X-1921948Y1012590D02*
X-1903011D01*
G01X-1921948D02*
X-1903011D01*
G01X-1921948Y1228472D02*
X-1903011D01*
G01X-1921948Y1463291D02*
X1202658D01*
G01X-1903011Y1444354D02*
X1183721D01*
G01X-1471836Y1094840D02*
X-1804723D01*
G01X-1677660Y-714465D02*
Y-733402D01*
G01X-1627329Y1283043D02*
X-1726357D01*
G01X-1677660Y1463291D02*
Y1444354D01*
G01X-1600032Y-529335D02*
X-1635072D01*
G01X-1600032D02*
Y-564375D01*
G01Y-525398D02*
G03X-1596095Y-529335I3937J0D01*
G01X-1600032Y-525398D02*
G03X-1596095Y-529335I3937J0D01*
G01D02*
X-1580347D01*
G01X-1596095D02*
X-1483773D01*
G01X-1600032Y194145D02*
Y-525398D01*
G01Y194145D02*
Y-525398D01*
G01X-1592566Y36329D02*
X-1591053Y36576D01*
G01X-1587775Y30404D02*
X-1589288Y30157D01*
G01X-1592566Y37563D02*
X-1591305Y37810D01*
G01X-1587775Y29169D02*
X-1589036Y28922D01*
G01X-1584245Y55586D02*
X-1596095D01*
G01X-1589792Y54105D02*
X-1584245D01*
G01X-1596095D02*
X-1591305D01*
G01Y47192D02*
X-1596095D01*
G01X-1584245D02*
X-1589792D01*
G01X-1596095Y45710D02*
X-1584245D01*
G01X-1591305Y43735D02*
X-1592313D01*
G01X-1588279D02*
X-1589288D01*
G01Y39785D02*
X-1588279D01*
G01X-1592313D02*
X-1591305D01*
G01Y37810D02*
X-1589036D01*
G01X-1591053Y36576D02*
X-1589288D01*
G01Y30157D02*
X-1591053D01*
G01X-1589036Y28922D02*
X-1591305D01*
G01X-1584245Y26947D02*
X-1592313D01*
G01X-1590548Y25713D02*
X-1584245D01*
G01X-1592313D02*
X-1591557D01*
G01X-1584245Y22997D02*
X-1590296D01*
G01Y21763D02*
X-1584245D01*
G01Y19047D02*
X-1590296D01*
G01Y17813D02*
X-1584245D01*
G01Y15838D02*
X-1592313D01*
G01X-1590548Y14603D02*
X-1584245D01*
G01X-1592313D02*
X-1591557D01*
G01X-1584245Y11887D02*
X-1590296D01*
G01Y10653D02*
X-1584245D01*
G01Y7937D02*
X-1590296D01*
G01Y6703D02*
X-1584245D01*
G01X-1589036Y37810D02*
X-1587775Y37563D01*
G01X-1591305Y28922D02*
X-1592566Y29169D01*
G01X-1589288Y36576D02*
X-1587775Y36329D01*
G01X-1591053Y30157D02*
X-1592566Y30404D01*
G01X-1587775Y37563D02*
X-1587019Y37316D01*
G01X-1592566Y29169D02*
X-1593322Y29416D01*
G01X-1587019Y37316D02*
X-1586010Y36823D01*
G01X-1591557Y18306D02*
X-1590296Y17813D01*
G01X-1591557Y7197D02*
X-1590296Y6703D01*
G01X-1593322Y29416D02*
X-1594330Y29910D01*
G01X-1590296Y22997D02*
X-1590801Y23244D01*
G01X-1590296Y19047D02*
X-1590801Y19294D01*
G01X-1590296Y11887D02*
X-1590801Y12134D01*
G01X-1590296Y7937D02*
X-1590801Y8184D01*
G01X-1587775Y36329D02*
X-1586262Y35341D01*
G01X-1592566Y30404D02*
X-1594078Y31391D01*
G01X-1586010Y36823D02*
X-1585254Y36082D01*
G01X-1594330Y29910D02*
X-1595087Y30651D01*
G01X-1590801Y23244D02*
X-1591053Y23491D01*
G01X-1592061Y22750D02*
X-1591305Y22010D01*
G01X-1590801Y19294D02*
X-1591053Y19541D01*
G01X-1592061Y18800D02*
X-1591557Y18306D01*
G01X-1590801Y12134D02*
X-1591053Y12381D01*
G01X-1592061Y11641D02*
X-1591305Y10900D01*
G01X-1590801Y8184D02*
X-1591053Y8431D01*
G01X-1592061Y7690D02*
X-1591557Y7197D01*
G01X-1586262Y35341D02*
X-1585758Y34601D01*
G01X-1585254Y36082D02*
X-1584497Y34848D01*
G01X-1595087Y30651D02*
X-1595843Y31885D01*
G01X-1594078Y31391D02*
X-1594583Y32132D01*
G01X-1587019Y29416D02*
X-1587775Y29169D01*
G01X-1591053Y23491D02*
X-1591305Y23985D01*
G01X-1591053Y19541D02*
X-1591305Y20035D01*
G01X-1591053Y12381D02*
X-1591305Y12875D01*
G01X-1591053Y8431D02*
X-1591305Y8925D01*
G01X-1593322Y37316D02*
X-1592566Y37563D01*
G01X-1590801Y10406D02*
X-1590296Y10653D01*
G01X-1590801Y21516D02*
X-1590296Y21763D01*
G01X-1592313Y23491D02*
X-1592061Y22750D01*
G01X-1592313Y19541D02*
X-1592061Y18800D01*
G01X-1592313Y12381D02*
X-1592061Y11641D01*
G01X-1592313Y8431D02*
X-1592061Y7690D01*
G01X-1586010Y29910D02*
X-1587019Y29416D01*
G01X-1594330Y36823D02*
X-1593322Y37316D01*
G01X-1584497Y34848D02*
X-1584245Y33366D01*
G01X-1595843Y31885D02*
X-1596095Y33366D01*
G01X-1585758Y34601D02*
X-1585506Y33366D01*
G01X-1594583Y32132D02*
X-1594835Y33366D01*
G01X-1586262Y31391D02*
X-1587775Y30404D01*
G01X-1594078Y35341D02*
X-1592566Y36329D01*
G01X-1591053Y10159D02*
X-1590801Y10406D01*
G01X-1591305Y10900D02*
X-1592061Y10159D01*
G01X-1591053Y14109D02*
X-1590548Y14603D01*
G01X-1591557D02*
X-1592061Y14109D01*
G01X-1591053Y21269D02*
X-1590801Y21516D01*
G01X-1591305Y22010D02*
X-1592061Y21269D01*
G01X-1585254Y30651D02*
X-1586010Y29910D01*
G01X-1591053Y25219D02*
X-1590548Y25713D01*
G01X-1591557D02*
X-1592061Y25219D01*
G01X-1595087Y36082D02*
X-1594330Y36823D01*
G01X-1585758Y32132D02*
X-1586262Y31391D01*
G01X-1584245Y33366D02*
X-1584497Y31885D01*
G01X-1584245Y54105D02*
Y55586D01*
G01Y45710D02*
Y47192D01*
G01Y25713D02*
Y26947D01*
G01Y21763D02*
Y22997D01*
G01Y17813D02*
Y19047D01*
G01Y14603D02*
Y15838D01*
G01Y10653D02*
Y11887D01*
G01Y6703D02*
Y7937D01*
G01X-1588279Y39785D02*
Y43735D01*
G01X-1589288D02*
Y39785D01*
G01X-1589792Y47192D02*
Y54105D01*
G01X-1591305Y39785D02*
Y43735D01*
G01Y23985D02*
Y24479D01*
G01Y20035D02*
Y20775D01*
G01Y12875D02*
Y13369D01*
G01Y8925D02*
Y9666D01*
G01Y54105D02*
Y47192D01*
G01X-1592313Y9419D02*
Y8431D01*
G01Y13369D02*
Y12381D01*
G01Y15838D02*
Y14603D01*
G01Y20528D02*
Y19541D01*
G01Y24479D02*
Y23491D01*
G01Y26947D02*
Y25713D01*
G01Y43735D02*
Y39785D01*
G01X-1596095Y47192D02*
Y45710D01*
G01Y55586D02*
Y54105D01*
G01X-1594583Y34601D02*
X-1594078Y35341D01*
G01X-1584497Y31885D02*
X-1585254Y30651D01*
G01X-1595843Y34848D02*
X-1595087Y36082D01*
G01X-1591305Y9666D02*
X-1591053Y10159D01*
G01X-1591305Y20775D02*
X-1591053Y21269D01*
G01X-1592061Y10159D02*
X-1592313Y9419D01*
G01X-1591305Y13369D02*
X-1591053Y14109D01*
G01X-1592061D02*
X-1592313Y13369D01*
G01X-1592061Y21269D02*
X-1592313Y20528D01*
G01X-1591305Y24479D02*
X-1591053Y25219D01*
G01X-1592061D02*
X-1592313Y24479D01*
G01X-1585506Y33366D02*
X-1585758Y32132D01*
G01X-1594835Y33366D02*
X-1594583Y34601D01*
G01X-1596095Y33366D02*
X-1595843Y34848D01*
G01X-1599617Y195906D02*
G03X-1600032Y194145I3522J-1759D01*
G01X-1599617Y195906D02*
G03X-1600032Y194145I3522J-1759D01*
G01X-1581436Y232268D02*
X-1599617Y195905D01*
G01X-1581436Y232268D02*
X-1599617Y195905D01*
G01X-1598153Y473369D02*
Y432110D01*
G01Y473369D02*
X-1612042D01*
G01X-1598153Y477306D02*
G03X-1594216Y473369I3937J0D01*
G01X-1598153Y477306D02*
G03X-1594216Y473369I3937J0D01*
G01D02*
X-1481893D01*
G01X-1594216D02*
X-1481893D01*
G01X-1598153Y1196849D02*
Y477306D01*
G01Y1196849D02*
Y477306D01*
G01X-1531223Y571795D02*
X-1612042D01*
G01X-1519019Y711755D02*
X-1612042D01*
G01X-1518625Y886952D02*
X-1612042D01*
G01X-1589706Y907055D02*
X-1591389Y906780D01*
G01X-1589986Y908428D02*
X-1591389Y908154D01*
G01X-1587461Y898537D02*
X-1586058Y898812D01*
G01X-1587741Y899911D02*
X-1586058Y900185D01*
G01X-1587461Y918870D02*
X-1582129D01*
G01X-1595318D02*
X-1589144D01*
G01X-1582129Y917221D02*
X-1595318D01*
G01X-1587461Y915023D02*
X-1586338D01*
G01X-1590828D02*
X-1589706D01*
G01Y910627D02*
X-1590828D01*
G01X-1586338D02*
X-1587461D01*
G01Y908428D02*
X-1589986D01*
G01X-1587741Y907055D02*
X-1589706D01*
G01Y899911D02*
X-1587741D01*
G01X-1589986Y898537D02*
X-1587461D01*
G01X-1595318Y896339D02*
X-1586338D01*
G01X-1588303Y894965D02*
X-1595318D01*
G01X-1586338D02*
X-1587180D01*
G01X-1595318Y891942D02*
X-1588583D01*
G01Y890568D02*
X-1595318D01*
G01Y887546D02*
X-1588583D01*
G01Y886172D02*
X-1595318D01*
G01Y883974D02*
X-1586338D01*
G01X-1588303Y882600D02*
X-1595318D01*
G01X-1586338D02*
X-1587180D01*
G01X-1595318Y879578D02*
X-1588583D01*
G01Y878204D02*
X-1595318D01*
G01Y875181D02*
X-1588583D01*
G01Y873807D02*
X-1595318D01*
G01X-1586058Y908154D02*
X-1587461Y908428D01*
G01X-1586058Y906780D02*
X-1587741Y907055D01*
G01X-1591389Y900185D02*
X-1589706Y899911D01*
G01X-1591389Y898812D02*
X-1589986Y898537D01*
G01X-1585216Y907879D02*
X-1586058Y908154D01*
G01X-1592231Y899086D02*
X-1591389Y898812D01*
G01X-1584093Y907329D02*
X-1585216Y907879D01*
G01X-1593354Y899636D02*
X-1592231Y899086D01*
G01X-1588022Y890294D02*
X-1588583Y890568D01*
G01X-1588022Y877929D02*
X-1588583Y878204D01*
G01X-1586058Y898812D02*
X-1585216Y899086D01*
G01X-1591389Y908154D02*
X-1592231Y907879D01*
G01X-1587180Y874357D02*
X-1588583Y873807D01*
G01X-1584374Y905681D02*
X-1586058Y906780D01*
G01X-1593073Y901284D02*
X-1591389Y900185D01*
G01X-1587180Y886722D02*
X-1588583Y886172D01*
G01Y875181D02*
X-1588022Y875456D01*
G01X-1588583Y879578D02*
X-1588022Y879852D01*
G01X-1588583Y887546D02*
X-1588022Y887821D01*
G01X-1588583Y891942D02*
X-1588022Y892217D01*
G01X-1583251Y906505D02*
X-1584093Y907329D01*
G01X-1585216Y899086D02*
X-1584093Y899636D01*
G01X-1592231Y907879D02*
X-1593354Y907329D01*
G01X-1587180Y894965D02*
X-1586619Y894415D01*
G01X-1587741D02*
X-1588303Y894965D01*
G01X-1594196Y900460D02*
X-1593354Y899636D01*
G01X-1587461Y890843D02*
X-1586619Y890019D01*
G01X-1587741D02*
X-1588022Y890294D01*
G01X-1587180Y882600D02*
X-1586619Y882051D01*
G01X-1587741D02*
X-1588303Y882600D01*
G01X-1587461Y878479D02*
X-1586619Y877654D01*
G01X-1587741D02*
X-1588022Y877929D01*
G01X-1586058Y900185D02*
X-1584374Y901284D01*
G01X-1591389Y906780D02*
X-1593073Y905681D01*
G01X-1582410Y905131D02*
X-1583251Y906505D01*
G01X-1583813Y904856D02*
X-1584374Y905681D01*
G01X-1593634Y902109D02*
X-1593073Y901284D01*
G01X-1586619Y874906D02*
X-1587180Y874357D01*
G01X-1588022Y875456D02*
X-1587741Y875731D01*
G01X-1586619Y879303D02*
X-1587461Y878479D01*
G01X-1588022Y879852D02*
X-1587741Y880127D01*
G01X-1586619Y887271D02*
X-1587180Y886722D01*
G01X-1588022Y887821D02*
X-1587741Y888095D01*
G01X-1586619Y891667D02*
X-1587461Y890843D01*
G01X-1588022Y892217D02*
X-1587741Y892492D01*
G01X-1584093Y899636D02*
X-1583251Y900460D01*
G01X-1587461Y889469D02*
X-1587741Y890019D01*
G01X-1587461Y877105D02*
X-1587741Y877654D01*
G01X-1595037Y901834D02*
X-1594196Y900460D01*
G01X-1593354Y907329D02*
X-1594196Y906505D01*
G01X-1583532Y903483D02*
X-1583813Y904856D01*
G01X-1586619Y894415D02*
X-1586338Y893591D01*
G01X-1587461D02*
X-1587741Y894415D01*
G01X-1586619Y890019D02*
X-1586338Y889195D01*
G01X-1586619Y882051D02*
X-1586338Y881226D01*
G01X-1587461D02*
X-1587741Y882051D01*
G01X-1586619Y877654D02*
X-1586338Y876830D01*
G01X-1584374Y901284D02*
X-1583813Y902109D01*
G01X-1593073Y905681D02*
X-1593634Y904856D01*
G01X-1583251Y900460D02*
X-1582410Y901834D01*
G01X-1594196Y906505D02*
X-1595037Y905131D01*
G01X-1587741Y875731D02*
X-1587461Y876280D01*
G01X-1587741Y880127D02*
X-1587461Y880677D01*
G01X-1587741Y888095D02*
X-1587461Y888645D01*
G01X-1587741Y892492D02*
X-1587461Y893041D01*
G01X-1586338Y875731D02*
X-1586619Y874906D01*
G01X-1586338Y880127D02*
X-1586619Y879303D01*
G01X-1595318Y903483D02*
X-1595037Y901834D01*
G01X-1593915Y903483D02*
X-1593634Y902109D01*
G01X-1586338Y888095D02*
X-1586619Y887271D01*
G01X-1586338Y892492D02*
X-1586619Y891667D01*
G01X-1583813Y902109D02*
X-1583532Y903483D01*
G01X-1593634Y904856D02*
X-1593915Y903483D01*
G01X-1595037Y905131D02*
X-1595318Y903483D01*
G01X-1586338Y876830D02*
Y875731D01*
G01Y881226D02*
Y880127D01*
G01Y883974D02*
Y882600D01*
G01Y889195D02*
Y888095D01*
G01Y893591D02*
Y892492D01*
G01Y896339D02*
Y894965D01*
G01Y915023D02*
Y910627D01*
G01X-1587461D02*
Y915023D01*
G01Y893041D02*
Y893591D01*
G01Y888645D02*
Y889469D01*
G01Y880677D02*
Y881226D01*
G01Y876280D02*
Y877105D01*
G01Y926563D02*
Y918870D01*
G01X-1589144D02*
Y926563D01*
G01X-1589706Y915023D02*
Y910627D01*
G01X-1590828D02*
Y915023D01*
G01X-1595318Y917221D02*
Y918870D01*
G01Y894965D02*
Y896339D01*
G01Y890568D02*
Y891942D01*
G01Y886172D02*
Y887546D01*
G01Y882600D02*
Y883974D01*
G01Y878204D02*
Y879578D01*
G01Y873807D02*
Y875181D01*
G01X-1538113Y945810D02*
X-1612042D01*
G01X-1595318Y928212D02*
X-1582129D01*
G01X-1589144Y926563D02*
X-1595318D01*
G01X-1582129D02*
X-1587461D01*
G01X-1595318D02*
Y928212D01*
G01X-1597737Y1198610D02*
G03X-1598153Y1196849I3521J-1761D01*
G01X-1597737Y1198610D02*
G03X-1598153Y1196849I3521J-1761D01*
G01X-1579556Y1234973D02*
X-1597737Y1198610D01*
G01X-1579556Y1234973D02*
X-1597737Y1198610D01*
G01X-1624179Y1283043D02*
X-1627329D01*
G01X-1554723Y1218870D02*
X-1624179Y1283043D01*
G01X-1552877Y1213527D02*
X-1612042D01*
G01X-1579971Y1237149D02*
X-1612042D01*
G01X-1580347Y233602D02*
Y-529335D01*
G01X-1510465Y-430910D02*
G03I-18701J0D01*
G01X-1522277D02*
G03I-6889J0D01*
G01X-1516962Y-284257D02*
G03Y-297643I0J-6693D01*
G01X-1491568Y-290950D02*
G03I-18701J0D01*
G01X-1503576Y-297643D02*
X-1516962D01*
G01X-1503576Y-284257D02*
X-1516962D01*
G01X-1503379Y-115753D02*
G03I-6496J0D01*
G01X-1491174D02*
G03I-18701J0D01*
G01X-1522277Y-56894D02*
G03I-6889J0D01*
G01X-1510465D02*
G03I-18701J0D01*
G01X-1542946Y210822D02*
G03I-7874J0D01*
G01X-1532119D02*
G03I-18701J0D01*
G01X-1542592Y227616D02*
X-1505849Y302613D01*
G01X-1580347Y233602D02*
G03X-1581435Y232268I2433J-3095D01*
G01X-1577914Y234444D02*
G03X-1581435Y232268I0J-3937D01*
G01X-1213883Y234444D02*
X-1577914D01*
G01X-1527286Y567858D02*
Y432110D01*
G01X-1548094Y488682D02*
X-1548125Y488921D01*
G01X-1547996Y488446D02*
X-1548094Y488682D01*
G01X-1547826Y488230D02*
X-1547996Y488446D01*
G01X-1547614Y488072D02*
X-1547826Y488230D01*
G01X-1547380Y487975D02*
X-1547614Y488072D01*
G01X-1547097Y487936D02*
X-1547380Y487975D01*
G01X-1548115Y488785D02*
X-1548125Y488921D01*
G01X-1548085Y488652D02*
X-1548115Y488785D01*
G01X-1548036Y488523D02*
X-1548085Y488652D01*
G01X-1547968Y488401D02*
X-1548036Y488523D01*
G01X-1547881Y488288D02*
X-1547968Y488401D01*
G01X-1547778Y488186D02*
X-1547881Y488288D01*
G01X-1547660Y488099D02*
X-1547778Y488186D01*
G01X-1547530Y488029D02*
X-1547660Y488099D01*
G01X-1547390Y487978D02*
X-1547530Y488029D01*
G01X-1547245Y487947D02*
X-1547390Y487978D01*
G01X-1547097Y487936D02*
X-1547245Y487947D01*
G01X-1553702Y488785D02*
X-1553692Y488921D01*
G01X-1553732Y488652D02*
X-1553702Y488785D01*
G01X-1553781Y488523D02*
X-1553732Y488652D01*
G01X-1553849Y488401D02*
X-1553781Y488523D01*
G01X-1553936Y488288D02*
X-1553849Y488401D01*
G01X-1554039Y488186D02*
X-1553936Y488288D01*
G01X-1554157Y488099D02*
X-1554039Y488186D01*
G01X-1554287Y488029D02*
X-1554157Y488099D01*
G01X-1554427Y487978D02*
X-1554287Y488029D01*
G01X-1554573Y487947D02*
X-1554427Y487978D01*
G01X-1554721Y487936D02*
X-1554573Y487947D01*
G01X-1553724Y488682D02*
X-1553692Y488921D01*
G01X-1553822Y488446D02*
X-1553724Y488682D01*
G01X-1553991Y488230D02*
X-1553822Y488446D01*
G01X-1554203Y488072D02*
X-1553991Y488230D01*
G01X-1554437Y487975D02*
X-1554203Y488072D01*
G01X-1554721Y487936D02*
X-1554437Y487975D01*
G01X-1546220Y488431D02*
X-1546120Y488671D01*
G01X-1546379Y488227D02*
X-1546220Y488431D01*
G01X-1546591Y488068D02*
X-1546379Y488227D01*
G01X-1547956Y492661D02*
G03X-1549924Y494629I-1968J0D01*
G01X-1551893D02*
G03X-1553861Y492661I0J-1968D01*
G01X-1563901Y489905D02*
G03X-1563507Y489511I394J0D01*
G01X-1538310D02*
G03X-1537916Y489905I0J394D01*
G01X-1557084Y475877D02*
G03X-1556101Y474944I983J51D01*
G01X-1545716D02*
G03X-1544733Y475877I0J984D01*
G01X-1559291Y486362D02*
G03X-1557921Y487595I0J1378D01*
G01X-1560983D02*
G03X-1559612Y486362I1370J145D01*
G01X-1542362D02*
G03X-1540992Y487595I0J1378D01*
G01X-1544054D02*
G03X-1542683Y486362I1370J145D01*
G01X-1565475Y489905D02*
G03X-1563507Y487936I1969J0D01*
G01X-1538310D02*
G03X-1536342Y489905I0J1968D01*
G01X-1538434Y489590D02*
X-1538276Y489650D01*
G01X-1539819Y489590D02*
X-1539662Y489650D01*
G01X-1538591Y491387D02*
X-1538749Y491327D01*
G01X-1543662Y489590D02*
X-1543504Y489650D01*
G01X-1539977Y491387D02*
X-1540134Y491327D01*
G01X-1545047Y489590D02*
X-1544890Y489650D01*
G01X-1538591Y492405D02*
X-1538749Y492345D01*
G01X-1546433Y489590D02*
X-1546276Y489650D01*
G01X-1539977Y492405D02*
X-1540134Y492345D01*
G01X-1543819Y491387D02*
X-1543977Y491327D01*
G01X-1545205Y491387D02*
X-1545362Y491327D01*
G01X-1543819Y492405D02*
X-1543977Y492345D01*
G01X-1546622Y491387D02*
X-1546780Y491327D01*
G01X-1545205Y492405D02*
X-1545362Y492345D01*
G01X-1556291Y489889D02*
X-1556133Y489949D01*
G01X-1557677Y489590D02*
X-1557519Y489650D01*
G01X-1561267Y489590D02*
X-1561110Y489650D01*
G01X-1557834Y491387D02*
X-1557992Y491327D01*
G01X-1556448Y492105D02*
X-1556606Y492045D01*
G01X-1564007Y489650D02*
X-1564164Y489590D01*
G01X-1557834Y492405D02*
X-1557992Y492345D01*
G01X-1546834Y487970D02*
X-1546589Y488069D01*
G01X-1543359Y489511D02*
X-1543935Y489260D01*
G01X-1544207Y489140D02*
X-1544200Y489144D01*
G01X-1544206Y489141D02*
X-1543679Y489372D01*
G01X-1560612Y489371D02*
X-1560288Y489511D01*
G01D02*
X-1560864Y489260D01*
G01X-1560628Y489364D02*
X-1561135Y489141D01*
G01X-1544206D02*
X-1544202Y489143D01*
G01X-1561135Y489141D02*
X-1561131Y489143D01*
G01X-1546307Y489949D02*
X-1546433Y489889D01*
G01X-1546748Y491027D02*
X-1546622Y491087D01*
G01X-1556133Y489650D02*
X-1556259Y489590D01*
G01X-1561141Y490009D02*
X-1561267Y489949D01*
G01X-1564038Y490009D02*
X-1564164Y489949D01*
G01X-1561456Y492405D02*
X-1561582Y492345D01*
G01X-1563858Y489726D02*
X-1565261Y489012D01*
G01X-1541056Y492829D02*
X-1540844Y492937D01*
G01X-1543172D02*
X-1543384Y492829D01*
G01X-1549044Y492937D02*
X-1549256Y492829D01*
G01X-1559572Y492937D02*
X-1559784Y492829D01*
G01X-1538402Y489889D02*
X-1538308Y489949D01*
G01X-1539788Y489889D02*
X-1539693Y489949D01*
G01X-1538623Y491087D02*
X-1538717Y491027D01*
G01X-1540008Y491087D02*
X-1540103Y491027D01*
G01X-1538717Y492045D02*
X-1538623Y492105D01*
G01X-1540103Y492045D02*
X-1540008Y492105D01*
G01X-1543630Y489889D02*
X-1543536Y489949D01*
G01X-1545016Y489889D02*
X-1544921Y489949D01*
G01X-1543851Y491087D02*
X-1543945Y491027D01*
G01X-1545236Y491087D02*
X-1545331Y491027D01*
G01X-1543945Y492045D02*
X-1543851Y492105D01*
G01X-1545331Y492045D02*
X-1545236Y492105D01*
G01X-1548291Y491207D02*
X-1548197Y491267D01*
G01X-1557645Y489889D02*
X-1557551Y489949D01*
G01X-1556322Y491147D02*
X-1556133Y491267D01*
G01X-1557866Y491087D02*
X-1557960Y491027D01*
G01Y492045D02*
X-1557866Y492105D01*
G01X-1561550Y491986D02*
X-1561456Y492045D01*
G01X-1540950Y493261D02*
X-1541109Y493153D01*
G01X-1543437D02*
X-1543278Y493261D01*
G01X-1549150D02*
X-1549309Y493153D01*
G01X-1559678Y493261D02*
X-1559837Y493153D01*
G01X-1556292Y494126D02*
X-1556504Y493964D01*
G01X-1548165Y490967D02*
X-1548039Y491087D01*
G01X-1556007Y489770D02*
X-1556133Y489650D01*
G01Y489949D02*
X-1556070Y490009D01*
G01X-1556763Y492225D02*
X-1556637Y492345D01*
G01X-1561110Y489650D02*
X-1560984Y489770D01*
G01X-1563881D02*
X-1564007Y489650D01*
G01X-1561582Y492345D02*
X-1561708Y492225D01*
G01X-1540844Y492937D02*
X-1540633Y493153D01*
G01X-1542960D02*
X-1543172Y492937D01*
G01X-1548833Y493153D02*
X-1549044Y492937D01*
G01X-1559361Y493153D02*
X-1559572Y492937D01*
G01X-1538276Y489650D02*
X-1538119Y489829D01*
G01X-1539662Y489650D02*
X-1539504Y489829D01*
G01X-1538749Y492345D02*
X-1538906Y492165D01*
G01X-1540134Y492345D02*
X-1540292Y492165D01*
G01X-1543504Y489650D02*
X-1543347Y489829D01*
G01X-1544890Y489650D02*
X-1544733Y489829D01*
G01X-1546276Y489650D02*
X-1546118Y489829D01*
G01X-1543977Y492345D02*
X-1544134Y492165D01*
G01X-1545362Y492345D02*
X-1545520Y492165D01*
G01X-1546780Y491327D02*
X-1546937Y491147D01*
G01X-1557519Y489650D02*
X-1557362Y489829D01*
G01X-1557992Y492345D02*
X-1558149Y492165D01*
G01X-1538308Y489949D02*
X-1538213Y490069D01*
G01X-1538717Y491027D02*
X-1538812Y490908D01*
G01X-1539693Y489949D02*
X-1539599Y490069D01*
G01X-1538749Y491327D02*
X-1538938Y491087D01*
G01X-1538812Y491926D02*
X-1538717Y492045D01*
G01X-1540103Y491027D02*
X-1540197Y490908D01*
G01X-1540134Y491327D02*
X-1540323Y491087D01*
G01X-1540197Y491926D02*
X-1540103Y492045D01*
G01X-1543536Y489949D02*
X-1543441Y490069D01*
G01X-1543945Y491027D02*
X-1544040Y490908D01*
G01X-1544921Y489949D02*
X-1544827Y490069D01*
G01X-1543977Y491327D02*
X-1544166Y491087D01*
G01X-1544040Y491926D02*
X-1543945Y492045D01*
G01X-1545331Y491027D02*
X-1545425Y490908D01*
G01X-1546213Y490069D02*
X-1546307Y489949D01*
G01X-1545362Y491327D02*
X-1545551Y491087D01*
G01X-1545425Y491926D02*
X-1545331Y492045D01*
G01X-1555913Y489889D02*
X-1556007Y489770D01*
G01X-1557551Y489949D02*
X-1557456Y490069D01*
G01X-1556606Y492045D02*
X-1556700Y491926D01*
G01X-1557960Y491027D02*
X-1558055Y490908D01*
G01X-1557992Y491327D02*
X-1558181Y491087D01*
G01X-1558055Y491926D02*
X-1557960Y492045D01*
G01X-1561047Y490129D02*
X-1561141Y490009D01*
G01X-1561645Y491866D02*
X-1561550Y491986D01*
G01X-1563944Y490129D02*
X-1564038Y490009D01*
G01X-1546874Y490848D02*
X-1546748Y491027D01*
G01X-1555944Y491207D02*
X-1556070Y491027D01*
G01X-1540844Y493423D02*
X-1540950Y493261D01*
G01X-1549044Y493423D02*
X-1549150Y493261D01*
G01X-1559572Y493423D02*
X-1559678Y493261D01*
G01X-1538812Y490908D02*
X-1538875Y490788D01*
G01X-1540197Y490908D02*
X-1540260Y490788D01*
G01X-1544040Y490908D02*
X-1544103Y490788D01*
G01X-1545425Y490908D02*
X-1545488Y490788D01*
G01X-1548197Y491267D02*
X-1548134Y491387D01*
G01X-1555157Y490967D02*
X-1555378Y490548D01*
G01X-1556070Y490009D02*
X-1556007Y490129D01*
G01X-1556133Y491267D02*
X-1556070Y491387D01*
G01X-1556889Y491986D02*
X-1556763Y492225D01*
G01X-1558055Y490908D02*
X-1558118Y490788D01*
G01X-1560984Y489770D02*
X-1560858Y490009D01*
G01X-1561708Y492225D02*
X-1561834Y491986D01*
G01X-1563755Y490009D02*
X-1563881Y489770D01*
G01X-1555378Y491027D02*
X-1554685Y492405D01*
G01X-1554433D02*
X-1555000Y491267D01*
G01X-1540633Y493153D02*
X-1540527Y493369D01*
G01X-1548727D02*
X-1548833Y493153D01*
G01X-1559255Y493369D02*
X-1559361Y493153D01*
G01X-1559784Y492829D02*
X-1560048Y492775D01*
G01X-1549256Y492829D02*
X-1549520Y492775D01*
G01X-1543384Y492829D02*
X-1543648Y492775D01*
G01X-1541320D02*
X-1541056Y492829D01*
G01X-1559837Y493153D02*
X-1560048Y493099D01*
G01X-1549309Y493153D02*
X-1549520Y493099D01*
G01X-1543648D02*
X-1543437Y493153D01*
G01X-1541109D02*
X-1541320Y493099D01*
G01X-1556637Y492345D02*
X-1556417Y492405D01*
G01X-1538119Y489829D02*
X-1538024Y490069D01*
G01X-1539504Y489829D02*
X-1539410Y490069D01*
G01X-1538906Y492165D02*
X-1539001Y491926D01*
G01X-1540292Y492165D02*
X-1540386Y491926D01*
G01X-1543347Y489829D02*
X-1543252Y490069D01*
G01X-1544733Y489829D02*
X-1544638Y490069D01*
G01X-1544134Y492165D02*
X-1544229Y491926D01*
G01X-1546118Y489829D02*
X-1546024Y490069D01*
G01X-1545520Y492165D02*
X-1545614Y491926D01*
G01X-1548039Y491087D02*
X-1547945Y491327D01*
G01X-1557362Y489829D02*
X-1557267Y490069D01*
G01X-1558149Y492165D02*
X-1558244Y491926D01*
G01X-1538213Y490069D02*
X-1538150Y490249D01*
G01X-1538875Y491746D02*
X-1538812Y491926D01*
G01X-1539599Y490069D02*
X-1539536Y490249D01*
G01X-1540260Y491746D02*
X-1540197Y491926D01*
G01X-1543441Y490069D02*
X-1543378Y490249D01*
G01X-1544103Y491746D02*
X-1544040Y491926D01*
G01X-1544827Y490069D02*
X-1544764Y490249D01*
G01X-1545488Y491746D02*
X-1545425Y491926D01*
G01X-1546150Y490249D02*
X-1546213Y490069D01*
G01X-1546831Y487971D02*
X-1547097Y487936D01*
G01X-1555850Y490069D02*
X-1555913Y489889D01*
G01X-1555881Y491387D02*
X-1555944Y491207D01*
G01X-1556700Y491926D02*
X-1556763Y491746D01*
G01X-1557456Y490069D02*
X-1557393Y490249D01*
G01X-1558118Y491746D02*
X-1558055Y491926D01*
G01X-1560984Y490309D02*
X-1561047Y490129D01*
G01X-1563881Y490309D02*
X-1563944Y490129D01*
G01X-1543278Y493261D02*
X-1543225Y493423D01*
G01X-1549331Y491686D02*
X-1549740Y490189D01*
G01X-1549835Y490309D02*
X-1549425Y491806D01*
G01X-1556007Y490129D02*
X-1555976Y490249D01*
G01X-1556070Y491387D02*
X-1556007Y491626D01*
G01X-1540733Y492105D02*
X-1541363Y489590D01*
G01X-1541552D02*
X-1540922Y492105D01*
G01X-1560858Y490009D02*
X-1560795Y490249D01*
G01X-1563692D02*
X-1563755Y490009D01*
G01X-1548991Y493639D02*
X-1549044Y493423D01*
G01X-1559519Y493639D02*
X-1559572Y493423D01*
G01X-1537520Y489530D02*
X-1537583Y489231D01*
G01X-1537709D02*
X-1537646Y489530D01*
G01X-1538024Y490069D02*
X-1537961Y490368D01*
G01X-1539001Y491926D02*
X-1539064Y491626D01*
G01X-1539410Y490069D02*
X-1539347Y490368D01*
G01X-1540386Y491926D02*
X-1540449Y491626D01*
G01X-1542181Y492105D02*
X-1542119Y492405D01*
G01X-1542748Y489530D02*
X-1542811Y489231D01*
G01X-1542244Y492405D02*
X-1542307Y492105D01*
G01X-1542937Y489231D02*
X-1542874Y489530D01*
G01X-1543252Y490069D02*
X-1543189Y490368D01*
G01X-1544229Y491926D02*
X-1544292Y491626D01*
G01X-1544638Y490069D02*
X-1544575Y490368D01*
G01X-1545614Y491926D02*
X-1545677Y491626D01*
G01X-1546024Y490069D02*
X-1545961Y490368D01*
G01X-1547410Y492105D02*
X-1547347Y492405D01*
G01X-1547473D02*
X-1547536Y492105D01*
G01X-1557267Y490069D02*
X-1557204Y490368D01*
G01X-1558244Y491926D02*
X-1558307Y491626D01*
G01X-1542908Y493423D02*
X-1542960Y493153D01*
G01X-1548674Y493639D02*
X-1548727Y493369D01*
G01X-1559202Y493639D02*
X-1559255Y493369D01*
G01X-1552858Y489949D02*
X-1552417Y492405D01*
G01X-1552228D02*
X-1552732Y489590D01*
G01X-1560543D02*
X-1560039Y492405D01*
G01X-1538150Y490249D02*
X-1538119Y490428D01*
G01X-1538875Y490788D02*
X-1538906Y490608D01*
G01Y491566D02*
X-1538875Y491746D01*
G01X-1539536Y490249D02*
X-1539504Y490428D01*
G01X-1540260Y490788D02*
X-1540292Y490608D01*
G01Y491566D02*
X-1540260Y491746D01*
G01X-1543378Y490249D02*
X-1543347Y490428D01*
G01X-1544103Y490788D02*
X-1544134Y490608D01*
G01Y491566D02*
X-1544103Y491746D01*
G01X-1544764Y490249D02*
X-1544733Y490428D01*
G01X-1545488Y490788D02*
X-1545520Y490608D01*
G01Y491566D02*
X-1545488Y491746D01*
G01X-1546118Y490428D02*
X-1546150Y490249D01*
G01X-1547945Y491327D02*
X-1547913Y491506D01*
G01X-1548134Y491387D02*
X-1548102Y491566D01*
G01X-1555819Y490249D02*
X-1555850Y490069D01*
G01X-1557393Y490249D02*
X-1557362Y490428D01*
G01X-1558118Y490788D02*
X-1558149Y490608D01*
G01Y491566D02*
X-1558118Y491746D01*
G01X-1542167Y493477D02*
X-1542484D01*
G01X-1543225Y493423D02*
X-1542908D01*
G01X-1544124Y493099D02*
X-1543648D01*
G01X-1560048D02*
X-1561001D01*
G01X-1549520D02*
X-1549944D01*
G01X-1541320D02*
X-1541744D01*
G01Y492775D02*
X-1541320D01*
G01X-1551584D02*
X-1551213D01*
G01X-1553224D02*
X-1552906D01*
G01X-1560048D02*
X-1561318D01*
G01X-1557721D02*
X-1558038D01*
G01X-1558461D02*
X-1558779D01*
G01X-1554493D02*
X-1554811D01*
G01X-1549520D02*
X-1549944D01*
G01X-1547933D02*
X-1548251D01*
G01X-1546135D02*
X-1546611D01*
G01X-1543648D02*
X-1544124D01*
G01X-1545394D02*
X-1545711D01*
G01X-1553861Y492661D02*
X-1547956D01*
G01X-1537709Y492405D02*
X-1537583D01*
G01X-1541867D02*
X-1540733D01*
G01X-1542937D02*
X-1542811D01*
G01X-1551283D02*
X-1550087D01*
G01X-1552417D02*
X-1552228D01*
G01X-1553488D02*
X-1553299D01*
G01X-1555567D02*
X-1555378D01*
G01X-1554685D02*
X-1554433D01*
G01X-1556417D02*
X-1556354D01*
G01X-1560039D02*
X-1559787D01*
G01X-1563409D02*
X-1562212D01*
G01X-1564920D02*
X-1564164D01*
G01X-1561298D02*
X-1561456D01*
G01X-1557708D02*
X-1557834D01*
G01X-1546024D02*
X-1547095D01*
G01X-1547347D02*
X-1547473D01*
G01X-1548323D02*
X-1549079D01*
G01X-1543693D02*
X-1543819D01*
G01X-1545079D02*
X-1545205D01*
G01X-1539851D02*
X-1539977D01*
G01X-1542119D02*
X-1542244D01*
G01X-1538465D02*
X-1538591D01*
G01X-1538623Y492105D02*
X-1538434D01*
G01X-1540008D02*
X-1539819D01*
G01X-1543851D02*
X-1543662D01*
G01X-1545236D02*
X-1545047D01*
G01X-1546937D02*
X-1546024D01*
G01X-1557866D02*
X-1557677D01*
G01X-1562212D02*
X-1562716D01*
G01X-1562905D02*
X-1563409D01*
G01X-1556322D02*
X-1556448D01*
G01X-1550087D02*
X-1550590D01*
G01X-1550779D02*
X-1551283D01*
G01X-1548291D02*
X-1548890D01*
G01X-1540922D02*
X-1541867D01*
G01X-1561456Y492045D02*
X-1561267D01*
G01X-1564731D02*
X-1564164D01*
G01X-1540968Y491873D02*
X-1560387D01*
G01X-1538182Y491746D02*
X-1538024D01*
G01X-1539567D02*
X-1539410D01*
G01X-1543410D02*
X-1543252D01*
G01X-1544796D02*
X-1544638D01*
G01X-1557425D02*
X-1557267D01*
G01X-1561078D02*
X-1560889D01*
G01X-1556763D02*
X-1556921D01*
G01X-1565475Y491452D02*
X-1563901D01*
G01X-1536342D02*
X-1537916D01*
G01X-1557677Y491387D02*
X-1557834D01*
G01X-1546433D02*
X-1546622D01*
G01X-1543662D02*
X-1543819D01*
G01X-1545047D02*
X-1545205D01*
G01X-1539819D02*
X-1539977D01*
G01X-1538434D02*
X-1538591D01*
G01X-1548890Y491207D02*
X-1548291D01*
G01X-1561267D02*
X-1561456D01*
G01X-1556448Y491147D02*
X-1556322D01*
G01X-1546622Y491087D02*
X-1546433D01*
G01X-1557645D02*
X-1557866D01*
G01X-1543630D02*
X-1543851D01*
G01X-1545016D02*
X-1545236D01*
G01X-1539788D02*
X-1540008D01*
G01X-1538402D02*
X-1538623D01*
G01X-1551976Y490908D02*
X-1551535D01*
G01X-1554181D02*
X-1553740D01*
G01X-1559031D02*
X-1558590D01*
G01X-1556322D02*
X-1556448D01*
G01X-1547095Y490848D02*
X-1546874D01*
G01X-1548890D02*
X-1548354D01*
G01X-1561456D02*
X-1561267D01*
G01X-1558590Y490608D02*
X-1559031D01*
G01X-1553740D02*
X-1554181D01*
G01X-1551535D02*
X-1551976D01*
G01X-1559629Y490548D02*
X-1560196D01*
G01X-1561771Y490368D02*
X-1561960D01*
G01X-1559598Y490309D02*
X-1560228D01*
G01X-1546906D02*
X-1547095D01*
G01X-1556952Y490249D02*
X-1556795D01*
G01X-1564164Y489949D02*
X-1564731D01*
G01X-1561267D02*
X-1561519D01*
G01X-1565475Y489905D02*
X-1563901D01*
G01X-1536342D02*
X-1537916D01*
G01X-1538623Y489889D02*
X-1538402D01*
G01X-1540008D02*
X-1539788D01*
G01X-1543851D02*
X-1543630D01*
G01X-1545236D02*
X-1545016D01*
G01X-1556480D02*
X-1556291D01*
G01X-1557866D02*
X-1557645D01*
G01X-1546433D02*
X-1546622D01*
G01X-1538591Y489590D02*
X-1538434D01*
G01X-1539977D02*
X-1539819D01*
G01X-1543819D02*
X-1543662D01*
G01X-1545205D02*
X-1545047D01*
G01X-1546622D02*
X-1546433D01*
G01X-1549079D02*
X-1548890D01*
G01X-1548102D02*
X-1547882D01*
G01X-1557834D02*
X-1557677D01*
G01X-1561519D02*
X-1561267D01*
G01X-1562716D02*
X-1562905D01*
G01X-1564164D02*
X-1564920D01*
G01X-1559283D02*
X-1559472D01*
G01X-1560354D02*
X-1560543D01*
G01X-1556259D02*
X-1556511D01*
G01X-1552732D02*
X-1552984D01*
G01X-1555378D02*
X-1555567D01*
G01X-1554433D02*
X-1554685D01*
G01X-1550590D02*
X-1550779D01*
G01X-1541363D02*
X-1541552D01*
G01X-1563507Y489511D02*
X-1561617D01*
G01X-1538310D02*
X-1540357D01*
G01D02*
X-1561617D01*
G01X-1542244Y489231D02*
X-1542119D01*
G01X-1547473D02*
X-1547347D01*
G01X-1542811D02*
X-1542937D01*
G01X-1537583D02*
X-1537709D01*
G01X-1551893Y488921D02*
X-1555730D01*
G01X-1546087D02*
X-1549924D01*
G01X-1547097Y487936D02*
X-1538310D01*
G01X-1554721D02*
X-1563507D01*
G01X-1549924D02*
X-1551893D01*
G01D02*
X-1554721D01*
G01X-1547097D02*
X-1549924D01*
G01X-1544054Y487595D02*
X-1540992D01*
G01X-1560983D02*
X-1557921D01*
G01X-1542683Y486362D02*
X-1542362D01*
G01X-1559612D02*
X-1559291D01*
G01X-1544733Y475877D02*
X-1557084D01*
G01X-1545716Y474944D02*
X-1556101D01*
G01X-1560228Y490309D02*
X-1560354Y489590D01*
G01X-1560196Y490548D02*
X-1559913Y492165D01*
G01X-1561676Y491686D02*
X-1561645Y491866D01*
G01X-1546087Y488921D02*
X-1546120Y488669D01*
G01X-1555850Y491626D02*
X-1555881Y491387D01*
G01X-1556921Y491746D02*
X-1556889Y491986D01*
G01X-1561834D02*
X-1561865Y491746D01*
G01X-1563850Y490548D02*
X-1563881Y490309D01*
G01X-1537457Y490069D02*
X-1537520Y489530D01*
G01X-1537646D02*
X-1537583Y490069D01*
G01X-1542244Y491566D02*
X-1542181Y492105D01*
G01X-1542307D02*
X-1542370Y491566D01*
G01X-1542685Y490069D02*
X-1542748Y489530D01*
G01X-1542874D02*
X-1542811Y490069D01*
G01X-1547473Y491566D02*
X-1547410Y492105D01*
G01X-1547536D02*
X-1547599Y491566D01*
G01X-1563661Y490548D02*
X-1563692Y490249D01*
G01X-1540992Y487595D02*
X-1540790Y489511D01*
G01X-1557921Y487595D02*
X-1557720Y489511D01*
G01X-1538938Y491207D02*
X-1538906Y491566D01*
G01X-1540323Y491207D02*
X-1540292Y491566D01*
G01X-1544166Y491207D02*
X-1544134Y491566D01*
G01X-1545551Y491207D02*
X-1545520Y491566D01*
G01X-1558181Y491207D02*
X-1558149Y491566D01*
G01X-1539064Y491626D02*
X-1539095Y491207D01*
G01X-1540449Y491626D02*
X-1540481Y491207D01*
G01X-1544292Y491626D02*
X-1544323Y491207D01*
G01X-1545677Y491626D02*
X-1545709Y491207D01*
G01X-1558307Y491626D02*
X-1558338Y491207D01*
G01X-1537426Y490608D02*
X-1537457Y490069D01*
G01X-1537583D02*
X-1537552Y490608D01*
G01X-1542276Y491027D02*
X-1542244Y491566D01*
G01X-1542370D02*
X-1542402Y491027D01*
G01X-1542654Y490608D02*
X-1542685Y490069D01*
G01X-1542811D02*
X-1542780Y490608D01*
G01X-1547504Y491027D02*
X-1547473Y491566D01*
G01X-1547599D02*
X-1547630Y491027D01*
G01X-1544733Y475877D02*
X-1544019Y489511D01*
G01X-1542008Y492829D02*
X-1541744Y492775D01*
G01X-1544124D02*
X-1544389Y492829D01*
G01X-1549944Y492775D02*
X-1550208Y492829D01*
G01X-1554986Y487971D02*
X-1554721Y487936D01*
G01X-1559578Y495968D02*
X-1559774Y489511D01*
G01X-1536342Y489905D02*
Y503423D01*
G01X-1537426Y491027D02*
Y490608D01*
G01X-1537552D02*
Y491027D01*
G01X-1537916Y489905D02*
Y512338D01*
G01X-1537961Y490368D02*
Y490668D01*
G01X-1538119Y490428D02*
Y490608D01*
G01X-1538783Y500928D02*
Y489511D01*
G01X-1538906Y490608D02*
Y490428D01*
G01X-1538938Y491087D02*
Y491207D01*
G01X-1539095D02*
Y490788D01*
G01X-1539294Y489511D02*
Y487936D01*
G01X-1539347Y490368D02*
Y490668D01*
G01X-1539504Y490428D02*
Y490608D01*
G01X-1540292D02*
Y490428D01*
G01X-1540323Y491087D02*
Y491207D01*
G01X-1540357Y496913D02*
Y489511D01*
G01X-1540481Y491207D02*
Y490788D01*
G01X-1540527Y493369D02*
Y493639D01*
G01X-1540672Y489511D02*
Y487936D01*
G01X-1540733Y492405D02*
Y492105D01*
G01X-1540844Y493585D02*
Y493423D01*
G01X-1540968Y489511D02*
Y491873D01*
G01X-1541867Y492105D02*
Y492405D01*
G01X-1542276Y490608D02*
Y491027D01*
G01X-1542402D02*
Y490608D01*
G01X-1542654Y491027D02*
Y490608D01*
G01X-1542780D02*
Y491027D01*
G01X-1543189Y490368D02*
Y490668D01*
G01X-1543347Y490428D02*
Y490608D01*
G01X-1543625Y487936D02*
Y489511D01*
G01X-1544134Y490608D02*
Y490428D01*
G01X-1544166Y491087D02*
Y491207D01*
G01X-1544216Y489142D02*
Y487936D01*
G01X-1544323Y491207D02*
Y490788D01*
G01X-1544575Y490368D02*
Y490668D01*
G01X-1544653Y494450D02*
Y493639D01*
G01X-1544733Y490428D02*
Y490608D01*
G01X-1544971Y493639D02*
Y494450D01*
G01X-1545003Y489511D02*
Y487936D01*
G01X-1545161Y489511D02*
Y487936D01*
G01X-1545394Y495314D02*
Y492775D01*
G01X-1545520Y490608D02*
Y490428D01*
G01X-1545551Y491087D02*
Y491207D01*
G01X-1545709D02*
Y490788D01*
G01X-1545711Y492775D02*
Y495314D01*
G01X-1545869Y496204D02*
Y489511D01*
G01X-1545961Y490368D02*
Y490608D01*
G01X-1545987Y491873D02*
Y489511D01*
G01X-1546024Y492105D02*
Y492405D01*
G01X-1546087Y491873D02*
Y488921D01*
G01X-1546118Y490548D02*
Y490428D01*
G01X-1546135Y495314D02*
Y492775D01*
G01X-1546452Y493153D02*
Y495314D01*
G01X-1546937Y491147D02*
Y492105D01*
G01X-1547095Y492405D02*
Y490848D01*
G01X-1547504Y490608D02*
Y491027D01*
G01X-1547630D02*
Y490608D01*
G01X-1547913Y491506D02*
Y491746D01*
G01X-1547933Y494990D02*
Y492775D01*
G01X-1547956Y487936D02*
Y489511D01*
G01Y492661D02*
Y491873D01*
G01X-1548102Y491566D02*
Y491746D01*
G01X-1548125Y491873D02*
Y488921D01*
G01X-1548251Y492775D02*
Y495314D01*
G01X-1548290Y487936D02*
Y489511D01*
G01X-1548674Y494450D02*
Y493639D01*
G01X-1548890Y489590D02*
Y490848D01*
G01Y492105D02*
Y491207D01*
G01X-1548991Y494450D02*
Y493639D01*
G01X-1549079Y492405D02*
Y489590D01*
G01X-1549924Y491873D02*
Y487936D01*
G01X-1550087Y492405D02*
Y492105D01*
G01X-1550473Y493639D02*
Y494450D01*
G01X-1550590Y492105D02*
Y489590D01*
G01X-1550779D02*
Y492105D01*
G01X-1550790Y493639D02*
Y494450D01*
G01X-1551283Y492105D02*
Y492405D01*
G01X-1551535Y490908D02*
Y490608D01*
G01X-1551893Y491873D02*
Y487936D01*
G01X-1551976Y490608D02*
Y490908D01*
G01X-1552906Y492775D02*
Y493910D01*
G01X-1553224Y495314D02*
Y492775D01*
G01X-1553527Y487936D02*
Y489511D01*
G01X-1553530Y487936D02*
Y489511D01*
G01X-1553692Y491873D02*
Y488921D01*
G01X-1553740Y490908D02*
Y490608D01*
G01X-1553861Y487936D02*
Y489511D01*
G01Y492661D02*
Y491873D01*
G01X-1554181Y490608D02*
Y490908D01*
G01X-1554493Y495044D02*
Y492775D01*
G01X-1554811D02*
Y495044D01*
G01X-1555378Y492405D02*
Y491027D01*
G01Y490548D02*
Y489590D01*
G01X-1555567D02*
Y492405D01*
G01X-1555730Y491873D02*
Y488921D01*
G01X-1555819Y490488D02*
Y490249D01*
G01X-1555830Y489511D02*
Y491873D01*
G01X-1555850Y491746D02*
Y491626D01*
G01X-1555976Y490249D02*
Y490488D01*
G01X-1556007Y491626D02*
Y491746D01*
G01X-1556105Y496204D02*
Y489511D01*
G01X-1556448Y490908D02*
Y491147D01*
G01X-1556656Y489511D02*
Y487936D01*
G01X-1556814Y489511D02*
Y487936D01*
G01X-1557204Y490368D02*
Y490668D01*
G01X-1557362Y490428D02*
Y490608D01*
G01X-1557601Y489511D02*
Y487936D01*
G01X-1557721Y493910D02*
Y492775D01*
G01X-1558038D02*
Y495314D01*
G01X-1558149Y490608D02*
Y490428D01*
G01X-1558181Y491087D02*
Y491207D01*
G01X-1558192Y487936D02*
Y489511D01*
G01X-1558338Y491207D02*
Y490788D01*
G01X-1558461Y495314D02*
Y492775D01*
G01X-1558590Y490908D02*
Y490608D01*
G01X-1558779Y492775D02*
Y495314D01*
G01X-1559031Y490608D02*
Y490908D01*
G01X-1559202Y494450D02*
Y493639D01*
G01X-1559519Y494450D02*
Y493639D01*
G01X-1559570Y489511D02*
Y491873D01*
G01X-1560387Y489511D02*
Y491873D01*
G01X-1560795Y490249D02*
Y490548D01*
G01X-1560984Y490488D02*
Y490309D01*
G01X-1561001Y493099D02*
Y494990D01*
G01X-1561145Y489142D02*
Y487936D01*
G01X-1561318Y492775D02*
Y495314D01*
G01X-1561617Y496913D02*
Y489511D01*
G01X-1561676Y491566D02*
Y491686D01*
G01X-1561865Y491746D02*
Y491506D01*
G01X-1562212Y492405D02*
Y492105D01*
G01X-1562523Y489511D02*
Y487936D01*
G01X-1562716Y492105D02*
Y489590D01*
G01X-1562905D02*
Y492105D01*
G01X-1563192Y500928D02*
Y489511D01*
G01X-1563409Y492105D02*
Y492405D01*
G01X-1563661Y491447D02*
Y490548D01*
G01X-1563850Y491447D02*
Y490548D01*
G01X-1563901Y489905D02*
Y512338D01*
G01X-1564731Y489949D02*
Y492045D01*
G01X-1564920Y489590D02*
Y492405D01*
G01X-1565475Y489905D02*
Y503423D01*
G01X-1542396Y495968D02*
X-1542200Y489511D01*
G01X-1537457Y491566D02*
X-1537426Y491027D01*
G01X-1537552D02*
X-1537583Y491566D01*
G01X-1542244Y490069D02*
X-1542276Y490608D01*
G01X-1542402D02*
X-1542370Y490069D01*
G01X-1542685Y491566D02*
X-1542654Y491027D01*
G01X-1542780D02*
X-1542811Y491566D01*
G01X-1547473Y490069D02*
X-1547504Y490608D01*
G01X-1547630D02*
X-1547599Y490069D01*
G01X-1539095Y490788D02*
X-1539064Y490368D01*
G01X-1540481Y490788D02*
X-1540449Y490368D01*
G01X-1544323Y490788D02*
X-1544292Y490368D01*
G01X-1537520Y492105D02*
X-1537457Y491566D01*
G01X-1537583D02*
X-1537646Y492105D01*
G01X-1542181Y489530D02*
X-1542244Y490069D01*
G01X-1542370D02*
X-1542307Y489530D01*
G01X-1542748Y492105D02*
X-1542685Y491566D01*
G01X-1542811D02*
X-1542874Y492105D01*
G01X-1547410Y489530D02*
X-1547473Y490069D01*
G01X-1547599D02*
X-1547536Y489530D01*
G01X-1555881Y491986D02*
X-1555850Y491746D01*
G01Y490728D02*
X-1555819Y490488D01*
G01X-1561865Y491506D02*
X-1561834Y491267D01*
G01X-1561960Y490368D02*
X-1561928Y490129D01*
G01X-1563881Y491686D02*
X-1563850Y491447D01*
G01X-1555730Y488921D02*
X-1555697Y488669D01*
G01X-1538024Y491746D02*
X-1538056Y491926D01*
G01X-1538119Y490608D02*
X-1538150Y490788D01*
G01X-1538906Y490428D02*
X-1538875Y490249D01*
G01X-1539410Y491746D02*
X-1539441Y491926D01*
G01X-1539504Y490608D02*
X-1539536Y490788D01*
G01X-1540292Y490428D02*
X-1540260Y490249D01*
G01X-1543252Y491746D02*
X-1543284Y491926D01*
G01X-1543347Y490608D02*
X-1543378Y490788D01*
G01X-1544134Y490428D02*
X-1544103Y490249D01*
G01X-1544638Y491746D02*
X-1544670Y491926D01*
G01X-1544733Y490608D02*
X-1544764Y490788D01*
G01X-1545520Y490428D02*
X-1545488Y490249D01*
G01X-1546150Y490728D02*
X-1546118Y490548D01*
G01X-1547913Y491746D02*
X-1547945Y491926D01*
G01X-1548102Y491746D02*
X-1548134Y491926D01*
G01X-1552984Y489590D02*
X-1553488Y492405D01*
G01X-1553299D02*
X-1552858Y489949D01*
G01X-1544918Y493369D02*
X-1544971Y493639D01*
G01X-1548354Y490848D02*
X-1548102Y489590D01*
G01X-1537583Y492405D02*
X-1537520Y492105D01*
G01X-1537646D02*
X-1537709Y492405D01*
G01X-1537961Y490668D02*
X-1538024Y490967D01*
G01X-1539064Y490368D02*
X-1539001Y490069D01*
G01X-1539347Y490668D02*
X-1539410Y490967D01*
G01X-1540449Y490368D02*
X-1540386Y490069D01*
G01X-1542119Y489231D02*
X-1542181Y489530D01*
G01X-1542811Y492405D02*
X-1542748Y492105D01*
G01X-1542307Y489530D02*
X-1542244Y489231D01*
G01X-1542874Y492105D02*
X-1542937Y492405D01*
G01X-1543189Y490668D02*
X-1543252Y490967D01*
G01X-1544292Y490368D02*
X-1544229Y490069D01*
G01X-1544575Y490668D02*
X-1544638Y490967D01*
G01X-1545677Y490368D02*
X-1545614Y490069D01*
G01X-1545961Y490608D02*
X-1546024Y490908D01*
G01X-1556133Y490848D02*
X-1556322Y490908D01*
G01X-1556354Y492405D02*
X-1556133Y492345D01*
G01X-1541320Y493910D02*
X-1541109Y493856D01*
G01X-1541744Y493099D02*
X-1541955Y493153D01*
G01X-1544336D02*
X-1544124Y493099D01*
G01X-1549944D02*
X-1550155Y493153D01*
G01X-1578468Y1236307D02*
Y473369D01*
G01X-1557084Y475877D02*
X-1557798Y489511D01*
G01X-1545709Y490788D02*
X-1545677Y490368D01*
G01X-1558338Y490788D02*
X-1558307Y490368D01*
G01X-1544054Y487595D02*
X-1544216Y489142D01*
G01X-1560983Y487595D02*
X-1561145Y489142D01*
G01X-1563692Y491746D02*
X-1563661Y491447D01*
G01X-1556921Y490069D02*
X-1556952Y490249D01*
G01X-1557267Y491746D02*
X-1557299Y491926D01*
G01X-1557362Y490608D02*
X-1557393Y490788D01*
G01X-1558149Y490428D02*
X-1558118Y490249D01*
G01X-1559913Y492165D02*
X-1559629Y490548D01*
G01X-1559472Y489590D02*
X-1559598Y490309D01*
G01X-1560889Y491746D02*
X-1560921Y491926D01*
G01X-1561645Y491387D02*
X-1561676Y491566D01*
G01X-1561739Y490189D02*
X-1561771Y490368D01*
G01X-1559787Y492405D02*
X-1559283Y489590D01*
G01X-1550737Y493369D02*
X-1550790Y493639D01*
G01X-1547882Y489590D02*
X-1548165Y490967D01*
G01X-1547347Y489231D02*
X-1547410Y489530D01*
G01X-1547536D02*
X-1547473Y489231D01*
G01X-1557204Y490668D02*
X-1557267Y490967D01*
G01X-1558307Y490368D02*
X-1558244Y490069D01*
G01X-1542484Y493477D02*
X-1542431Y493261D01*
G01X-1544653Y493639D02*
X-1544600Y493423D01*
G01X-1550420D02*
X-1550473Y493639D01*
G01X-1546843Y490069D02*
X-1546906Y490309D01*
G01X-1547095D02*
X-1547032Y490069D01*
G01X-1555976Y490488D02*
X-1556039Y490728D01*
G01X-1556795Y490249D02*
X-1556763Y490129D01*
G01X-1561110Y491866D02*
X-1561078Y491746D01*
G01X-1560795Y490548D02*
X-1560858Y490788D01*
G01X-1563755Y491986D02*
X-1563692Y491746D01*
G01X-1561928Y490129D02*
X-1561834Y489829D01*
G01X-1542114Y493315D02*
X-1542167Y493477D01*
G01X-1555000Y491267D02*
X-1554433Y489590D01*
G01X-1554685D02*
X-1555157Y490967D01*
G01X-1538245Y491926D02*
X-1538182Y491746D01*
G01X-1538875Y490249D02*
X-1538812Y490069D01*
G01X-1539630Y491926D02*
X-1539567Y491746D01*
G01X-1540260Y490249D02*
X-1540197Y490069D01*
G01X-1543473Y491926D02*
X-1543410Y491746D01*
G01X-1544103Y490249D02*
X-1544040Y490069D01*
G01X-1544859Y491926D02*
X-1544796Y491746D01*
G01X-1545488Y490249D02*
X-1545425Y490069D01*
G01X-1546213Y490908D02*
X-1546150Y490728D01*
G01X-1556007Y491746D02*
X-1556070Y491926D01*
G01X-1555913Y490908D02*
X-1555850Y490728D01*
G01X-1552007Y493910D02*
X-1551584Y492775D01*
G01X-1538056Y491926D02*
X-1538150Y492165D01*
G01X-1539441Y491926D02*
X-1539536Y492165D01*
G01X-1539001Y490069D02*
X-1538906Y489829D01*
G01X-1540386Y490069D02*
X-1540292Y489829D01*
G01X-1543284Y491926D02*
X-1543378Y492165D01*
G01X-1544670Y491926D02*
X-1544764Y492165D01*
G01X-1544229Y490069D02*
X-1544134Y489829D01*
G01X-1545614Y490069D02*
X-1545520Y489829D01*
G01X-1546024Y490908D02*
X-1546118Y491147D01*
G01X-1547032Y490069D02*
X-1546937Y489829D01*
G01X-1547945Y491926D02*
X-1548039Y492165D01*
G01X-1544389Y492829D02*
X-1544600Y492937D01*
G01X-1550208Y492829D02*
X-1550420Y492937D01*
G01X-1537959Y489726D02*
X-1536556Y489012D01*
G01X-1546433Y491087D02*
X-1546307Y491027D01*
G01X-1546622Y489889D02*
X-1546748Y489949D01*
G01X-1556511Y489590D02*
X-1556637Y489650D01*
G01X-1561267Y490848D02*
X-1561141Y490788D01*
G01X-1561582Y490908D02*
X-1561456Y490848D01*
G01X-1564164Y492045D02*
X-1564038Y491986D01*
G01X-1561519Y489949D02*
X-1561645Y490009D01*
G01X-1555228Y488069D02*
X-1554983Y487970D01*
G01X-1538308Y492345D02*
X-1538465Y492405D01*
G01X-1539693Y492345D02*
X-1539851Y492405D01*
G01X-1538276Y491327D02*
X-1538434Y491387D01*
G01X-1539662Y491327D02*
X-1539819Y491387D01*
G01X-1543536Y492345D02*
X-1543693Y492405D01*
G01X-1544921Y492345D02*
X-1545079Y492405D01*
G01X-1538749Y489650D02*
X-1538591Y489590D01*
G01X-1543504Y491327D02*
X-1543662Y491387D01*
G01X-1540134Y489650D02*
X-1539977Y489590D01*
G01X-1544890Y491327D02*
X-1545047Y491387D01*
G01X-1548165Y492345D02*
X-1548323Y492405D01*
G01X-1546276Y491327D02*
X-1546433Y491387D01*
G01X-1543977Y489650D02*
X-1543819Y489590D01*
G01X-1545362Y489650D02*
X-1545205Y489590D01*
G01X-1546780Y489650D02*
X-1546622Y489590D01*
G01X-1556165Y492045D02*
X-1556322Y492105D01*
G01X-1557551Y492345D02*
X-1557708Y492405D01*
G01X-1557519Y491327D02*
X-1557677Y491387D01*
G01X-1561141Y492345D02*
X-1561298Y492405D01*
G01X-1556637Y489949D02*
X-1556480Y489889D01*
G01X-1564164Y492405D02*
X-1564007Y492345D01*
G01X-1561110Y491147D02*
X-1561267Y491207D01*
G01X-1557992Y489650D02*
X-1557834Y489590D01*
G01X-1561676Y489650D02*
X-1561519Y489590D01*
G01X-1557488Y491926D02*
X-1557425Y491746D01*
G01X-1556858Y489889D02*
X-1556921Y490069D01*
G01X-1558118Y490249D02*
X-1558055Y490069D01*
G01X-1561047Y490668D02*
X-1560984Y490488D01*
G01X-1563944Y491866D02*
X-1563881Y491686D01*
G01X-1551213Y492775D02*
X-1551690Y494018D01*
G01X-1557299Y491926D02*
X-1557393Y492165D01*
G01X-1558244Y490069D02*
X-1558149Y489829D01*
G01X-1560921Y491926D02*
X-1561015Y492165D01*
G01X-1555597Y488430D02*
X-1555697Y488671D01*
G01X-1540527Y493639D02*
X-1540633Y493856D01*
G01X-1544812Y493153D02*
X-1544918Y493369D01*
G01X-1550631Y493153D02*
X-1550737Y493369D01*
G01X-1539536Y490788D02*
X-1539599Y490908D01*
G01X-1544764Y490788D02*
X-1544827Y490908D01*
G01X-1556007Y492225D02*
X-1555881Y491986D01*
G01X-1556763Y490129D02*
X-1556700Y490009D01*
G01X-1557393Y490788D02*
X-1557456Y490908D01*
G01X-1561173Y491986D02*
X-1561110Y491866D01*
G01X-1538024Y490967D02*
X-1538119Y491147D01*
G01X-1538150Y490788D02*
X-1538213Y490908D01*
G01X-1539410Y490967D02*
X-1539504Y491147D01*
G01X-1543252Y490967D02*
X-1543347Y491147D01*
G01X-1543378Y490788D02*
X-1543441Y490908D01*
G01X-1544638Y490967D02*
X-1544733Y491147D01*
G01X-1548134Y491926D02*
X-1548197Y492045D01*
G01X-1557267Y490967D02*
X-1557362Y491147D01*
G01X-1560858Y490788D02*
X-1560984Y491027D01*
G01X-1561834Y491267D02*
X-1561708Y491027D01*
G01X-1561645Y490009D02*
X-1561739Y490189D01*
G01X-1563881Y492225D02*
X-1563755Y491986D01*
G01X-1542431Y493261D02*
X-1542273Y492991D01*
G01X-1546611Y492775D02*
X-1547933Y494990D01*
G01X-1547775Y495314D02*
X-1546452Y493153D01*
G01X-1540950Y493747D02*
X-1540844Y493585D01*
G01X-1544600Y493423D02*
X-1544495Y493261D01*
G01X-1550314D02*
X-1550420Y493423D01*
G01X-1548039Y492165D02*
X-1548165Y492345D01*
G01X-1561015Y492165D02*
X-1561141Y492345D01*
G01X-1555597Y488430D02*
X-1555438Y488227D01*
G01X-1538339Y492045D02*
X-1538245Y491926D01*
G01X-1538213Y490908D02*
X-1538308Y491027D01*
G01X-1539725Y492045D02*
X-1539630Y491926D01*
G01X-1538812Y490069D02*
X-1538717Y489949D01*
G01X-1539599Y490908D02*
X-1539693Y491027D01*
G01X-1540197Y490069D02*
X-1540103Y489949D01*
G01X-1543567Y492045D02*
X-1543473Y491926D01*
G01X-1543441Y490908D02*
X-1543536Y491027D01*
G01X-1544953Y492045D02*
X-1544859Y491926D01*
G01X-1544040Y490069D02*
X-1543945Y489949D01*
G01X-1544827Y490908D02*
X-1544921Y491027D01*
G01X-1545425Y490069D02*
X-1545331Y489949D01*
G01X-1546307Y491027D02*
X-1546213Y490908D01*
G01X-1546748Y489949D02*
X-1546843Y490069D01*
G01X-1549425Y491806D02*
X-1549331Y491686D01*
G01X-1549740Y490189D02*
X-1549835Y490309D01*
G01X-1556070Y491926D02*
X-1556165Y492045D01*
G01X-1556039Y490728D02*
X-1556133Y490848D01*
G01X-1557582Y492045D02*
X-1557488Y491926D01*
G01X-1557456Y490908D02*
X-1557551Y491027D01*
G01X-1556763Y489770D02*
X-1556858Y489889D01*
G01X-1558055Y490069D02*
X-1557960Y489949D01*
G01X-1538150Y492165D02*
X-1538308Y492345D01*
G01X-1538119Y491147D02*
X-1538276Y491327D01*
G01X-1539536Y492165D02*
X-1539693Y492345D01*
G01X-1539504Y491147D02*
X-1539662Y491327D01*
G01X-1538906Y489829D02*
X-1538749Y489650D01*
G01X-1540292Y489829D02*
X-1540134Y489650D01*
G01X-1543378Y492165D02*
X-1543536Y492345D01*
G01X-1543347Y491147D02*
X-1543504Y491327D01*
G01X-1544764Y492165D02*
X-1544921Y492345D01*
G01X-1544733Y491147D02*
X-1544890Y491327D01*
G01X-1544134Y489829D02*
X-1543977Y489650D01*
G01X-1546118Y491147D02*
X-1546276Y491327D01*
G01X-1545520Y489829D02*
X-1545362Y489650D01*
G01X-1546937Y489829D02*
X-1546780Y489650D01*
G01X-1557393Y492165D02*
X-1557551Y492345D01*
G01X-1557362Y491147D02*
X-1557519Y491327D01*
G01X-1540633Y493856D02*
X-1540844Y494072D01*
G01X-1541955Y493153D02*
X-1542114Y493315D01*
G01X-1544600Y492937D02*
X-1544812Y493153D01*
G01X-1550420Y492937D02*
X-1550631Y493153D01*
G01X-1556133Y492345D02*
X-1556007Y492225D01*
G01X-1556700Y490009D02*
X-1556637Y489949D01*
G01Y489650D02*
X-1556763Y489770D01*
G01X-1560984Y491027D02*
X-1561110Y491147D01*
G01X-1561708Y491027D02*
X-1561582Y490908D01*
G01X-1564007Y492345D02*
X-1563881Y492225D01*
G01X-1556070Y491027D02*
X-1555913Y490908D01*
G01X-1555226Y488068D02*
X-1555438Y488227D01*
G01X-1541109Y493856D02*
X-1540950Y493747D01*
G01X-1544495Y493261D02*
X-1544336Y493153D01*
G01X-1550155D02*
X-1550314Y493261D01*
G01X-1538434Y492105D02*
X-1538339Y492045D01*
G01X-1539819Y492105D02*
X-1539725Y492045D01*
G01X-1538308Y491027D02*
X-1538402Y491087D01*
G01X-1539693Y491027D02*
X-1539788Y491087D01*
G01X-1538717Y489949D02*
X-1538623Y489889D01*
G01X-1540103Y489949D02*
X-1540008Y489889D01*
G01X-1543662Y492105D02*
X-1543567Y492045D01*
G01X-1545047Y492105D02*
X-1544953Y492045D01*
G01X-1543536Y491027D02*
X-1543630Y491087D01*
G01X-1544921Y491027D02*
X-1545016Y491087D01*
G01X-1543945Y489949D02*
X-1543851Y489889D01*
G01X-1548197Y492045D02*
X-1548291Y492105D01*
G01X-1545331Y489949D02*
X-1545236Y489889D01*
G01X-1557677Y492105D02*
X-1557582Y492045D01*
G01X-1557551Y491027D02*
X-1557645Y491087D01*
G01X-1557960Y489949D02*
X-1557866Y489889D01*
G01X-1561267Y492045D02*
X-1561173Y491986D01*
G01X-1561456Y491207D02*
X-1561550Y491267D01*
G01X-1542273Y492991D02*
X-1542008Y492829D01*
G01X-1561141Y490788D02*
X-1561047Y490668D01*
G01X-1561550Y491267D02*
X-1561645Y491387D01*
G01X-1564038Y491986D02*
X-1563944Y491866D01*
G01X-1558149Y489829D02*
X-1557992Y489650D01*
G01X-1561834Y489829D02*
X-1561676Y489650D01*
G01X-1563727Y505546D02*
X-1563605Y505466D01*
G01X-1563824Y505660D02*
X-1563727Y505546D01*
G01X-1518192Y517827D02*
X-1518186Y517661D01*
G01X-1518210Y517987D02*
X-1518192Y517827D01*
G01X-1518239Y518131D02*
X-1518210Y517987D01*
G01X-1518278Y518250D02*
X-1518239Y518131D01*
G01X-1518325Y518343D02*
X-1518278Y518250D01*
G01X-1518377Y518403D02*
X-1518325Y518343D01*
G01X-1537533Y500246D02*
X-1537405Y500015D01*
G01X-1537655Y500506D02*
X-1537533Y500246D01*
G01X-1537754Y500802D02*
X-1537655Y500506D01*
G01X-1537530Y500251D02*
X-1537405Y500015D01*
G01X-1537657Y500501D02*
X-1537530Y500251D01*
G01X-1537754Y500802D02*
X-1537657Y500501D01*
G01X-1564999Y503837D02*
X-1564996Y503909D01*
G01X-1564999Y503724D02*
Y503837D01*
G01X-1564996Y503581D02*
X-1564999Y503724D01*
G01X-1562354Y504344D02*
X-1562326Y504067D01*
G01X-1562436Y504605D02*
X-1562354Y504344D01*
G01X-1562567Y504845D02*
X-1562436Y504605D01*
G01X-1562742Y505054D02*
X-1562567Y504845D01*
G01X-1562956Y505224D02*
X-1562742Y505054D01*
G01X-1563200Y505349D02*
X-1562956Y505224D01*
G01X-1563474Y505425D02*
X-1563200Y505349D01*
G01X-1563111Y505311D02*
X-1563605Y505466D01*
G01X-1562785Y505094D02*
X-1563111Y505311D01*
G01X-1562534Y504795D02*
X-1562785Y505094D01*
G01X-1562377Y504438D02*
X-1562534Y504795D01*
G01X-1562326Y504067D02*
X-1562377Y504438D01*
G01X-1563882Y505794D02*
X-1563824Y505660D01*
G01X-1563901Y505930D02*
X-1563882Y505794D01*
G01X-1537435Y503506D02*
X-1537430Y503392D01*
G01X-1537439Y503615D02*
X-1537435Y503506D01*
G01X-1538341Y505212D02*
X-1538343Y505399D01*
G01Y505048D02*
X-1538341Y505212D01*
G01X-1562435Y504447D02*
X-1562354Y504263D01*
G01X-1562570Y504620D02*
X-1562435Y504447D01*
G01X-1562747Y504767D02*
X-1562570Y504620D01*
G01X-1562966Y504889D02*
X-1562747Y504767D01*
G01X-1563210Y504976D02*
X-1562966Y504889D01*
G01X-1563474Y505027D02*
X-1563210Y504976D01*
G01X-1565452Y504291D02*
X-1565475Y504445D01*
G01X-1565383Y504151D02*
X-1565452Y504291D01*
G01X-1565274Y504038D02*
X-1565383Y504151D01*
G01X-1565138Y503964D02*
X-1565274Y504038D01*
G01X-1564989Y503934D02*
X-1565138Y503964D01*
G01X-1516841Y518343D02*
X-1516893Y518403D01*
G01X-1516794Y518249D02*
X-1516841Y518343D01*
G01X-1516755Y518127D02*
X-1516794Y518249D01*
G01X-1516726Y517985D02*
X-1516755Y518127D01*
G01X-1516708Y517826D02*
X-1516726Y517985D01*
G01X-1516702Y517661D02*
X-1516708Y517826D01*
G01X-1536821Y503581D02*
X-1536828Y503423D01*
G01X-1536818Y503723D02*
X-1536821Y503581D01*
G01X-1537435Y503890D02*
X-1537430Y503904D01*
G01X-1537439Y503852D02*
X-1537435Y503890D01*
G01X-1537440Y503791D02*
X-1537439Y503852D01*
G01X-1518324Y516979D02*
X-1518377Y516918D01*
G01X-1518278Y517072D02*
X-1518324Y516979D01*
G01X-1518239Y517194D02*
X-1518278Y517072D01*
G01X-1518210Y517336D02*
X-1518239Y517194D01*
G01X-1518192Y517496D02*
X-1518210Y517336D01*
G01X-1518186Y517661D02*
X-1518192Y517496D01*
G01X-1536821Y503909D02*
X-1536828Y503934D01*
G01X-1536818Y503837D02*
X-1536821Y503909D01*
G01X-1536818Y503724D02*
Y503837D01*
G01X-1536821Y503581D02*
X-1536818Y503724D01*
G01X-1536828Y503423D02*
X-1536821Y503581D01*
G01X-1536540Y504040D02*
X-1536675Y503965D01*
G01X-1536433Y504153D02*
X-1536540Y504040D01*
G01X-1536365Y504292D02*
X-1536433Y504153D01*
G01X-1536342Y504445D02*
X-1536365Y504292D01*
G01X-1537585Y503871D02*
X-1537430Y503904D01*
G01X-1537720Y503796D02*
X-1537585Y503871D01*
G01X-1537824Y503686D02*
X-1537720Y503796D01*
G01X-1537892Y503547D02*
X-1537824Y503686D01*
G01X-1537916Y503392D02*
X-1537892Y503547D01*
G01X-1564996Y503581D02*
X-1564989Y503423D01*
G01X-1564999Y503724D02*
X-1564996Y503581D01*
G01X-1564999Y503837D02*
Y503724D01*
G01X-1564996Y503909D02*
X-1564999Y503837D01*
G01X-1564989Y503934D02*
X-1564996Y503909D01*
G01X-1537913Y500015D02*
X-1537916D01*
G01X-1537902Y500014D02*
X-1537913Y500015D01*
G01X-1537885D02*
X-1537902Y500014D01*
G01X-1564287Y500251D02*
X-1564412Y500015D01*
G01X-1564160Y500500D02*
X-1564287Y500251D01*
G01X-1564063Y500802D02*
X-1564160Y500500D01*
G01X-1564284Y500246D02*
X-1564412Y500015D01*
G01X-1564162Y500507D02*
X-1564284Y500246D01*
G01X-1564063Y500802D02*
X-1564162Y500507D01*
G01X-1537901Y503516D02*
X-1537916Y503392D01*
G01X-1537854Y503637D02*
X-1537901Y503516D01*
G01X-1537776Y503744D02*
X-1537854Y503637D01*
G01X-1537673Y503828D02*
X-1537776Y503744D01*
G01X-1537554Y503882D02*
X-1537673Y503828D01*
G01X-1537430Y503904D02*
X-1537554Y503882D01*
G01X-1563957Y503815D02*
X-1564023Y503747D01*
G01X-1563913Y503862D02*
X-1563957Y503815D01*
G01X-1563901Y503879D02*
X-1563913Y503862D01*
G01D02*
X-1563958Y503813D01*
G01X-1563901Y503878D02*
X-1563913Y503862D01*
G01X-1516708Y517494D02*
X-1516702Y517661D01*
G01X-1516726Y517335D02*
X-1516708Y517494D01*
G01X-1516756Y517191D02*
X-1516726Y517335D01*
G01X-1516794Y517071D02*
X-1516756Y517191D01*
G01X-1516841Y516978D02*
X-1516794Y517071D01*
G01X-1516893Y516918D02*
X-1516841Y516978D01*
G01X-1563915Y503859D02*
X-1563900Y503879D01*
G01X-1563974Y503796D02*
X-1563915Y503859D01*
G01X-1564124Y503646D02*
X-1564023Y503747D01*
G01X-1564238Y503536D02*
X-1564124Y503646D01*
G01X-1539086Y504374D02*
X-1539112Y504067D01*
G01X-1539013Y504664D02*
X-1539086Y504374D01*
G01X-1538895Y504924D02*
X-1539013Y504664D01*
G01X-1538737Y505142D02*
X-1538895Y504924D01*
G01X-1538549Y505306D02*
X-1538737Y505142D01*
G01X-1538343Y505408D02*
X-1538549Y505306D01*
G01X-1539442Y504433D02*
X-1539491Y504067D01*
G01X-1539285Y504792D02*
X-1539442Y504433D01*
G01X-1539032Y505094D02*
X-1539285Y504792D01*
G01X-1538701Y505313D02*
X-1539032Y505094D01*
G01X-1538343Y505425D02*
X-1538701Y505313D01*
G01X-1520397Y571795D02*
G03I-6889J0D01*
G01X-1508586D02*
G03I-18700J0D01*
G01X-1537430Y503904D02*
G03X-1537916Y503392I26J-511D01*
G01X-1536828Y503934D02*
G03X-1536342Y504445I-26J511D01*
G01X-1516676Y512622D02*
G03X-1517009Y513153I-590J0D01*
G01X-1516657Y515102D02*
G03X-1516323Y514571I590J1D01*
G01X-1516657Y500141D02*
G03X-1515869Y499354I787J0D01*
G01X-1535160Y507818D02*
G03I-1969J0D01*
G01X-1515475Y517661D02*
G03I-1969J0D01*
G01X-1510554Y507818D02*
G03I-1969J0D01*
G01X-1518231Y515102D02*
G03X-1517009Y513153I2165J0D01*
G01X-1515101Y512622D02*
G03X-1516323Y514571I-2165J0D01*
G01X-1518231Y500141D02*
G03X-1515869Y497779I2362J0D01*
G01X-1558383Y495449D02*
G03X-1543592I7395J88629D01*
G01X-1558403Y495214D02*
G03X-1543572I7415J88864D01*
G01X-1538343Y505425D02*
G03X-1537916Y505930I-85J505D01*
G01X-1565475Y504445D02*
G03X-1564989Y503934I512J0D01*
G01X-1563901Y505930D02*
G03X-1563474Y505425I512J0D01*
G01X-1538343D02*
G03X-1539491Y504067I229J-1358D01*
G01X-1562326D02*
G03X-1563474Y505425I-1377J0D01*
G01X-1562720Y507818D02*
G03I-1968J0D01*
G01X-1557798Y497976D02*
G03I-1969J0D01*
G01X-1540082D02*
G03I-1968J0D01*
G01X-1558946Y495526D02*
G03X-1558378Y495448I1001J5180D01*
G01X-1543596D02*
G03X-1543028Y495526I-433J5258D01*
G01X-1543577Y495212D02*
G03X-1542983Y495294I-456J5493D01*
G01X-1558991D02*
G03X-1558398Y495212I1050J5411D01*
G01X-1552956Y496204D02*
G03X-1552807Y496163I1955J6812D01*
G01X-1549167D02*
G03X-1549033Y496200I-1819J6849D01*
G01X-1541797Y494936D02*
X-1541638Y494990D01*
G01X-1551901Y494234D02*
X-1551742Y494288D01*
G01X-1512634Y507982D02*
X-1512496Y508029D01*
G01X-1556715Y494234D02*
X-1556557Y494288D01*
G01X-1564618Y508098D02*
X-1564189Y508244D01*
G01X-1541849Y495260D02*
X-1542061Y495152D01*
G01X-1544600D02*
X-1544389Y495260D01*
G01X-1551690Y494018D02*
X-1551478Y494126D01*
G01X-1550420Y495152D02*
X-1550208Y495260D01*
G01X-1542893Y499662D02*
X-1542575Y499824D01*
G01X-1563902Y506416D02*
X-1564189Y506269D01*
G01Y506635D02*
X-1564045Y506708D01*
G01X-1565621Y509414D02*
X-1565334Y509560D01*
G01X-1541955Y494828D02*
X-1541797Y494936D01*
G01X-1544336D02*
X-1544495Y494828D01*
G01X-1542496Y499418D02*
X-1542734Y499256D01*
G01X-1550314Y494828D02*
X-1550155Y494936D01*
G01X-1563687Y506562D02*
X-1563902Y506416D01*
G01X-1565263Y509194D02*
X-1565477Y509048D01*
G01X-1512267Y507889D02*
X-1512451Y507748D01*
G01X-1563759Y508171D02*
X-1564045Y507951D01*
G01X-1517691Y516283D02*
X-1516893Y516918D01*
G01X-1518377D02*
X-1519175Y516283D01*
G01X-1540749Y498283D02*
X-1542734Y496499D01*
G01X-1543369D02*
X-1541146Y498526D01*
G01X-1512496Y508029D02*
X-1512405Y508123D01*
G01X-1564387Y503392D02*
X-1564213Y503560D01*
G01X-1564077Y503693D02*
X-1564235Y503538D01*
G01X-1564077Y503693D02*
X-1563956Y503814D01*
G01X-1542061Y495152D02*
X-1542273Y494936D01*
G01X-1544812D02*
X-1544600Y495152D01*
G01X-1543210Y499337D02*
X-1542893Y499662D01*
G01X-1550631Y494936D02*
X-1550420Y495152D01*
G01X-1551742Y494288D02*
X-1551637Y494396D01*
G01X-1556557Y494288D02*
X-1556451Y494396D01*
G01X-1564045Y506708D02*
X-1563902Y506854D01*
G01X-1564189Y508244D02*
X-1564045Y508390D01*
G01X-1565907Y509121D02*
X-1565621Y509414D01*
G01X-1511440Y508545D02*
X-1511716Y508217D01*
G01Y508592D02*
X-1511440Y508921D01*
G01X-1563956Y503814D02*
X-1563912Y503863D01*
G01X-1538073Y507659D02*
X-1536855Y509048D01*
G01X-1538574Y507659D02*
X-1536855Y509633D01*
G01X-1559861Y499256D02*
X-1560338Y498689D01*
G01Y499337D02*
X-1559861Y499905D01*
G01X-1512129Y508076D02*
X-1512267Y507889D01*
G01X-1565334Y500802D02*
X-1565412Y500703D01*
G01X-1556133Y494342D02*
X-1556292Y494126D01*
G01X-1551478D02*
X-1551319Y494342D01*
G01X-1540590Y498526D02*
X-1540749Y498283D01*
G01X-1544495Y494828D02*
X-1544600Y494666D01*
G01X-1542734Y499256D02*
X-1542893Y499013D01*
G01X-1550420Y494666D02*
X-1550314Y494828D01*
G01X-1563544Y506781D02*
X-1563687Y506562D01*
G01X-1563616Y508390D02*
X-1563759Y508171D01*
G01X-1565477Y509048D02*
X-1565621Y508829D01*
G01X-1540168Y500928D02*
X-1540849Y499747D01*
G01X-1557884Y500928D02*
X-1558566Y499747D01*
G01X-1564189Y506269D02*
X-1564475Y506196D01*
G01X-1565411Y500705D02*
X-1565460Y500618D01*
G01X-1541146Y498526D02*
X-1540987Y498851D01*
G01X-1544918Y494720D02*
X-1544812Y494936D01*
G01X-1550737Y494720D02*
X-1550631Y494936D01*
G01X-1563902Y506854D02*
X-1563831Y507001D01*
G01X-1564045Y508390D02*
X-1563902Y508683D01*
G01X-1541145Y495894D02*
X-1543029Y495527D01*
G01X-1542984Y495295D02*
X-1541145Y495653D01*
G01X-1564905Y509268D02*
X-1565263Y509194D01*
G01X-1564547Y506562D02*
X-1564189Y506635D01*
G01X-1512451Y507748D02*
X-1512680Y507701D01*
G01X-1542099Y499499D02*
X-1542496Y499418D01*
G01X-1550208Y495260D02*
X-1549944Y495314D01*
G01X-1556504Y493964D02*
X-1556768Y493910D01*
G01X-1544389Y495260D02*
X-1544124Y495314D01*
G01X-1549829Y496042D02*
X-1549228Y496165D01*
G01X-1536675Y503965D02*
X-1536828Y503934D01*
G01X-1550155Y494936D02*
X-1549944Y494990D01*
G01X-1544124D02*
X-1544336Y494936D01*
G01X-1541638Y495314D02*
X-1541849Y495260D01*
G01X-1547444Y495968D02*
X-1547562Y495653D01*
G01X-1512083Y508217D02*
X-1512129Y508076D01*
G01X-1512405Y508123D02*
X-1512359Y508264D01*
G01X-1542008Y494666D02*
X-1541955Y494828D01*
G01X-1550412Y495972D02*
X-1549802Y496046D01*
G01X-1565334Y509560D02*
X-1564833Y509633D01*
G01X-1542575Y499824D02*
X-1542019Y499905D01*
G01X-1551319Y494342D02*
X-1551266Y494504D01*
G01X-1551637Y494396D02*
X-1551584Y494558D01*
G01X-1556081Y494504D02*
X-1556133Y494342D01*
G01X-1556451Y494396D02*
X-1556398Y494558D01*
G01X-1563473Y507001D02*
X-1563544Y506781D01*
G01X-1540511Y498851D02*
X-1540590Y498526D01*
G01X-1542273Y494936D02*
X-1542326Y494720D01*
G01X-1543290Y499013D02*
X-1543210Y499337D01*
G01X-1544600Y494666D02*
X-1544653Y494450D01*
G01X-1516657Y523566D02*
X-1518231D01*
G01X-1516657Y522385D02*
X-1518231D01*
G01X-1516657Y519039D02*
X-1520397D01*
G01X-1518231Y518842D02*
X-1516657D01*
G01X-1518377Y518403D02*
X-1516893D01*
G01X-1516657Y517661D02*
X-1518231D01*
G01X-1518377Y516918D02*
X-1516893D01*
G01X-1516657Y516283D02*
X-1520397D01*
G01X-1518231Y515102D02*
X-1516657D01*
G01X-1518231Y513758D02*
X-1516657D01*
G01X-1565475Y513724D02*
X-1563901D01*
G01X-1536342D02*
X-1537916D01*
G01X-1563901Y513519D02*
X-1565475D01*
G01X-1536342D02*
X-1537916D01*
G01X-1518231Y513133D02*
X-1516657D01*
G01X-1565475Y512543D02*
X-1563901D01*
G01X-1536342D02*
X-1537916D01*
G01X-1507601Y512346D02*
X-1515082D01*
G01X-1565475Y512338D02*
X-1563901D01*
G01X-1536342D02*
X-1537916D01*
G01X-1510357Y511362D02*
X-1515082D01*
G01X-1518231Y511165D02*
X-1516657D01*
G01X-1490653Y510771D02*
X-1516676D01*
G01X-1518231Y510062D02*
X-1516657D01*
G01X-1536855Y509633D02*
X-1536426D01*
G01X-1564833D02*
X-1564690D01*
G01X-1511145Y509590D02*
X-1513901D01*
G01X-1511145Y509324D02*
X-1513901D01*
G01X-1564618Y509268D02*
X-1564905D01*
G01X-1563901Y508991D02*
X-1565475D01*
G01X-1536342D02*
X-1537916D01*
G01X-1511440Y508921D02*
X-1511164D01*
G01X-1513783D02*
X-1512680D01*
G01X-1565621Y508829D02*
X-1565979D01*
G01X-1512634Y508686D02*
X-1513507D01*
G01X-1511145Y508475D02*
X-1513901D01*
G01X-1511145Y508409D02*
X-1513901D01*
G01X-1537916Y508374D02*
X-1536342D01*
G01X-1563901D02*
X-1565475D01*
G01X-1511145Y508342D02*
X-1513901D01*
G01X-1564905Y508098D02*
X-1564618D01*
G01X-1513507Y507982D02*
X-1512634D01*
G01X-1564618Y507805D02*
X-1564905D01*
G01X-1512680Y507701D02*
X-1513507D01*
G01X-1536426Y507659D02*
X-1535710D01*
G01X-1536855D02*
X-1538073D01*
G01X-1563901Y507613D02*
X-1565475D01*
G01X-1536342D02*
X-1537916D01*
G01X-1511145Y507494D02*
X-1513901D01*
G01X-1511145Y507228D02*
X-1513901D01*
G01X-1535710Y507220D02*
X-1536426D01*
G01X-1536855D02*
X-1538574D01*
G01X-1566050Y507001D02*
X-1565692D01*
G01X-1516657Y506913D02*
X-1518231D01*
G01X-1537916Y506853D02*
X-1536342D01*
G01X-1565475D02*
X-1563901D01*
G01X-1513507Y506716D02*
X-1513783D01*
G01X-1511164D02*
X-1511440D01*
G01X-1564976Y506562D02*
X-1564547D01*
G01X-1537916Y506235D02*
X-1536342D01*
G01X-1563901D02*
X-1565475D01*
G01X-1564475Y506196D02*
X-1565048D01*
G01X-1536426D02*
X-1536855D01*
G01X-1563901Y504067D02*
X-1562326D01*
G01X-1537916D02*
X-1539491D01*
G01X-1565475Y503676D02*
X-1563901D01*
G01X-1536342D02*
X-1537916D01*
G01X-1536828Y503423D02*
X-1536342D01*
G01X-1564989D02*
X-1565475D01*
G01X-1537430Y503392D02*
X-1537916D01*
G01Y503110D02*
X-1536342D01*
G01X-1565475D02*
X-1563901D01*
G01X-1518231Y502680D02*
X-1516657D01*
G01X-1562405Y502503D02*
X-1554924D01*
G01X-1539570D02*
X-1547050D01*
G01Y501716D02*
X-1554924D01*
G01X-1557680Y501519D02*
X-1562405D01*
G01X-1539570D02*
X-1544294D01*
G01X-1516657Y501499D02*
X-1518231D01*
G01X-1547738Y501440D02*
X-1554236D01*
G01X-1565475Y501117D02*
X-1563901D01*
G01X-1536342D02*
X-1537916D01*
G01X-1538783Y500928D02*
X-1563192D01*
G01Y500802D02*
X-1565334D01*
G01X-1536483D02*
X-1538783D01*
G01X-1563932Y500015D02*
X-1564412D01*
G01D02*
X-1563932D01*
G01X-1537405D02*
X-1536342D01*
G01X-1564412D02*
X-1565475D01*
G01X-1563901D02*
X-1564412D01*
G01X-1537405D02*
X-1537916D01*
G01X-1537405D02*
X-1537885D01*
G01X-1542019Y499905D02*
X-1541702D01*
G01X-1559861D02*
X-1559385D01*
G01X-1558566Y499747D02*
X-1561125D01*
G01X-1540849D02*
X-1543409D01*
G01X-1518231Y499531D02*
X-1516657D01*
G01X-1541781Y499499D02*
X-1542099D01*
G01X-1543409Y499401D02*
X-1540849D01*
G01X-1558566D02*
X-1561125D01*
G01X-1491460Y499354D02*
X-1515869D01*
G01X-1542893Y499013D02*
X-1543290D01*
G01X-1548231Y498645D02*
X-1553743D01*
G01X-1558566Y498566D02*
X-1561125D01*
G01X-1540849D02*
X-1543409D01*
G01Y498560D02*
X-1540849D01*
G01X-1558566D02*
X-1561125D01*
G01X-1491460Y497779D02*
X-1515869D01*
G01X-1543409Y497725D02*
X-1540849D01*
G01X-1558566D02*
X-1561125D01*
G01X-1543409Y497379D02*
X-1540849D01*
G01X-1558566D02*
X-1561125D01*
G01X-1556499Y496913D02*
X-1561617D01*
G01X-1540357D02*
X-1545475D01*
G01X-1537916Y496865D02*
X-1536342D01*
G01X-1563901D02*
X-1565475D01*
G01X-1542734Y496499D02*
X-1540511D01*
G01X-1563904Y500015D02*
X-1563915Y500014D01*
G01X-1551001Y495949D02*
X-1550386Y495974D01*
G01X-1536828Y503934D02*
X-1537430Y503904D01*
G01X-1536828Y503423D02*
X-1537430Y503392D01*
G01X-1563904Y500015D02*
X-1563901D01*
G01X-1550473Y494450D02*
X-1550420Y494666D01*
G01X-1563544Y508683D02*
X-1563616Y508390D01*
G01X-1565979Y508829D02*
X-1565907Y509121D01*
G01X-1565459Y500620D02*
X-1565475Y500546D01*
G01X-1544971Y494450D02*
X-1544918Y494720D01*
G01X-1550790Y494450D02*
X-1550737Y494720D01*
G01X-1547690Y501716D02*
X-1548231Y498645D01*
G01X-1563900Y503879D02*
X-1564989Y503934D01*
G01X-1564387Y503392D02*
X-1564989Y503423D01*
G01X-1551589Y495974D02*
X-1550974Y495949D01*
G01X-1563932Y500015D02*
X-1563915Y500014D01*
G01X-1545869Y496204D02*
X-1556105D01*
G01X-1509767D02*
X-1514491D01*
G01X-1552814Y496165D02*
X-1549160D01*
G01X-1559385Y496094D02*
X-1559861D01*
G01X-1540511D02*
X-1543369D01*
G01X-1542396Y495968D02*
X-1559578D01*
G01X-1544193Y495894D02*
X-1545420Y495893D01*
G01X-1548231Y495894D02*
X-1541145D01*
G01X-1551775D02*
X-1560830D01*
G01X-1548231D02*
X-1550200D01*
G01X-1548231Y495889D02*
X-1553743D01*
G01X-1547562Y495653D02*
X-1541145D01*
G01X-1554412D02*
X-1560830D01*
G01X-1547562D02*
X-1554412D01*
G01X-1543029Y495527D02*
X-1558946D01*
G01X-1558378Y495449D02*
X-1543597D01*
G01X-1544124Y495314D02*
X-1543648D01*
G01X-1545711D02*
X-1545394D01*
G01X-1548251D02*
X-1547775D01*
G01X-1546452D02*
X-1546135D01*
G01X-1549944D02*
X-1549520D01*
G01X-1555657D02*
X-1553647D01*
G01X-1558038D02*
X-1556768D01*
G01X-1558779D02*
X-1558461D01*
G01X-1561318D02*
X-1560048D01*
G01X-1551954D02*
X-1553224D01*
G01X-1541373D02*
X-1541638D01*
G01X-1542984Y495295D02*
X-1558991D01*
G01X-1558397Y495213D02*
X-1543577D01*
G01X-1556715Y495044D02*
X-1557721D01*
G01X-1551901D02*
X-1552906D01*
G01X-1553647D02*
X-1554493D01*
G01X-1554811D02*
X-1555657D01*
G01X-1541638Y494990D02*
X-1541320D01*
G01X-1549944D02*
X-1549520D01*
G01X-1561001D02*
X-1560048D01*
G01X-1543648D02*
X-1544124D01*
G01X-1541003Y494720D02*
X-1540686D01*
G01X-1542908Y494666D02*
X-1543225D01*
G01X-1549924Y494629D02*
X-1551893D01*
G01X-1552906Y494234D02*
X-1551901D01*
G01X-1557721D02*
X-1556715D01*
G01X-1541320D02*
X-1541638D01*
G01Y493910D02*
X-1541320D01*
G01X-1552906D02*
X-1552007D01*
G01X-1556768D02*
X-1557721D01*
G01X-1546779Y495894D02*
X-1548231Y495892D01*
G01X-1511440Y506716D02*
Y508545D01*
G01X-1511716Y508217D02*
Y508592D01*
G01X-1511735Y508409D02*
Y507228D01*
G01X-1512083Y508405D02*
Y508217D01*
G01X-1512359Y508264D02*
Y508405D01*
G01X-1513310Y508409D02*
Y507228D01*
G01X-1513507Y508686D02*
Y507982D01*
G01Y507701D02*
Y506716D01*
G01X-1513704Y499354D02*
Y497779D01*
G01X-1513783Y506716D02*
Y508921D01*
G01X-1513901Y507228D02*
Y509590D01*
G01X-1514491Y496204D02*
Y497779D01*
G01X-1514688Y510771D02*
Y499354D01*
G01X-1515082Y510771D02*
Y512346D01*
G01X-1515101Y512622D02*
Y510771D01*
G01X-1515279Y499354D02*
Y497779D01*
G01X-1515869Y510771D02*
Y499354D01*
G01X-1516657Y499531D02*
Y523566D01*
G01X-1516676Y512622D02*
Y510771D01*
G01X-1516736Y516283D02*
Y519039D01*
G01X-1518231Y499531D02*
Y523566D01*
G01X-1518233Y516283D02*
Y519039D01*
G01X-1518754D02*
Y516283D01*
G01X-1518764D02*
Y519039D01*
G01X-1518822D02*
Y516283D01*
G01X-1520238Y519039D02*
Y516283D01*
G01X-1520261D02*
Y519039D01*
G01X-1520397D02*
Y516283D01*
G01X-1552146Y496042D02*
X-1552747Y496165D01*
G01X-1512680Y508921D02*
X-1512451Y508874D01*
G01X-1564260Y509194D02*
X-1564618Y509268D01*
G01X-1565334Y506635D02*
X-1564976Y506562D01*
G01X-1541384Y499418D02*
X-1541781Y499499D01*
G01X-1541109Y495260D02*
X-1541373Y495314D01*
G01X-1543648D02*
X-1543384Y495260D01*
G01X-1541056Y494180D02*
X-1541320Y494234D01*
G01X-1549520Y495314D02*
X-1549256Y495260D01*
G01X-1551690D02*
X-1551954Y495314D01*
G01X-1556768D02*
X-1556504Y495260D01*
G01X-1560048Y495314D02*
X-1559784Y495260D01*
G01X-1558946Y495527D02*
X-1560830Y495894D01*
G01X-1558991Y495295D02*
X-1560830Y495653D01*
G01X-1564189Y507732D02*
X-1564618Y507805D01*
G01X-1541702Y499905D02*
X-1541225Y499824D01*
G01X-1564690Y509633D02*
X-1564189Y509560D01*
G01X-1552172Y496046D02*
X-1551562Y495972D01*
G01X-1538343Y505425D02*
Y505399D01*
G01X-1538342Y505316D02*
X-1538343Y505187D01*
G01X-1538341Y504798D02*
X-1538343Y504285D01*
G01X-1537440Y503792D02*
Y503710D01*
G01X-1535710Y507659D02*
Y507220D01*
G01X-1536342Y504445D02*
Y512338D01*
G01Y513724D02*
Y512338D01*
G01Y503423D02*
Y504445D01*
G01X-1536426Y507220D02*
Y506196D01*
G01Y509633D02*
Y507659D01*
G01X-1536828Y500802D02*
Y503423D01*
G01X-1536855Y506196D02*
Y507220D01*
G01Y509048D02*
Y507659D01*
G01X-1537430Y503392D02*
Y500802D01*
G01X-1537916Y513724D02*
Y512338D01*
G01X-1538343Y504285D02*
Y505425D01*
G01Y500802D02*
Y504067D01*
G01Y505408D02*
Y504067D01*
G01X-1538574Y507220D02*
Y507659D01*
G01X-1539491Y504067D02*
Y500928D01*
G01X-1539570Y502503D02*
Y500928D01*
G01X-1540357Y500600D02*
Y496913D01*
G01X-1540511Y499013D02*
Y498851D01*
G01Y496499D02*
Y496094D01*
G01X-1540849Y497379D02*
Y499747D01*
G01X-1540987Y498851D02*
Y499013D01*
G01X-1541145Y495894D02*
Y495653D01*
G01X-1542008Y494558D02*
Y494666D01*
G01X-1542326Y494720D02*
Y494504D01*
G01X-1542396Y496913D02*
Y495968D01*
G01X-1543369Y496094D02*
Y496499D01*
G01X-1543409Y499747D02*
Y497379D01*
G01X-1544294Y502503D02*
Y501519D01*
G01X-1545082Y502503D02*
Y500928D01*
G01X-1545475Y496913D02*
Y495968D01*
G01X-1547050Y502503D02*
Y501716D01*
G01X-1548231Y495653D02*
Y495894D01*
G01X-1550200D02*
Y495653D01*
G01X-1550987Y495295D02*
Y495213D01*
G01X-1551266Y494504D02*
Y494720D01*
G01X-1551584Y494558D02*
Y494720D01*
G01X-1551775Y495653D02*
Y495894D01*
G01X-1552906Y495044D02*
Y494234D01*
G01X-1553647Y495314D02*
Y495044D01*
G01X-1553743Y495894D02*
Y495653D01*
G01X-1554924Y501716D02*
Y502503D01*
G01X-1555657Y495044D02*
Y495314D01*
G01X-1556081Y494720D02*
Y494504D01*
G01X-1556398Y494558D02*
Y494720D01*
G01X-1556499Y496913D02*
Y495968D01*
G01X-1556893Y502503D02*
Y500928D01*
G01X-1557680Y502503D02*
Y501519D01*
G01X-1557721Y495044D02*
Y494234D01*
G01X-1558566Y497379D02*
Y499747D01*
G01X-1559385Y499905D02*
Y496094D01*
G01X-1559578Y496913D02*
Y495968D01*
G01X-1559861Y496094D02*
Y499256D01*
G01X-1560338Y498689D02*
Y499337D01*
G01X-1560830Y495894D02*
Y495653D01*
G01X-1561125Y499747D02*
Y497379D01*
G01X-1561617Y500600D02*
Y496913D01*
G01X-1562326Y504067D02*
Y501519D01*
G01X-1562405Y502503D02*
Y500928D01*
G01X-1563473Y507293D02*
Y507001D01*
G01X-1563474Y505027D02*
Y500802D01*
G01Y505027D02*
Y505425D01*
G01D02*
Y505027D01*
G01X-1563544Y508829D02*
Y508683D01*
G01X-1563831Y507001D02*
Y507293D01*
G01X-1563901Y513724D02*
Y512338D01*
G01X-1563902Y508683D02*
Y508829D01*
G01X-1564387Y503392D02*
Y500802D01*
G01X-1564905Y507805D02*
Y508098D01*
G01X-1564989Y503423D02*
Y500802D01*
G01X-1565475Y504445D02*
Y512338D01*
G01Y504445D02*
Y503423D01*
G01Y513724D02*
Y512338D01*
G01X-1538343Y505006D02*
X-1538341Y504798D01*
G01X-1538342Y505334D02*
X-1538343Y505408D01*
G01X-1537440Y503712D02*
X-1537439Y503613D01*
G01X-1537430Y503392D02*
X-1537435Y503506D01*
G01X-1562354Y504263D02*
X-1562326Y504067D01*
G01X-1556650Y496819D02*
X-1556667Y496913D01*
G01X-1554285Y501716D02*
X-1553743Y498645D01*
G01X-1542960Y494936D02*
X-1542908Y494666D01*
G01X-1548727Y494720D02*
X-1548674Y494450D01*
G01X-1536358Y500620D02*
X-1536342Y500546D01*
G01X-1512129Y508545D02*
X-1512083Y508405D01*
G01X-1512359D02*
X-1512405Y508545D01*
G01X-1512496Y508639D02*
X-1512634Y508686D01*
G01X-1541320Y494990D02*
X-1541162Y494936D01*
G01X-1541638Y494234D02*
X-1541797Y494288D01*
G01X-1551742Y494990D02*
X-1551901Y495044D01*
G01X-1556557Y494990D02*
X-1556715Y495044D01*
G01X-1565048Y506196D02*
X-1565334Y506269D01*
G01X-1543437Y494936D02*
X-1543648Y494990D01*
G01X-1541849Y493964D02*
X-1541638Y493910D01*
G01X-1549520Y494990D02*
X-1549309Y494936D01*
G01X-1560048Y494990D02*
X-1559837Y494936D01*
G01X-1559255Y494720D02*
X-1559202Y494450D01*
G01X-1556651Y496825D02*
X-1556629Y496729D01*
G01X-1540590Y499337D02*
X-1540511Y499013D01*
G01X-1542326Y494504D02*
X-1542273Y494288D01*
G01X-1549044Y494666D02*
X-1548991Y494450D01*
G01X-1559572Y494666D02*
X-1559519Y494450D01*
G01X-1563616Y509121D02*
X-1563544Y508829D01*
G01Y507586D02*
X-1563473Y507293D01*
G01X-1556630Y496735D02*
X-1556604Y496646D01*
G01X-1540686Y494720D02*
X-1540738Y494882D01*
G01X-1541955Y494396D02*
X-1542008Y494558D01*
G01X-1543225Y494666D02*
X-1543278Y494828D01*
G01X-1551266Y494720D02*
X-1551319Y494882D01*
G01X-1551584Y494720D02*
X-1551637Y494882D01*
G01X-1556133D02*
X-1556081Y494720D01*
G01X-1556398D02*
X-1556451Y494882D01*
G01X-1512267Y508733D02*
X-1512129Y508545D01*
G01X-1512405D02*
X-1512496Y508639D01*
G01X-1516893Y518403D02*
X-1517691Y519039D01*
G01X-1519175D02*
X-1518377Y518403D01*
G01X-1512451Y508874D02*
X-1512267Y508733D01*
G01X-1541225Y499824D02*
X-1540908Y499662D01*
G01X-1564189Y509560D02*
X-1563902Y509414D01*
G01X-1565477Y506708D02*
X-1565334Y506635D01*
G01X-1540844Y494072D02*
X-1541056Y494180D01*
G01X-1543384Y495260D02*
X-1543172Y495152D01*
G01X-1565334Y506269D02*
X-1565621Y506416D01*
G01X-1542061Y494072D02*
X-1541849Y493964D01*
G01X-1549256Y495260D02*
X-1549044Y495152D01*
G01X-1559784Y495260D02*
X-1559572Y495152D01*
G01X-1564045Y507951D02*
X-1563687Y507805D01*
G01X-1565979Y506781D02*
X-1566050Y507001D01*
G01X-1556604Y496647D02*
X-1556573Y496562D01*
G01X-1554531Y495968D02*
X-1554412Y495653D01*
G01X-1556575Y496567D02*
X-1556537Y496481D01*
G01X-1541056Y494828D02*
X-1541003Y494720D01*
G01X-1548833Y494936D02*
X-1548727Y494720D01*
G01X-1563831Y507293D02*
X-1563974Y507586D01*
G01X-1559361Y494936D02*
X-1559255Y494720D01*
G01X-1565692Y507001D02*
X-1565621Y506854D01*
G01X-1556540Y496486D02*
X-1556499Y496409D01*
G01X-1536406Y500705D02*
X-1536357Y500618D01*
G01X-1544090Y500928D02*
X-1543409Y499747D01*
G01X-1561807Y500928D02*
X-1561125Y499747D01*
G01X-1540987Y499013D02*
X-1541146Y499256D01*
G01X-1549150Y494828D02*
X-1549044Y494666D01*
G01X-1563902Y508829D02*
X-1564045Y509048D01*
G01X-1563687Y507805D02*
X-1563544Y507586D01*
G01X-1565835Y506562D02*
X-1565979Y506781D01*
G01X-1559678Y494828D02*
X-1559572Y494666D01*
G01X-1540738Y494882D02*
X-1540897Y495098D01*
G01X-1551319Y494882D02*
X-1551478Y495098D01*
G01X-1556292D02*
X-1556133Y494882D01*
G01X-1536483Y500802D02*
X-1536405Y500703D01*
G01X-1540908Y499662D02*
X-1540590Y499337D01*
G01X-1541162Y494936D02*
X-1541056Y494828D01*
G01X-1542273Y494288D02*
X-1542061Y494072D01*
G01X-1543172Y495152D02*
X-1542960Y494936D01*
G01X-1549044Y495152D02*
X-1548833Y494936D01*
G01X-1563902Y509414D02*
X-1563616Y509121D01*
G01X-1551637Y494882D02*
X-1551742Y494990D01*
G01X-1565621Y506854D02*
X-1565477Y506708D01*
G01X-1556451Y494882D02*
X-1556557Y494990D01*
G01X-1559572Y495152D02*
X-1559361Y494936D01*
G01X-1539112Y505016D02*
X-1538343Y504285D01*
G01X-1540897Y495098D02*
X-1541109Y495260D01*
G01X-1551478Y495098D02*
X-1551690Y495260D01*
G01X-1556504D02*
X-1556292Y495098D01*
G01X-1541146Y499256D02*
X-1541384Y499418D01*
G01X-1541797Y494288D02*
X-1541955Y494396D01*
G01X-1564045Y509048D02*
X-1564260Y509194D01*
G01X-1543278Y494828D02*
X-1543437Y494936D01*
G01X-1563974Y507586D02*
X-1564189Y507732D01*
G01X-1565621Y506416D02*
X-1565835Y506562D01*
G01X-1549309Y494936D02*
X-1549150Y494828D01*
G01X-1559837Y494936D02*
X-1559678Y494828D01*
G01X-1513812Y622734D02*
X-1513074Y622986D01*
G01X-1517011Y621981D02*
X-1517749Y621729D01*
G01X-1535958Y616201D02*
X-1535220Y616452D01*
G01X-1517749Y622734D02*
X-1517011Y622986D01*
G01X-1524885Y622734D02*
X-1524147Y622986D01*
G01X-1528084Y621981D02*
X-1528822Y621729D01*
G01Y622734D02*
X-1528084Y622986D01*
G01X-1537680Y621227D02*
X-1538418Y620975D01*
G01Y625247D02*
X-1537680Y625499D01*
G01X-1513320Y621981D02*
X-1513812Y621729D01*
G01X-1524393Y621981D02*
X-1524885Y621729D01*
G01X-1543340Y622734D02*
X-1546785Y620975D01*
G01X-1548507D02*
X-1543832Y623488D01*
G01X-1534973Y615196D02*
X-1533743Y615949D01*
G01X-1538664Y626504D02*
X-1539895Y625750D01*
G01X-1535220Y616452D02*
X-1534481Y616955D01*
G01X-1538418Y620975D02*
X-1539157Y620473D01*
G01X-1538664Y622232D02*
X-1540141Y621227D01*
G01X-1539157Y624745D02*
X-1538418Y625247D01*
G01X-1513812Y621729D02*
X-1514058Y621478D01*
G01X-1514550Y621981D02*
X-1513812Y622734D01*
G01X-1517749Y621729D02*
X-1518241Y621227D01*
G01Y622232D02*
X-1517749Y622734D01*
G01X-1537434Y626755D02*
X-1538664Y626504D01*
G01X-1537434Y622483D02*
X-1538664Y622232D01*
G01X-1536204Y614944D02*
X-1534973Y615196D01*
G01X-1524885Y621729D02*
X-1525131Y621478D01*
G01X-1525623Y621981D02*
X-1524885Y622734D01*
G01X-1528822Y621729D02*
X-1529314Y621227D01*
G01Y622232D02*
X-1528822Y622734D01*
G01X-1539157Y620473D02*
X-1539649Y619970D01*
G01X-1533743Y615949D02*
X-1533005Y616955D01*
G01X-1539895Y625750D02*
X-1540633Y624745D01*
G01X-1551952Y626755D02*
X-1550475D01*
G01X-1560318D02*
X-1558842D01*
G01X-1536450D02*
X-1537434D01*
G01X-1537680Y625499D02*
X-1536204D01*
G01X-1534235Y623991D02*
X-1533005D01*
G01X-1513074Y622986D02*
X-1512090D01*
G01X-1517011D02*
X-1516027D01*
G01X-1519472D02*
X-1518241D01*
G01X-1524147D02*
X-1523162D01*
G01X-1528084D02*
X-1527099D01*
G01X-1530544D02*
X-1529314D01*
G01X-1536204Y622483D02*
X-1537434D01*
G01X-1558842Y621981D02*
X-1551952D01*
G01X-1527592D02*
X-1528084D01*
G01X-1523655D02*
X-1524393D01*
G01X-1516519D02*
X-1517011D01*
G01X-1512582D02*
X-1513320D01*
G01X-1535958Y621227D02*
X-1537680D01*
G01X-1551952Y620473D02*
X-1558842D01*
G01X-1534481Y616955D02*
X-1533989Y617708D01*
G01X-1539649Y623991D02*
X-1539157Y624745D01*
G01X-1543340Y619216D02*
X-1543832Y618462D01*
G01X-1537680Y616201D02*
X-1535958D01*
G01X-1537434Y614944D02*
X-1536204D01*
G01X-1558842D02*
X-1560318D01*
G01X-1550475D02*
X-1551952D01*
G01X-1529314D02*
X-1530544D01*
G01X-1525377D02*
X-1526607D01*
G01X-1521440D02*
X-1522670D01*
G01X-1518241D02*
X-1519472D01*
G01X-1514304D02*
X-1515535D01*
G01X-1510367D02*
X-1511598D01*
G01X-1482011Y599354D02*
X-1576499D01*
G01X-1514058Y621478D02*
X-1514304Y620975D01*
G01X-1525131Y621478D02*
X-1525377Y620975D01*
G01X-1535220Y626504D02*
X-1536450Y626755D01*
G01X-1534973Y622232D02*
X-1536204Y622483D01*
G01X-1538664Y615196D02*
X-1537434Y614944D01*
G01X-1533005Y616955D02*
X-1532513Y618211D01*
G01X-1540633Y624745D02*
X-1541125Y623488D01*
G01X-1533989Y617708D02*
X-1533743Y618462D01*
G01X-1539649Y619970D02*
X-1539895Y619216D01*
G01Y623237D02*
X-1539649Y623991D01*
G01X-1512090Y622986D02*
X-1511351Y622734D01*
G01X-1516027Y622986D02*
X-1515288Y622734D01*
G01X-1523162Y622986D02*
X-1522424Y622734D01*
G01X-1527099Y622986D02*
X-1526361Y622734D01*
G01X-1536204Y625499D02*
X-1535466Y625247D01*
G01X-1535220Y620975D02*
X-1535958Y621227D01*
G01X-1538418Y616452D02*
X-1537680Y616201D01*
G01X-1512090Y621729D02*
X-1512582Y621981D01*
G01X-1516027Y621729D02*
X-1516519Y621981D01*
G01X-1523162Y621729D02*
X-1523655Y621981D01*
G01X-1527099Y621729D02*
X-1527592Y621981D01*
G01X-1546785Y620975D02*
X-1543340Y619216D01*
G01X-1540141Y621729D02*
X-1539895Y623237D01*
G01X-1541125Y623488D02*
X-1541371Y621729D01*
G01X-1511598Y614944D02*
Y620975D01*
G01X-1514304D02*
Y614944D01*
G01X-1515535D02*
Y620975D01*
G01X-1518241Y621227D02*
Y614944D01*
G01Y622986D02*
Y622232D01*
G01X-1519472Y614944D02*
Y622986D01*
G01X-1521440Y620975D02*
Y614944D01*
G01X-1522670D02*
Y620975D01*
G01X-1525377D02*
Y614944D01*
G01X-1526607D02*
Y620975D01*
G01X-1529314Y621227D02*
Y614944D01*
G01Y622986D02*
Y622232D01*
G01X-1530544Y614944D02*
Y622986D01*
G01X-1541371Y619970D02*
X-1541125Y618211D01*
G01X-1511351Y622734D02*
X-1510859Y622232D01*
G01X-1511844Y621478D02*
X-1512090Y621729D01*
G01X-1515288Y622734D02*
X-1514550Y621981D01*
G01X-1515781Y621478D02*
X-1516027Y621729D01*
G01X-1535466Y625247D02*
X-1534727Y624745D01*
G01X-1534481Y620473D02*
X-1535220Y620975D01*
G01X-1539157Y616955D02*
X-1538418Y616452D01*
G01X-1533989Y625750D02*
X-1535220Y626504D01*
G01X-1533743Y621478D02*
X-1534973Y622232D01*
G01X-1539895Y615949D02*
X-1538664Y615196D01*
G01X-1543832Y618462D02*
X-1548507Y620975D01*
G01X-1532513Y618211D02*
Y619468D01*
G01X-1533743Y618462D02*
Y619216D01*
G01X-1539895D02*
Y618462D01*
G01X-1540141Y621227D02*
Y621729D01*
G01X-1541371D02*
Y619970D01*
G01X-1550475Y626755D02*
Y614944D01*
G01X-1551952Y621981D02*
Y626755D01*
G01Y614944D02*
Y620473D01*
G01X-1558842D02*
Y614944D01*
G01Y626755D02*
Y621981D01*
G01X-1560318Y614944D02*
Y626755D01*
G01X-1533005Y623991D02*
X-1533251Y624745D01*
G01X-1533743Y619216D02*
X-1533989Y619970D01*
G01X-1539895Y618462D02*
X-1539649Y617708D01*
G01X-1521932Y622232D02*
X-1521440Y620975D01*
G01X-1532513Y619468D02*
X-1533005Y620724D01*
G01X-1541125Y618211D02*
X-1540633Y616955D01*
G01X-1511598Y620975D02*
X-1511844Y621478D01*
G01X-1515535Y620975D02*
X-1515781Y621478D01*
G01X-1522670Y620975D02*
X-1522916Y621478D01*
G01X-1526607Y620975D02*
X-1526853Y621478D01*
G01X-1534727Y624745D02*
X-1534235Y623991D01*
G01X-1539649Y617708D02*
X-1539157Y616955D01*
G01X-1543832Y623488D02*
X-1543340Y622734D01*
G01X-1533251Y624745D02*
X-1533989Y625750D01*
G01X-1540633Y616955D02*
X-1539895Y615949D01*
G01X-1522424Y622734D02*
X-1521932Y622232D01*
G01X-1522916Y621478D02*
X-1523162Y621729D01*
G01X-1526361Y622734D02*
X-1525623Y621981D01*
G01X-1526853Y621478D02*
X-1527099Y621729D01*
G01X-1533005Y620724D02*
X-1533743Y621478D01*
G01X-1533989Y619970D02*
X-1534481Y620473D01*
G01X-1576499Y599354D02*
Y646598D01*
G01X-1515082Y718448D02*
G03Y705062I0J-6693D01*
G01X-1492867Y701910D02*
G03I-22487J0D01*
G01X-1512237Y679494D02*
X-1513074Y679209D01*
G01Y680348D02*
X-1512237Y680633D01*
G01X-1521161Y680348D02*
X-1520325Y680633D01*
G01X-1524786Y679494D02*
X-1525623Y679209D01*
G01Y680348D02*
X-1524786Y680633D01*
G01X-1535541Y701202D02*
X-1535295Y701286D01*
G01X-1536607Y700951D02*
X-1536853Y700867D01*
G01Y701202D02*
X-1536607Y701286D01*
G01X-1539232Y701202D02*
X-1538986Y701286D01*
G01X-1540298Y700951D02*
X-1540544Y700867D01*
G01Y701202D02*
X-1540298Y701286D01*
G01X-1520603Y679494D02*
X-1521161Y679209D01*
G01X-1543251Y702124D02*
X-1543661Y702040D01*
G01X-1543251Y699024D02*
X-1542841Y699108D01*
G01X-1535377Y700951D02*
X-1535541Y700867D01*
G01X-1539068Y700951D02*
X-1539232Y700867D01*
G01X-1533153Y671804D02*
X-1531758Y672658D01*
G01X-1536499Y684620D02*
X-1537893Y683766D01*
G01X-1543251Y702543D02*
X-1543743Y702459D01*
G01X-1543251Y698606D02*
X-1542759Y698689D01*
G01X-1534826Y684905D02*
X-1536499Y684620D01*
G01X-1534826Y671519D02*
X-1533153Y671804D01*
G01X-1534826Y683481D02*
X-1536220Y683196D01*
G01X-1534826Y672943D02*
X-1533431Y673228D01*
G01X-1542759Y698689D02*
X-1542349Y698941D01*
G01X-1543743Y702459D02*
X-1544153Y702208D01*
G01X-1533431Y673228D02*
X-1532595Y673797D01*
G01X-1536220Y683196D02*
X-1537057Y682626D01*
G01X-1542841Y699108D02*
X-1542595Y699276D01*
G01X-1543661Y702040D02*
X-1543907Y701873D01*
G01X-1501696Y705062D02*
X-1515082D01*
G01X-1547844Y702543D02*
X-1547352D01*
G01X-1550633D02*
X-1550141D01*
G01X-1535295Y701286D02*
X-1534967D01*
G01X-1536607D02*
X-1536279D01*
G01X-1537428D02*
X-1537017D01*
G01X-1538986D02*
X-1538658D01*
G01X-1540298D02*
X-1539970D01*
G01X-1541118D02*
X-1540708D01*
G01X-1546696D02*
X-1545384D01*
G01X-1550141Y700951D02*
X-1547844D01*
G01X-1545384D02*
X-1546696D01*
G01X-1540134D02*
X-1540298D01*
G01X-1536443D02*
X-1536607D01*
G01X-1538822D02*
X-1539068D01*
G01X-1535131D02*
X-1535377D01*
G01X-1547844Y700448D02*
X-1550141D01*
G01X-1546696Y700281D02*
X-1545384D01*
G01Y699946D02*
X-1546696D01*
G01X-1550141Y698606D02*
X-1550633D01*
G01X-1547352D02*
X-1547844D01*
G01X-1539396D02*
X-1539806D01*
G01X-1540708D02*
X-1541118D01*
G01X-1535705D02*
X-1536115D01*
G01X-1537017D02*
X-1537428D01*
G01X-1538084D02*
X-1538494D01*
G01X-1534393D02*
X-1534803D01*
G01X-1513074Y679209D02*
X-1513632Y678639D01*
G01Y679778D02*
X-1513074Y680348D01*
G01X-1521161Y679209D02*
X-1521440Y678924D01*
G01X-1571775Y693054D02*
X-1508389D01*
G01X-1550443Y684905D02*
X-1548769D01*
G01X-1559924D02*
X-1558251D01*
G01X-1512237Y680633D02*
X-1511122D01*
G01X-1515026D02*
X-1513632D01*
G01X-1520325D02*
X-1519209D01*
G01X-1524786D02*
X-1523671D01*
G01X-1527575D02*
X-1526181D01*
G01X-1546538D02*
X-1542077D01*
G01X-1558251Y679494D02*
X-1550443D01*
G01X-1542077D02*
X-1546538D01*
G01X-1524229D02*
X-1524786D01*
G01X-1519767D02*
X-1520603D01*
G01X-1511680D02*
X-1512237D01*
G01X-1550443Y677785D02*
X-1558251D01*
G01X-1546538Y677215D02*
X-1542077D01*
G01Y676076D02*
X-1546538D01*
G01X-1558251Y671519D02*
X-1559924D01*
G01X-1548769D02*
X-1550443D01*
G01X-1526181D02*
X-1527575D01*
G01X-1521719D02*
X-1523113D01*
G01X-1517257D02*
X-1518651D01*
G01X-1513632D02*
X-1515026D01*
G01X-1477956Y664708D02*
X-1571775D01*
G01X-1521998Y679494D02*
X-1521161Y680348D01*
G01X-1531758Y672658D02*
X-1530922Y673513D01*
G01X-1525623Y679209D02*
X-1526181Y678639D01*
G01Y679778D02*
X-1525623Y680348D01*
G01X-1537893Y683766D02*
X-1538730Y682911D01*
G01X-1535541Y700867D02*
X-1535623Y700784D01*
G01X-1535787Y700951D02*
X-1535541Y701202D01*
G01X-1536853Y700867D02*
X-1537017Y700700D01*
G01Y701035D02*
X-1536853Y701202D01*
G01X-1539232Y700867D02*
X-1539314Y700784D01*
G01X-1539478Y700951D02*
X-1539232Y701202D01*
G01X-1542349Y698941D02*
X-1542103Y699192D01*
G01X-1540544Y700867D02*
X-1540708Y700700D01*
G01Y701035D02*
X-1540544Y701202D01*
G01X-1544153Y702208D02*
X-1544399Y701956D01*
G01X-1542841Y702040D02*
X-1543251Y702124D01*
G01X-1543661Y699108D02*
X-1543251Y699024D01*
G01X-1542759Y702459D02*
X-1543251Y702543D01*
G01X-1543743Y698689D02*
X-1543251Y698606D01*
G01X-1533153Y684620D02*
X-1534826Y684905D01*
G01X-1576499Y646598D02*
X-1482011D01*
G01X-1532595Y673797D02*
X-1531479Y675506D01*
G01X-1534967Y701286D02*
X-1534721Y701202D01*
G01X-1536279Y701286D02*
X-1536033Y701202D01*
G01X-1538658Y701286D02*
X-1538412Y701202D01*
G01X-1539970Y701286D02*
X-1539724Y701202D01*
G01X-1533431Y683196D02*
X-1534826Y683481D01*
G01X-1536220Y673228D02*
X-1534826Y672943D01*
G01X-1536499Y671804D02*
X-1534826Y671519D01*
G01X-1537057Y682626D02*
X-1538172Y680918D01*
G01X-1542595Y699276D02*
X-1542267Y699778D01*
G01X-1543907Y701873D02*
X-1544235Y701370D01*
G01X-1521440Y678924D02*
X-1521719Y678354D01*
G01X-1519209Y680633D02*
X-1518372Y680348D01*
G01X-1523671Y680633D02*
X-1522834Y680348D01*
G01X-1530922Y673513D02*
X-1530364Y674652D01*
G01X-1538730Y682911D02*
X-1539288Y681772D01*
G01X-1535623Y700784D02*
X-1535705Y700616D01*
G01X-1539314Y700784D02*
X-1539396Y700616D01*
G01X-1542103Y699192D02*
X-1541939Y699527D01*
G01X-1544399Y701956D02*
X-1544563Y701621D01*
G01X-1542595Y701873D02*
X-1542841Y702040D01*
G01X-1542349Y702208D02*
X-1542759Y702459D01*
G01X-1544153Y698941D02*
X-1543743Y698689D01*
G01X-1531758Y683766D02*
X-1533153Y684620D01*
G01X-1534967Y700867D02*
X-1535131Y700951D01*
G01X-1536279Y700867D02*
X-1536443Y700951D01*
G01X-1538658Y700867D02*
X-1538822Y700951D01*
G01X-1539970Y700867D02*
X-1540134Y700951D01*
G01X-1511122Y679209D02*
X-1511680Y679494D01*
G01X-1519209Y679209D02*
X-1519767Y679494D01*
G01X-1523671Y679209D02*
X-1524229Y679494D01*
G01X-1530364Y674652D02*
X-1530085Y675506D01*
G01X-1539288Y681772D02*
X-1539567Y680918D01*
G01X-1541939Y699527D02*
X-1541857Y699778D01*
G01X-1544563Y701621D02*
X-1544645Y701370D01*
G01X-1530085Y675506D02*
X-1529806Y676930D01*
G01X-1534721Y701202D02*
X-1534557Y701035D01*
G01X-1534885Y700784D02*
X-1534967Y700867D01*
G01X-1536033Y701202D02*
X-1535787Y700951D01*
G01X-1536197Y700784D02*
X-1536279Y700867D01*
G01X-1538412Y701202D02*
X-1538248Y701035D01*
G01X-1518372Y680348D02*
X-1517815Y679778D01*
G01X-1538576Y700784D02*
X-1538658Y700867D01*
G01X-1539724Y701202D02*
X-1539478Y700951D01*
G01X-1539888Y700784D02*
X-1539970Y700867D01*
G01X-1518930Y678924D02*
X-1519209Y679209D01*
G01X-1542103Y701956D02*
X-1542349Y702208D01*
G01X-1543907Y699276D02*
X-1543661Y699108D01*
G01X-1532595Y682626D02*
X-1533431Y683196D01*
G01X-1537057Y673797D02*
X-1536220Y673228D01*
G01X-1537893Y672658D02*
X-1536499Y671804D01*
G01X-1539567Y680918D02*
X-1539846Y679494D01*
G01X-1541857Y699778D02*
X-1541775Y700197D01*
G01X-1544645Y701370D02*
X-1544727Y700951D01*
G01X-1531479Y675506D02*
X-1531201Y677215D01*
G01X-1538172Y680918D02*
X-1538451Y679209D01*
G01X-1542267Y699778D02*
X-1542185Y700281D01*
G01X-1544235Y701370D02*
X-1544317Y700867D01*
G01X-1513632Y678639D02*
Y671519D01*
G01Y680633D02*
Y679778D01*
G01X-1515026Y671519D02*
Y680633D01*
G01X-1517257Y678354D02*
Y671519D01*
G01X-1518651D02*
Y678354D01*
G01X-1521719D02*
Y671519D01*
G01X-1523113D02*
Y678354D01*
G01X-1526181Y678639D02*
Y671519D01*
G01Y680633D02*
Y679778D01*
G01X-1527575Y671519D02*
Y680633D01*
G01X-1529806Y676930D02*
Y679494D01*
G01X-1531201Y677215D02*
Y679209D01*
G01D02*
X-1531479Y680918D01*
G01X-1542185Y700867D02*
X-1542267Y701370D01*
G01X-1538451Y677215D02*
X-1538172Y675506D01*
G01X-1544317Y700281D02*
X-1544235Y699778D01*
G01X-1529806Y679494D02*
X-1530085Y680918D01*
G01X-1541775Y700951D02*
X-1541857Y701370D01*
G01X-1539846Y676930D02*
X-1539567Y675506D01*
G01X-1544727Y700197D02*
X-1544645Y699778D01*
G01X-1530085Y680918D02*
X-1530364Y681772D01*
G01X-1541857Y701370D02*
X-1541939Y701621D01*
G01X-1517815Y679778D02*
X-1517257Y678354D01*
G01X-1534557Y701035D02*
X-1534393Y700616D01*
G01X-1538248Y701035D02*
X-1538084Y700616D01*
G01X-1518651Y678354D02*
X-1518930Y678924D01*
G01X-1523113Y678354D02*
X-1523392Y678924D01*
G01X-1534803Y700616D02*
X-1534885Y700784D01*
G01X-1536115Y700616D02*
X-1536197Y700784D01*
G01X-1538494Y700616D02*
X-1538576Y700784D01*
G01X-1530364Y681772D02*
X-1530922Y682911D01*
G01X-1539806Y700616D02*
X-1539888Y700784D01*
G01X-1541939Y701621D02*
X-1542103Y701956D01*
G01X-1544563Y699527D02*
X-1544399Y699192D01*
G01X-1542267Y701370D02*
X-1542595Y701873D01*
G01X-1531479Y680918D02*
X-1532595Y682626D01*
G01X-1544235Y699778D02*
X-1543907Y699276D01*
G01X-1538172Y675506D02*
X-1537057Y673797D01*
G01X-1522834Y680348D02*
X-1521998Y679494D01*
G01X-1523392Y678924D02*
X-1523671Y679209D01*
G01X-1544399Y699192D02*
X-1544153Y698941D01*
G01X-1530922Y682911D02*
X-1531758Y683766D01*
G01X-1538730Y673513D02*
X-1537893Y672658D01*
G01X-1534393Y700616D02*
Y698606D01*
G01X-1534803D02*
Y700616D01*
G01X-1535705D02*
Y698606D01*
G01X-1536115D02*
Y700616D01*
G01X-1537017Y700700D02*
Y698606D01*
G01Y701286D02*
Y701035D01*
G01X-1537428Y698606D02*
Y701286D01*
G01X-1538084Y700616D02*
Y698606D01*
G01X-1538451Y679209D02*
Y677215D01*
G01X-1538494Y698606D02*
Y700616D01*
G01X-1539396D02*
Y698606D01*
G01X-1539806D02*
Y700616D01*
G01X-1539846Y679494D02*
Y676930D01*
G01X-1540708Y700700D02*
Y698606D01*
G01Y701286D02*
Y701035D01*
G01X-1541118Y698606D02*
Y701286D01*
G01X-1541775Y700197D02*
Y700951D01*
G01X-1542077Y677215D02*
Y676076D01*
G01Y680633D02*
Y679494D01*
G01X-1542185Y700281D02*
Y700867D01*
G01X-1544317D02*
Y700281D01*
G01X-1544727Y700951D02*
Y700197D01*
G01X-1545384Y700281D02*
Y699946D01*
G01Y701286D02*
Y700951D01*
G01X-1546538Y679494D02*
Y680633D01*
G01Y676076D02*
Y677215D01*
G01X-1546696Y699946D02*
Y700281D01*
G01Y700951D02*
Y701286D01*
G01X-1547352Y702543D02*
Y698606D01*
G01X-1547844Y700951D02*
Y702543D01*
G01Y698606D02*
Y700448D01*
G01X-1548769Y684905D02*
Y671519D01*
G01X-1550141Y700448D02*
Y698606D01*
G01Y702543D02*
Y700951D01*
G01X-1550443Y679494D02*
Y684905D01*
G01Y671519D02*
Y677785D01*
G01X-1550633Y698606D02*
Y702543D01*
G01X-1558251Y677785D02*
Y671519D01*
G01Y684905D02*
Y679494D01*
G01X-1559924Y671519D02*
Y684905D01*
G01X-1564098Y730456D02*
Y693054D01*
G01X-1544645Y699778D02*
X-1544563Y699527D01*
G01X-1539567Y675506D02*
X-1539288Y674652D01*
G01D02*
X-1538730Y673513D01*
G01X-1571775Y664708D02*
Y693054D01*
G01X-1508389Y730456D02*
X-1571775D01*
G01X-1501696Y718448D02*
X-1515082D01*
G01X-1571775Y730456D02*
Y882031D01*
G01X-1501499Y886952D02*
G03I-6496J0D01*
G01X-1526037Y882030D02*
G03X-1507995Y905653I18042J4922D01*
G01X-1538723Y897779D02*
X-1539216Y897695D01*
G01X-1538723Y893842D02*
X-1538231Y893926D01*
G01X-1538723Y897360D02*
X-1539134Y897276D01*
G01X-1538723Y894261D02*
X-1538313Y894344D01*
G01X-1571775Y918448D02*
X-1260751D01*
G01X-1507995Y905653D02*
X-1571775D01*
G01X-1543317Y897779D02*
X-1542825D01*
G01X-1546105D02*
X-1545613D01*
G01X-1530767Y896522D02*
X-1530439D01*
G01X-1532080D02*
X-1531752D01*
G01X-1532900D02*
X-1532490D01*
G01X-1534458D02*
X-1534130D01*
G01X-1535771D02*
X-1535443D01*
G01X-1536591D02*
X-1536181D01*
G01X-1542168D02*
X-1540856D01*
G01X-1545613Y896187D02*
X-1543317D01*
G01X-1540856D02*
X-1542168D01*
G01X-1535607D02*
X-1535771D01*
G01X-1534294D02*
X-1534540D01*
G01X-1531916D02*
X-1532080D01*
G01X-1530603D02*
X-1530849D01*
G01X-1543317Y895685D02*
X-1545613D01*
G01X-1542168Y895517D02*
X-1540856D01*
G01Y895182D02*
X-1542168D01*
G01X-1545613Y893842D02*
X-1546105D01*
G01X-1542825D02*
X-1543317D01*
G01X-1536181D02*
X-1536591D01*
G01X-1532490D02*
X-1532900D01*
G01X-1534868D02*
X-1535279D01*
G01X-1533556D02*
X-1533966D01*
G01X-1531178D02*
X-1531588D01*
G01X-1529865D02*
X-1530275D01*
G01X-1571775Y882031D02*
X-1526037D01*
G01X-1538231Y897695D02*
X-1538723Y897779D01*
G01X-1539216Y893926D02*
X-1538723Y893842D01*
G01X-1538313Y897276D02*
X-1538723Y897360D01*
G01X-1539134Y894344D02*
X-1538723Y894261D01*
G01X-1530439Y896522D02*
X-1530193Y896439D01*
G01X-1531752Y896522D02*
X-1531506Y896439D01*
G01X-1534130Y896522D02*
X-1533884Y896439D01*
G01X-1535443Y896522D02*
X-1535197Y896439D01*
G01X-1530439Y896104D02*
X-1530603Y896187D01*
G01X-1531752Y896104D02*
X-1531916Y896187D01*
G01X-1534130Y896104D02*
X-1534294Y896187D01*
G01X-1535443Y896104D02*
X-1535607Y896187D01*
G01X-1538067Y897109D02*
X-1538313Y897276D01*
G01X-1539380Y894512D02*
X-1539134Y894344D01*
G01X-1537821Y897444D02*
X-1538231Y897695D01*
G01X-1539626Y894177D02*
X-1539216Y893926D01*
G01X-1531014Y896439D02*
X-1530767Y896522D01*
G01X-1532080Y896187D02*
X-1532326Y896104D01*
G01Y896439D02*
X-1532080Y896522D01*
G01X-1534704Y896439D02*
X-1534458Y896522D01*
G01X-1535771Y896187D02*
X-1536017Y896104D01*
G01Y896439D02*
X-1535771Y896522D01*
G01X-1530849Y896187D02*
X-1531014Y896104D01*
G01X-1534540Y896187D02*
X-1534704Y896104D01*
G01X-1530193Y896439D02*
X-1530029Y896271D01*
G01X-1530357Y896020D02*
X-1530439Y896104D01*
G01X-1531506Y896439D02*
X-1531260Y896187D01*
G01X-1531670Y896020D02*
X-1531752Y896104D01*
G01X-1533884Y896439D02*
X-1533720Y896271D01*
G01X-1534048Y896020D02*
X-1534130Y896104D01*
G01X-1535197Y896439D02*
X-1534951Y896187D01*
G01X-1535361Y896020D02*
X-1535443Y896104D01*
G01X-1537575Y897193D02*
X-1537821Y897444D01*
G01X-1539872Y894428D02*
X-1539626Y894177D01*
G01X-1538231Y893926D02*
X-1537821Y894177D01*
G01X-1539216Y897695D02*
X-1539626Y897444D01*
G01X-1538313Y894344D02*
X-1538067Y894512D01*
G01X-1539134Y897276D02*
X-1539380Y897109D01*
G01X-1537739Y896606D02*
X-1538067Y897109D01*
G01X-1539708Y895015D02*
X-1539380Y894512D01*
G01X-1531014Y896104D02*
X-1531096Y896020D01*
G01X-1531260Y896187D02*
X-1531014Y896439D01*
G01X-1532326Y896104D02*
X-1532490Y895936D01*
G01Y896271D02*
X-1532326Y896439D01*
G01X-1530029Y896271D02*
X-1529865Y895852D01*
G01X-1533720Y896271D02*
X-1533556Y895852D01*
G01X-1530275D02*
X-1530357Y896020D01*
G01X-1531588Y895852D02*
X-1531670Y896020D01*
G01X-1533966Y895852D02*
X-1534048Y896020D01*
G01X-1535279Y895852D02*
X-1535361Y896020D01*
G01X-1537411Y896857D02*
X-1537575Y897193D01*
G01X-1540036Y894763D02*
X-1539872Y894428D01*
G01X-1534704Y896104D02*
X-1534786Y896020D01*
G01X-1534951Y896187D02*
X-1534704Y896439D01*
G01X-1537821Y894177D02*
X-1537575Y894428D01*
G01X-1536017Y896104D02*
X-1536181Y895936D01*
G01Y896271D02*
X-1536017Y896439D01*
G01X-1539626Y897444D02*
X-1539872Y897193D01*
G01X-1537657Y896104D02*
X-1537739Y896606D01*
G01X-1539790Y895517D02*
X-1539708Y895015D01*
G01X-1537247Y896187D02*
X-1537329Y896606D01*
G01X-1540200Y895433D02*
X-1540118Y895015D01*
G01X-1537329Y896606D02*
X-1537411Y896857D01*
G01X-1540118Y895015D02*
X-1540036Y894763D01*
G01X-1538067Y894512D02*
X-1537739Y895015D01*
G01X-1539380Y897109D02*
X-1539708Y896606D01*
G01X-1531096Y896020D02*
X-1531178Y895852D01*
G01X-1534786Y896020D02*
X-1534868Y895852D01*
G01X-1537575Y894428D02*
X-1537411Y894763D01*
G01X-1539872Y897193D02*
X-1540036Y896857D01*
G01X-1537411Y894763D02*
X-1537329Y895015D01*
G01X-1529865Y895852D02*
Y893842D01*
G01X-1530275D02*
Y895852D01*
G01X-1531178D02*
Y893842D01*
G01X-1582129Y903483D02*
X-1582410Y905131D01*
G01X-1540036Y896857D02*
X-1540118Y896606D01*
G01X-1537329Y895015D02*
X-1537247Y895433D01*
G01X-1540118Y896606D02*
X-1540200Y896187D01*
G01X-1537739Y895015D02*
X-1537657Y895517D01*
G01X-1539708Y896606D02*
X-1539790Y896104D01*
G01X-1531588Y893842D02*
Y895852D01*
G01X-1532490Y895936D02*
Y893842D01*
G01Y896522D02*
Y896271D01*
G01X-1532900Y893842D02*
Y896522D01*
G01X-1533556Y895852D02*
Y893842D01*
G01X-1533966D02*
Y895852D01*
G01X-1534868D02*
Y893842D01*
G01X-1535279D02*
Y895852D01*
G01X-1536181Y895936D02*
Y893842D01*
G01Y896522D02*
Y896271D01*
G01X-1536591Y893842D02*
Y896522D01*
G01X-1537247Y895433D02*
Y896187D01*
G01X-1537657Y895517D02*
Y896104D01*
G01X-1539790D02*
Y895517D01*
G01X-1540200Y896187D02*
Y895433D01*
G01X-1540856Y895517D02*
Y895182D01*
G01Y896522D02*
Y896187D01*
G01X-1542168Y895182D02*
Y895517D01*
G01Y896187D02*
Y896522D01*
G01X-1542825Y897779D02*
Y893842D01*
G01X-1543317Y896187D02*
Y897779D01*
G01Y893842D02*
Y895685D01*
G01X-1545613D02*
Y893842D01*
G01Y897779D02*
Y896187D01*
G01X-1546105Y893842D02*
Y897779D01*
G01X-1551302Y905653D02*
Y882031D01*
G01X-1582410Y901834D02*
X-1582129Y903483D01*
G01X-1571775Y905653D02*
Y918448D01*
G01X-1582129Y918870D02*
Y917221D01*
G01X-1527286Y949747D02*
Y978594D01*
G01X-1520397Y945810D02*
G03I-6889J0D01*
G01X-1508586D02*
G03I-18700J0D01*
G01X-1582129Y928212D02*
Y926563D01*
G01X-1467244Y1165280D02*
X-1566273D01*
G01X-1541066Y1213527D02*
G03I-7874J0D01*
G01X-1530239D02*
G03I-18701J0D01*
G01X-1548940Y1217464D02*
Y1284992D01*
G01X-1542997Y1231258D02*
X-1493452Y1379086D01*
G01X-1576034Y1237149D02*
G03X-1579556Y1234973I0J-3938D01*
G01X-1576034Y1237149D02*
G03X-1579556Y1234973I0J-3938D01*
G01X-1212003Y1237149D02*
X-1576034D01*
G01X-1212003D02*
X-1576034D01*
G01X-1457991Y-714465D02*
Y-733402D01*
G01X-1483773Y-529335D02*
G03X-1479836Y-525398I0J3937D01*
G01D02*
Y-100005D01*
G01X-1503576Y-297643D02*
G03Y-284257I0J6693D01*
G01X-1475899Y-96068D02*
G03X-1479836Y-100005I0J-3937D01*
G01X-1316450Y-96068D02*
X-1475899D01*
G01X-1428576Y139956D02*
G03I-8267J0D01*
G01X-1424048D02*
G03I-12795J0D01*
G01X-1422080D02*
G03I-14763J0D01*
G01X-1502700Y302613D02*
X-1216584D01*
G01X-1505849D02*
X-1502700D01*
G01X-1477956Y473369D02*
Y432110D01*
G01X-1507995Y876322D02*
Y432110D01*
G01X-1498675Y474944D02*
G03X-1497694Y475858I0J983D01*
G01X-1509635D02*
G03X-1508653Y474944I982J71D01*
G01X-1481893Y473369D02*
G03X-1477956Y477306I0J3937D01*
G01X-1481893Y473369D02*
G03X-1477956Y477306I0J3937D01*
G01X-1497694Y475858D02*
X-1496775Y488724D01*
G01X-1477956Y477306D02*
Y902700D01*
G01Y477306D02*
Y902700D01*
G01X-1496775Y488724D02*
X-1510554D01*
G01X-1497694Y475858D02*
X-1509635D01*
G01X-1498675Y474944D02*
X-1508653D01*
G01X-1496775Y488724D02*
Y499354D01*
G01X-1510554Y488724D02*
Y499354D01*
G01X-1509635Y475858D02*
X-1510554Y488724D01*
G01X-1489137Y517494D02*
X-1489143Y517661D01*
G01X-1489119Y517335D02*
X-1489137Y517494D01*
G01X-1489089Y517191D02*
X-1489119Y517335D01*
G01X-1489051Y517071D02*
X-1489089Y517191D01*
G01X-1489004Y516978D02*
X-1489051Y517071D01*
G01X-1488952Y516918D02*
X-1489004Y516978D01*
G01X-1490488Y516979D02*
X-1490436Y516918D01*
G01X-1490535Y517072D02*
X-1490488Y516979D01*
G01X-1490574Y517194D02*
X-1490535Y517072D01*
G01X-1490603Y517336D02*
X-1490574Y517194D01*
G01X-1490621Y517496D02*
X-1490603Y517336D01*
G01X-1490627Y517661D02*
X-1490621Y517496D01*
G01X-1489004Y518343D02*
X-1488952Y518403D01*
G01X-1489051Y518249D02*
X-1489004Y518343D01*
G01X-1489090Y518127D02*
X-1489051Y518249D01*
G01X-1489119Y517985D02*
X-1489090Y518127D01*
G01X-1489137Y517826D02*
X-1489119Y517985D01*
G01X-1489143Y517661D02*
X-1489137Y517826D01*
G01X-1490621Y517827D02*
X-1490627Y517661D01*
G01X-1490603Y517987D02*
X-1490621Y517827D01*
G01X-1490573Y518131D02*
X-1490603Y517987D01*
G01X-1490535Y518250D02*
X-1490573Y518131D01*
G01X-1490488Y518343D02*
X-1490535Y518250D01*
G01X-1490436Y518403D02*
X-1490488Y518343D01*
G01X-1490319Y513153D02*
G03X-1490653Y512622I256J-532D01*
G01X-1491006Y514571D02*
G03X-1490672Y515102I-256J532D01*
G01X-1491460Y499354D02*
G03X-1490672Y500141I0J788D01*
G01X-1487916Y517661D02*
G03I-1969J0D01*
G01X-1492838Y507818D02*
G03I-1968J0D01*
G01X-1490319Y513153D02*
G03X-1489098Y515102I-945J1949D01*
G01X-1491006Y514571D02*
G03X-1492227Y512622I945J-1949D01*
G01X-1491460Y497779D02*
G03X-1489098Y500141I0J2362D01*
G01X-1488952Y518403D02*
X-1488154Y519039D01*
G01X-1489637D02*
X-1490436Y518403D01*
G01X-1489098Y523566D02*
X-1490672D01*
G01X-1489098Y522385D02*
X-1490672D01*
G01X-1486932Y519039D02*
X-1490672D01*
G01Y518842D02*
X-1489098D01*
G01X-1488952Y518403D02*
X-1490436D01*
G01X-1489098Y517661D02*
X-1490672D01*
G01X-1488952Y516918D02*
X-1490436D01*
G01X-1486932Y516283D02*
X-1490672D01*
G01Y515102D02*
X-1489098D01*
G01X-1490672Y513758D02*
X-1489098D01*
G01X-1490672Y513133D02*
X-1489098D01*
G01X-1492247Y512346D02*
X-1499727D01*
G01Y511558D02*
X-1507601D01*
G01X-1492247Y511362D02*
X-1496972D01*
G01X-1490672Y511165D02*
X-1489098D01*
G01Y510062D02*
X-1490672D01*
G01X-1493428Y509590D02*
X-1496184D01*
G01X-1493428Y509324D02*
X-1496184D01*
G01X-1493428Y508475D02*
X-1496184D01*
G01X-1493428Y508409D02*
X-1496184D01*
G01X-1493428Y508342D02*
X-1496184D01*
G01X-1493428Y507494D02*
X-1496184D01*
G01X-1493428Y507228D02*
X-1496184D01*
G01X-1489098Y506913D02*
X-1490672D01*
G01Y502680D02*
X-1489098D01*
G01Y501499D02*
X-1490672D01*
G01Y499531D02*
X-1489098D01*
G01X-1486932Y519039D02*
Y516283D01*
G01X-1487068Y519039D02*
Y516283D01*
G01X-1487091D02*
Y519039D01*
G01X-1488507D02*
Y516283D01*
G01X-1488565Y519039D02*
Y516283D01*
G01X-1488575D02*
Y519039D01*
G01X-1489096D02*
Y516283D01*
G01X-1489098Y523566D02*
Y499531D01*
G01X-1490593Y519039D02*
Y516283D01*
G01X-1490653Y512622D02*
Y510771D01*
G01X-1490672Y499531D02*
Y523566D01*
G01X-1492838Y496204D02*
X-1497562D01*
G01X-1491460Y510771D02*
Y499354D01*
G01X-1492050D02*
Y497779D01*
G01X-1492227Y512622D02*
Y510771D01*
G01X-1492247D02*
Y512346D01*
G01X-1492641Y510771D02*
Y499354D01*
G01X-1492838Y496204D02*
Y497779D01*
G01X-1493428Y507228D02*
Y509590D01*
G01X-1493625Y499354D02*
Y497779D01*
G01X-1494019Y508409D02*
Y507228D01*
G01X-1495594D02*
Y508409D01*
G01X-1496184Y509590D02*
Y507228D01*
G01X-1496381Y499354D02*
Y497779D01*
G01X-1496972Y511362D02*
Y512346D01*
G01X-1497168Y499354D02*
Y497779D01*
G01X-1497562Y496204D02*
Y497779D01*
G01X-1497759Y510771D02*
Y512346D01*
G01Y499354D02*
Y497779D01*
G01X-1499727Y512346D02*
Y511558D01*
G01X-1500712Y499354D02*
Y497779D01*
G01X-1506617Y499354D02*
Y497779D01*
G01X-1507601Y512346D02*
Y511558D01*
G01X-1509570Y499354D02*
Y497779D01*
G01Y512346D02*
Y510771D01*
G01X-1509767Y496204D02*
Y497779D01*
G01X-1510160Y499354D02*
Y497779D01*
G01X-1510357Y511362D02*
Y512346D01*
G01X-1510948Y499354D02*
Y497779D01*
G01X-1511145Y507228D02*
Y509590D01*
G01X-1511164Y508921D02*
Y506716D01*
G01X-1488154Y516283D02*
X-1488952Y516918D01*
G01X-1490436D02*
X-1489637Y516283D01*
G01X-1335040Y579937D02*
X-1441864D01*
G01X-1482011Y646598D02*
Y599354D01*
G01X-1510367Y620975D02*
Y614944D01*
G01X-1510859Y622232D02*
X-1510367Y620975D01*
G01X-1508389Y708999D02*
Y725626D01*
G01X-1501696Y705062D02*
G03Y718448I0J6693D01*
G01X-1508389Y693054D02*
G03Y730456I0J18701D01*
G01X-1508612Y680348D02*
X-1507775Y680633D01*
G01X-1508054Y679494D02*
X-1508612Y679209D01*
G01D02*
X-1508891Y678924D01*
G01X-1509449Y679494D02*
X-1508612Y680348D01*
G01X-1507775Y680633D02*
X-1506660D01*
G01X-1507218Y679494D02*
X-1508054D01*
G01X-1509170Y671519D02*
X-1510564D01*
G01X-1504708D02*
X-1506102D01*
G01X-1508891Y678924D02*
X-1509170Y678354D01*
G01X-1506660Y680633D02*
X-1505823Y680348D01*
G01X-1511122Y680633D02*
X-1510285Y680348D01*
G01X-1506660Y679209D02*
X-1507218Y679494D01*
G01X-1505823Y680348D02*
X-1505265Y679778D01*
G01X-1506381Y678924D02*
X-1506660Y679209D01*
G01X-1510285Y680348D02*
X-1509449Y679494D01*
G01X-1510843Y678924D02*
X-1511122Y679209D01*
G01X-1504708Y678354D02*
Y671519D01*
G01X-1506102D02*
Y678354D01*
G01X-1509170D02*
Y671519D01*
G01X-1510564D02*
Y678354D01*
G01X-1505265Y679778D02*
X-1504708Y678354D01*
G01X-1506102D02*
X-1506381Y678924D01*
G01X-1510564Y678354D02*
X-1510843Y678924D01*
G01X-1444335Y662789D02*
X-1432524D01*
G01X-1501588Y684128D02*
X-1444335Y662789D01*
G01X-1444507Y858888D02*
X-1337683D01*
G01X-1447657D02*
X-1444507D01*
G01X-1502105Y884213D02*
X-1447657Y858888D01*
G01X-1474019Y906637D02*
G03X-1477956Y902700I0J-3937D01*
G01X-1474019Y906637D02*
G03X-1477956Y902700I0J-3937D01*
G01X-1309058Y919039D02*
X-1501302D01*
G01X-1314570Y906637D02*
X-1474019D01*
G01X-1314570D02*
X-1474019D01*
G01X-1501302Y919039D02*
Y983291D01*
G01D02*
X-1309058D01*
G01X-1444868Y958728D02*
X-1442407D01*
G01X-1458811D02*
X-1456351D01*
G01Y950771D02*
X-1444868D01*
G01Y948258D02*
X-1456351D01*
G01Y939043D02*
X-1458811D01*
G01X-1442407D02*
X-1444868D01*
G01X-1442407Y958728D02*
Y939043D01*
G01X-1444868Y950771D02*
Y958728D01*
G01Y939043D02*
Y948258D01*
G01X-1456351D02*
Y939043D01*
G01Y958728D02*
Y950771D01*
G01X-1458811Y939043D02*
Y958728D01*
G01X-1447759Y1006834D02*
X-1372956D01*
G01X-1447759Y1003330D02*
X-1502601D01*
G01X-1447759Y1081637D02*
Y1006834D01*
G01Y1135295D02*
Y1003330D01*
G01X-1502601D02*
Y1237149D01*
G01X-1468687Y1094840D02*
X-1471836D01*
G01X-1443472Y1130595D02*
X-1468687Y1094840D01*
G01X-1429058Y1142661D02*
G03I-5906J0D01*
G01X-1428546D02*
G03I-6418J0D01*
G01X-1428468D02*
G03I-6496J0D01*
G01X-1427601D02*
G03I-7363J0D01*
G01X-1427090D02*
G03I-7874J0D01*
G01D02*
G03I-7874J0D01*
G01X-1426696D02*
G03I-8268J0D01*
G01X-1425633D02*
G03I-9331J0D01*
G01X-1425121D02*
G03I-9843J0D01*
G01X-1422168D02*
G03I-12796J0D01*
G01X-1420200D02*
G03I-14764J0D01*
G01X-1475128Y1129590D02*
X-1474143D01*
G01X-1486118D02*
X-1485134D01*
G01X-1491696D02*
X-1490712D01*
G01X-1459544Y1127077D02*
X-1458888D01*
G01X-1462168D02*
X-1461512D01*
G01X-1463809D02*
X-1462989D01*
G01X-1466926D02*
X-1466269D01*
G01X-1469550D02*
X-1468894D01*
G01X-1471191D02*
X-1470370D01*
G01X-1490712Y1126407D02*
X-1486118D01*
G01X-1469222D02*
X-1469550D01*
G01X-1466598D02*
X-1467090D01*
G01X-1461840D02*
X-1462168D01*
G01X-1459216D02*
X-1459708D01*
G01X-1486118Y1125402D02*
X-1490712D01*
G01X-1474143Y1125067D02*
X-1472503D01*
G01X-1475128D02*
X-1477916D01*
G01X-1475128Y1124061D02*
X-1479065D01*
G01X-1472503D02*
X-1474143D01*
G01X-1490712Y1121716D02*
X-1491696D01*
G01X-1485134D02*
X-1486118D01*
G01X-1474143D02*
X-1475128D01*
G01X-1470370D02*
X-1471191D01*
G01X-1467746D02*
X-1468566D01*
G01X-1462989D02*
X-1463809D01*
G01X-1465121D02*
X-1465941D01*
G01X-1460364D02*
X-1461184D01*
G01X-1457739D02*
X-1458559D01*
G01X-1372956Y1081637D02*
X-1447759D01*
G01X-1458888Y1127077D02*
X-1458395Y1126909D01*
G01X-1461512Y1127077D02*
X-1461020Y1126909D01*
G01X-1466269Y1127077D02*
X-1465777Y1126909D01*
G01X-1468894Y1127077D02*
X-1468402Y1126909D01*
G01X-1458888Y1126239D02*
X-1459216Y1126407D01*
G01X-1461512Y1126239D02*
X-1461840Y1126407D01*
G01X-1466269Y1126239D02*
X-1466598Y1126407D01*
G01X-1468894Y1126239D02*
X-1469222Y1126407D01*
G01X-1482674Y1125737D02*
X-1480377Y1124564D01*
G01X-1480705Y1124061D02*
X-1483822Y1125737D01*
G01X-1458395Y1126909D02*
X-1458067Y1126574D01*
G01X-1458723Y1126072D02*
X-1458888Y1126239D01*
G01X-1461020Y1126909D02*
X-1460528Y1126407D01*
G01X-1461348Y1126072D02*
X-1461512Y1126239D01*
G01X-1465777Y1126909D02*
X-1465449Y1126574D01*
G01X-1466105Y1126072D02*
X-1466269Y1126239D01*
G01X-1468402Y1126909D02*
X-1467910Y1126407D01*
G01X-1468730Y1126072D02*
X-1468894Y1126239D01*
G01X-1480705Y1127412D02*
X-1480377Y1126909D01*
G01X-1458559Y1125737D02*
X-1458723Y1126072D01*
G01X-1461184Y1125737D02*
X-1461348Y1126072D01*
G01X-1465941Y1125737D02*
X-1466105Y1126072D01*
G01X-1468566Y1125737D02*
X-1468730Y1126072D01*
G01X-1458067Y1126574D02*
X-1457739Y1125737D01*
G01X-1465449Y1126574D02*
X-1465121Y1125737D01*
G01X-1457739D02*
Y1121716D01*
G01X-1458559D02*
Y1125737D01*
G01X-1460364D02*
Y1121716D01*
G01X-1461184D02*
Y1125737D01*
G01X-1462989Y1125904D02*
Y1121716D01*
G01Y1127077D02*
Y1126574D01*
G01X-1463809Y1121716D02*
Y1127077D01*
G01X-1465121Y1125737D02*
Y1121716D01*
G01X-1465941D02*
Y1125737D01*
G01X-1467746D02*
Y1121716D01*
G01X-1468566D02*
Y1125737D01*
G01X-1470370Y1125904D02*
Y1121716D01*
G01Y1127077D02*
Y1126574D01*
G01X-1471191Y1121716D02*
Y1127077D01*
G01X-1472503Y1125067D02*
Y1124061D01*
G01X-1474143D02*
Y1121716D01*
G01Y1129590D02*
Y1125067D01*
G01X-1475128Y1121716D02*
Y1124061D01*
G01Y1128250D02*
Y1125067D01*
G01X-1479065Y1124061D02*
Y1125067D01*
G01X-1485134Y1129590D02*
Y1121716D01*
G01X-1486118Y1126407D02*
Y1129590D01*
G01Y1121716D02*
Y1125402D01*
G01X-1490712D02*
Y1121716D01*
G01Y1129590D02*
Y1126407D01*
G01X-1460036Y1126909D02*
X-1459544Y1127077D01*
G01X-1462168Y1126407D02*
X-1462660Y1126239D01*
G01Y1126909D02*
X-1462168Y1127077D01*
G01X-1467418Y1126909D02*
X-1466926Y1127077D01*
G01X-1469550Y1126407D02*
X-1470042Y1126239D01*
G01Y1126909D02*
X-1469550Y1127077D01*
G01X-1459708Y1126407D02*
X-1460036Y1126239D01*
G01X-1467090Y1126407D02*
X-1467418Y1126239D01*
G01X-1491696Y1121716D02*
Y1129590D01*
G01X-1480377Y1126909D02*
X-1482674Y1125737D01*
G01X-1483822D02*
X-1480705Y1127412D01*
G01X-1460036Y1126239D02*
X-1460200Y1126072D01*
G01X-1460528Y1126407D02*
X-1460036Y1126909D01*
G01X-1462660Y1126239D02*
X-1462989Y1125904D01*
G01Y1126574D02*
X-1462660Y1126909D01*
G01X-1467418Y1126239D02*
X-1467582Y1126072D01*
G01X-1467910Y1126407D02*
X-1467418Y1126909D01*
G01X-1470042Y1126239D02*
X-1470370Y1125904D01*
G01Y1126574D02*
X-1470042Y1126909D01*
G01X-1460200Y1126072D02*
X-1460364Y1125737D01*
G01X-1467582Y1126072D02*
X-1467746Y1125737D01*
G01X-1477916Y1125067D02*
X-1475128Y1128250D01*
G01X-1479065Y1125067D02*
X-1475128Y1129590D01*
G01X-1480377Y1124564D02*
X-1480705Y1124061D01*
G01X-1447168Y1142661D02*
X-1475605D01*
G01X-1464095Y1165280D02*
X-1467244D01*
G01X-1441494Y1147731D02*
X-1464095Y1165280D01*
G01X-1447759Y1237149D02*
Y1150026D01*
G01X-1474743Y1379086D02*
X-1188627D01*
G01X-1493452D02*
X-1474743D01*
G01X-1457991Y1463291D02*
Y1444354D01*
G01X-1388641Y-47436D02*
X-1391102Y-47854D01*
G01X-1390282Y-49948D02*
X-1388231Y-49530D01*
G01X-1387001Y-47436D02*
X-1388641D01*
G01X-1388231Y-49530D02*
X-1386591D01*
G01X-1382490Y-52043D02*
X-1380439D01*
G01X-1427191Y-53718D02*
X-1428831D01*
G01X-1420629D02*
X-1422270D01*
G01X-1416528D02*
X-1418579D01*
G01X-1408736D02*
X-1410377D01*
G01X-1402175D02*
X-1403815D01*
G01X-1398074D02*
X-1400124D01*
G01X-1402995Y-55393D02*
X-1402175D01*
G01X-1409557D02*
X-1408326D01*
G01X-1421450D02*
X-1420629D01*
G01X-1428011D02*
X-1426781D01*
G01X-1386591Y-49530D02*
X-1384540Y-49948D01*
G01X-1384130Y-47854D02*
X-1387001Y-47436D01*
G01X-1383310Y-65026D02*
X-1394793D01*
G01Y-67121D02*
X-1380029D01*
G01X-1400124D02*
X-1398074D01*
G01X-1406686D02*
X-1404635D01*
G01X-1413247D02*
X-1411197D01*
G01X-1418579D02*
X-1416528D01*
G01X-1425141D02*
X-1423090D01*
G01X-1431702D02*
X-1429652D01*
G01X-1368136Y-57069D02*
X-1375928Y-52880D01*
G01X-1382490Y-48692D02*
X-1384130Y-47854D01*
G01X-1376748Y-54137D02*
X-1371007Y-57069D01*
G01X-1400944Y-54137D02*
X-1402175Y-53718D01*
G01Y-55393D02*
X-1400944Y-55812D01*
G01X-1407506Y-54137D02*
X-1408736Y-53718D01*
G01X-1419399Y-54137D02*
X-1420629Y-53718D01*
G01Y-55393D02*
X-1419399Y-55812D01*
G01X-1425961Y-54137D02*
X-1427191Y-53718D01*
G01X-1384540Y-49948D02*
X-1383310Y-50786D01*
G01X-1408326Y-55393D02*
X-1407506Y-55812D01*
G01X-1426781Y-55393D02*
X-1425961Y-55812D01*
G01X-1380849Y-50367D02*
X-1382490Y-48692D01*
G01X-1380029Y-65026D02*
X-1391512Y-54556D01*
G01X-1393562Y-55812D02*
X-1383310Y-65026D01*
G01X-1376748Y-60000D02*
X-1375928Y-61257D01*
G01X-1383310Y-50786D02*
X-1382490Y-52043D01*
G01X-1400124Y-54974D02*
X-1400944Y-54137D01*
G01Y-55812D02*
X-1400124Y-56650D01*
G01X-1406276Y-55393D02*
X-1407506Y-54137D01*
G01Y-55812D02*
X-1407096Y-56231D01*
G01X-1418579Y-54974D02*
X-1419399Y-54137D01*
G01Y-55812D02*
X-1418579Y-56650D01*
G01X-1424730Y-55393D02*
X-1425961Y-54137D01*
G01Y-55812D02*
X-1425551Y-56231D01*
G01X-1391512Y-54556D02*
X-1392332Y-52880D01*
G01X-1394383Y-54556D02*
X-1393562Y-55812D01*
G01X-1403815Y-53718D02*
X-1405045Y-54137D01*
G01X-1410377Y-53718D02*
X-1411607Y-54137D01*
G01X-1422270Y-53718D02*
X-1423500Y-54137D01*
G01X-1428831Y-53718D02*
X-1430062Y-54137D01*
G01X-1371007Y-57069D02*
X-1376748Y-60000D01*
G01X-1375928Y-61257D02*
X-1368136Y-57069D01*
G01X-1380439Y-52043D02*
X-1380849Y-50367D01*
G01X-1394793Y-52880D02*
X-1394383Y-54556D01*
G01X-1407096Y-56231D02*
X-1406686Y-57069D01*
G01X-1425551Y-56231D02*
X-1425141Y-57069D01*
G01X-1403815Y-55812D02*
X-1402995Y-55393D01*
G01X-1391102Y-47854D02*
X-1392742Y-48692D01*
G01X-1410377Y-55812D02*
X-1409557Y-55393D01*
G01X-1422270Y-55812D02*
X-1421450Y-55393D01*
G01X-1428831Y-55812D02*
X-1428011Y-55393D01*
G01X-1391512Y-50786D02*
X-1390282Y-49948D01*
G01X-1392742Y-48692D02*
X-1394383Y-50367D01*
G01X-1404225Y-56231D02*
X-1403815Y-55812D01*
G01X-1405045Y-54137D02*
X-1406276Y-55393D01*
G01X-1410787Y-56231D02*
X-1410377Y-55812D01*
G01X-1411607Y-54137D02*
X-1412427Y-54974D01*
G01X-1422680Y-56231D02*
X-1422270Y-55812D01*
G01X-1423500Y-54137D02*
X-1424730Y-55393D01*
G01X-1429242Y-56231D02*
X-1428831Y-55812D01*
G01X-1430062Y-54137D02*
X-1430882Y-54974D01*
G01X-1375928Y-52880D02*
X-1376748Y-54137D01*
G01X-1392332Y-52043D02*
X-1391512Y-50786D01*
G01X-1394383Y-50367D02*
X-1394793Y-52043D01*
G01X-1380029Y-67121D02*
Y-65026D01*
G01X-1392332Y-52880D02*
Y-52043D01*
G01X-1394793Y-65026D02*
Y-67121D01*
G01Y-52043D02*
Y-52880D01*
G01X-1398074Y-67121D02*
Y-53718D01*
G01X-1400124Y-56650D02*
Y-67121D01*
G01Y-53718D02*
Y-54974D01*
G01X-1404635Y-67121D02*
Y-57069D01*
G01X-1406686D02*
Y-67121D01*
G01X-1411197D02*
Y-57069D01*
G01X-1404635D02*
X-1404225Y-56231D01*
G01X-1411197Y-57069D02*
X-1410787Y-56231D01*
G01X-1423090Y-57069D02*
X-1422680Y-56231D01*
G01X-1429652Y-57069D02*
X-1429242Y-56231D01*
G01X-1412427Y-54974D02*
X-1413247Y-57069D01*
G01X-1430882Y-54974D02*
X-1431702Y-57069D01*
G01X-1413247D02*
Y-67121D01*
G01X-1416528D02*
Y-53718D01*
G01X-1418579Y-56650D02*
Y-67121D01*
G01Y-53718D02*
Y-54974D01*
G01X-1423090Y-67121D02*
Y-57069D01*
G01X-1425141D02*
Y-67121D01*
G01X-1429652D02*
Y-57069D01*
G01X-1431702D02*
Y-67121D01*
G01X-1432770Y152085D02*
X-1401405Y245467D01*
G01X-1398256D02*
X-1299227D01*
G01X-1401405D02*
X-1398256D01*
G01X-1399756Y958310D02*
X-1396885Y958728D01*
G01X-1421082D02*
X-1423132Y958310D01*
G01X-1397295Y956634D02*
X-1399346Y956215D01*
G01X-1419031Y946163D02*
X-1416980Y946582D01*
G01X-1419031Y939043D02*
X-1416980Y939462D01*
G01X-1395245Y941138D02*
X-1393194Y941556D01*
G01Y939462D02*
X-1394835Y939043D01*
G01X-1396885Y958728D02*
X-1396065D01*
G01X-1419031D02*
X-1421082D01*
G01X-1418621Y956634D02*
X-1421492D01*
G01X-1395655D02*
X-1397295D01*
G01X-1401397Y954121D02*
X-1403447D01*
G01X-1375150Y952446D02*
X-1373509D01*
G01X-1381711D02*
X-1380071D01*
G01X-1385813D02*
X-1383762D01*
G01X-1380891Y950771D02*
X-1381711D01*
G01X-1374330D02*
X-1375560D01*
G01X-1397295Y949933D02*
X-1395655D01*
G01X-1421492Y948258D02*
X-1418621D01*
G01X-1395655D02*
X-1397295D01*
G01X-1421082Y946163D02*
X-1419031D01*
G01X-1403857Y943650D02*
X-1401807D01*
G01X-1424362D02*
X-1426413D01*
G01X-1397706Y941138D02*
X-1395245D01*
G01X-1409188D02*
X-1407138D01*
G01X-1418621D02*
X-1421082D01*
G01X-1420671Y939043D02*
X-1419031D01*
G01X-1407138D02*
X-1409188D01*
G01X-1394835D02*
X-1398116D01*
G01X-1383762D02*
X-1385813D01*
G01X-1377200D02*
X-1379251D01*
G01X-1370639D02*
X-1372689D01*
G01X-1393605Y956215D02*
X-1395655Y956634D01*
G01X-1416980Y958310D02*
X-1419031Y958728D01*
G01X-1393194Y947839D02*
X-1395655Y948258D01*
G01X-1396065Y958728D02*
X-1393194Y958310D01*
G01X-1373509Y952446D02*
X-1372279Y952027D01*
G01X-1380071Y952446D02*
X-1378841Y952027D01*
G01X-1417391Y956215D02*
X-1418621Y956634D01*
G01X-1398116Y939043D02*
X-1399756Y939462D01*
G01X-1423132Y946582D02*
X-1421082Y946163D01*
G01X-1399756Y941556D02*
X-1397706Y941138D01*
G01X-1422722Y939462D02*
X-1420671Y939043D01*
G01X-1373509Y950352D02*
X-1374330Y950771D01*
G01X-1393194Y958310D02*
X-1391554Y957472D01*
G01X-1380071Y950352D02*
X-1380891Y950771D01*
G01X-1392374Y949095D02*
X-1390324Y948258D01*
G01X-1422722Y948676D02*
X-1421492Y948258D01*
G01X-1421082Y941138D02*
X-1422312Y941556D01*
G01X-1392374Y955378D02*
X-1393605Y956215D01*
G01X-1391964Y947001D02*
X-1393194Y947839D01*
G01X-1416160Y955378D02*
X-1417391Y956215D01*
G01X-1414930Y957053D02*
X-1416980Y958310D01*
G01X-1425183Y947839D02*
X-1423132Y946582D01*
G01X-1431334Y944907D02*
X-1439126Y949095D01*
G01X-1400576Y941975D02*
X-1399756Y941556D01*
G01Y939462D02*
X-1401397Y940300D01*
G01X-1436255Y949095D02*
X-1430514Y946163D01*
G01X-1372279Y952027D02*
X-1371459Y951189D01*
G01X-1373099Y949933D02*
X-1373509Y950352D01*
G01X-1378841Y952027D02*
X-1377610Y950771D01*
G01X-1379661Y949933D02*
X-1380071Y950352D01*
G01X-1391554Y957472D02*
X-1389914Y955797D01*
G01X-1401397Y940300D02*
X-1402627Y941138D01*
G01X-1423952Y949514D02*
X-1422722Y948676D01*
G01X-1422312Y941556D02*
X-1423542Y942394D01*
G01X-1424772Y940719D02*
X-1422722Y939462D01*
G01X-1401397Y942813D02*
X-1400576Y941975D01*
G01X-1371459Y951189D02*
X-1370639Y949095D01*
G01X-1372689D02*
X-1373099Y949933D01*
G01X-1379251Y949095D02*
X-1379661Y949933D01*
G01X-1391144Y945326D02*
X-1391964Y947001D01*
G01X-1391554Y954121D02*
X-1392374Y955378D01*
G01X-1390324Y948258D02*
X-1389503Y947001D01*
G01X-1402627Y941138D02*
X-1403447Y942394D01*
G01X-1415340Y954121D02*
X-1416160Y955378D01*
G01X-1424772Y950771D02*
X-1423952Y949514D01*
G01X-1423542Y942394D02*
X-1424362Y943650D01*
G01X-1431334Y953284D02*
X-1430514Y952027D01*
G01X-1413700Y955378D02*
X-1414930Y957053D01*
G01X-1426413Y949514D02*
X-1425183Y947839D01*
G01X-1426003Y942394D02*
X-1424772Y940719D01*
G01X-1376380Y952027D02*
X-1375150Y952446D01*
G01X-1381711Y950771D02*
X-1382942Y950352D01*
G01Y952027D02*
X-1381711Y952446D01*
G01X-1417391Y941556D02*
X-1418621Y941138D01*
G01X-1395655Y949933D02*
X-1393194Y950771D01*
G01X-1418621Y948258D02*
X-1417391Y948676D01*
G01X-1421492Y956634D02*
X-1422722Y956215D01*
G01X-1391554Y940300D02*
X-1393194Y939462D01*
G01X-1389914Y955797D02*
X-1389503Y954121D01*
G01Y947001D02*
X-1389093Y945326D01*
G01X-1403447Y942394D02*
X-1403857Y943650D01*
G01X-1414930Y952865D02*
X-1415340Y954121D01*
G01X-1412879Y953284D02*
X-1413700Y955378D01*
G01X-1427233Y951608D02*
X-1426413Y949514D01*
G01X-1401807Y943650D02*
X-1401397Y942813D01*
G01X-1393194Y941556D02*
X-1392374Y941975D01*
G01X-1375560Y950771D02*
X-1376380Y950352D01*
G01X-1401397Y957472D02*
X-1399756Y958310D01*
G01X-1430514Y952027D02*
X-1436255Y949095D01*
G01X-1439126D02*
X-1431334Y953284D01*
G01X-1416980Y939462D02*
X-1414930Y940719D01*
G01X-1390324Y941138D02*
X-1391554Y940300D01*
G01X-1416160Y942394D02*
X-1417391Y941556D01*
G01X-1399346Y956215D02*
X-1400576Y955378D01*
G01X-1390734Y950352D02*
X-1392374Y949095D01*
G01X-1370639D02*
Y939043D01*
G01X-1412469Y950352D02*
X-1412879Y953284D01*
G01X-1425183Y952027D02*
X-1424772Y950771D01*
G01X-1426413Y943650D02*
X-1426003Y942394D01*
G01X-1423132Y958310D02*
X-1425183Y957053D01*
G01X-1416980Y946582D02*
X-1414520Y948258D01*
G01X-1417391Y948676D02*
X-1416160Y949514D01*
G01X-1422722Y956215D02*
X-1423952Y955378D01*
G01X-1376380Y950352D02*
X-1376790Y949933D01*
G01X-1377610Y950771D02*
X-1376380Y952027D01*
G01X-1382942Y950352D02*
X-1383762Y949514D01*
G01X-1392374Y941975D02*
X-1391554Y942813D01*
G01X-1383762Y951189D02*
X-1382942Y952027D01*
G01X-1393194Y950771D02*
X-1392374Y951608D01*
G01X-1403037Y955797D02*
X-1401397Y957472D01*
G01X-1389503Y942394D02*
X-1390324Y941138D01*
G01X-1389914Y951608D02*
X-1390734Y950352D01*
G01X-1376790Y949933D02*
X-1377200Y949095D01*
G01X-1391554Y942813D02*
X-1391144Y943650D01*
G01X-1392374Y951608D02*
X-1391554Y953284D01*
G01X-1389093Y943650D02*
X-1389503Y942394D01*
G01Y953284D02*
X-1389914Y951608D01*
G01X-1372689Y939043D02*
Y949095D01*
G01X-1377200D02*
Y939043D01*
G01X-1379251D02*
Y949095D01*
G01X-1383762Y949514D02*
Y939043D01*
G01Y952446D02*
Y951189D01*
G01X-1385813Y939043D02*
Y952446D01*
G01X-1389093Y945326D02*
Y943650D01*
G01X-1389503Y954121D02*
Y953284D01*
G01X-1391144Y943650D02*
Y945326D01*
G01X-1391554Y953284D02*
Y954121D01*
G01X-1397295Y948258D02*
Y949933D01*
G01X-1407138Y941138D02*
Y939043D01*
G01X-1409188D02*
Y941138D01*
G01X-1414930Y940719D02*
X-1413700Y942394D01*
G01X-1425183Y957053D02*
X-1426413Y955378D01*
G01X-1400576D02*
X-1401397Y954121D01*
G01X-1415340Y943650D02*
X-1416160Y942394D01*
G01Y949514D02*
X-1415340Y950771D01*
G01X-1423952Y955378D02*
X-1424772Y954121D01*
G01X-1430514Y946163D02*
X-1431334Y944907D01*
G01X-1413700Y942394D02*
X-1412879Y944488D01*
G01X-1426413Y955378D02*
X-1427233Y953284D01*
G01X-1414930Y944907D02*
X-1415340Y943650D01*
G01Y950771D02*
X-1414930Y952027D01*
G01X-1424772Y954121D02*
X-1425183Y952865D01*
G01X-1403447Y954121D02*
X-1403037Y955797D01*
G01X-1414520Y947420D02*
X-1414930Y944907D01*
G01X-1412879Y944488D02*
X-1412469Y947420D01*
G01D02*
Y950352D01*
G01X-1414520Y948258D02*
Y947420D01*
G01X-1414930Y952027D02*
Y952865D01*
G01X-1425183D02*
Y952027D01*
G01X-1427233Y953284D02*
Y951608D01*
G01X-1372956Y1006834D02*
Y1081637D01*
G01X-1395097Y1139511D02*
X-1395357D01*
G01X-1392879D02*
X-1393140D01*
G01X-1373425Y1082277D02*
X-1373341Y1082293D01*
G01Y1082211D02*
X-1373425Y1082195D01*
G01X-1373743Y1083606D02*
X-1372956D01*
G01X-1373040Y1083507D02*
X-1373291D01*
G01X-1373391D02*
X-1373743D01*
G01X-1373190Y1083097D02*
X-1373140D01*
G01Y1082999D02*
X-1373207D01*
G01X-1373040Y1082867D02*
X-1372956D01*
G01X-1373743D02*
X-1373207D01*
G01X-1372956Y1082785D02*
X-1373040D01*
G01X-1373207D02*
X-1373743D01*
G01Y1082654D02*
X-1373207D01*
G01Y1082572D02*
X-1373291D01*
G01X-1373358D02*
X-1373743D01*
G01Y1082277D02*
X-1373425D01*
G01Y1082195D02*
X-1373743D01*
G01X-1373207Y1082064D02*
X-1373073D01*
G01X-1373743Y1081965D02*
X-1373090D01*
G01X-1372956Y1081867D02*
X-1373743D01*
G01Y1080850D02*
X-1377680D01*
G01X-1373241Y1083114D02*
X-1373190Y1083097D01*
G01X-1373207Y1082999D02*
X-1373257Y1083015D01*
G01X-1373073Y1082064D02*
X-1372956Y1081965D01*
G01X-1373090D02*
X-1373207Y1082064D01*
G01X-1373257Y1083015D02*
X-1373324Y1083064D01*
G01X-1377680Y1080850D02*
X-1373743Y1076913D01*
G01X-1373274Y1083146D02*
X-1373241Y1083114D01*
G01X-1373291Y1082572D02*
X-1373257Y1082539D01*
G01X-1373324D02*
X-1373358Y1082572D01*
G01X-1373257Y1082539D02*
X-1373224Y1082490D01*
G01X-1373291D02*
X-1373324Y1082539D01*
G01Y1083064D02*
X-1373375Y1083130D01*
G01X-1373291Y1083196D02*
X-1373274Y1083146D01*
G01X-1373375Y1083130D02*
X-1373391Y1083212D01*
G01X-1373224Y1082490D02*
X-1373207Y1082425D01*
G01X-1373274D02*
X-1373291Y1082490D01*
G01X-1372956Y1081965D02*
Y1081867D01*
G01Y1082867D02*
Y1082785D01*
G01Y1083606D02*
Y1083212D01*
G01X-1373040Y1082785D02*
Y1082867D01*
G01Y1083196D02*
Y1083507D01*
G01X-1373207Y1082654D02*
Y1082572D01*
G01Y1082425D02*
Y1082359D01*
G01Y1082867D02*
Y1082785D01*
G01X-1373291Y1083507D02*
Y1083196D01*
G01X-1373391Y1083212D02*
Y1083507D01*
G01X-1373743Y1082572D02*
Y1082654D01*
G01Y1082785D02*
Y1082867D01*
G01Y1083507D02*
Y1083606D01*
G01Y1081867D02*
Y1081965D01*
G01Y1082195D02*
Y1082277D01*
G01Y1076913D02*
Y1080850D01*
G01X-1392879Y1141598D02*
Y1139511D01*
G01X-1393140D02*
Y1141243D01*
G01X-1395097Y1140443D02*
Y1139511D01*
G01X-1395357D02*
Y1141598D01*
G01X-1373291Y1082228D02*
X-1373341Y1082211D01*
G01X-1373090Y1083015D02*
X-1373140Y1082999D01*
G01Y1083097D02*
X-1373090Y1083114D01*
G01X-1373207Y1082359D02*
X-1373224Y1082310D01*
G01X-1373056Y1083146D02*
X-1373040Y1083196D01*
G01X-1373291Y1082359D02*
X-1373274Y1082425D01*
G01X-1372956Y1083212D02*
X-1372973Y1083130D01*
G01X-1373023Y1083064D02*
X-1373090Y1083015D01*
G01X-1373257Y1082260D02*
X-1373291Y1082228D01*
G01X-1373341Y1082293D02*
X-1373308Y1082326D01*
G01X-1373090Y1083114D02*
X-1373056Y1083146D01*
G01X-1372973Y1083130D02*
X-1373023Y1083064D01*
G01X-1373224Y1082310D02*
X-1373257Y1082260D01*
G01X-1373308Y1082326D02*
X-1373291Y1082359D01*
G01X-1393672Y1107976D02*
X-1381861D01*
G01X-1426823Y1141232D02*
X-1393672Y1107976D01*
G01X-1434964Y1146598D02*
Y1179043D01*
G01X-1431986Y1155105D02*
X-1402935Y1276519D01*
G01X-1402955Y1158225D02*
X-1402972Y1158040D01*
G01X-1402900Y1158413D02*
X-1402955Y1158225D01*
G01X-1402802Y1158597D02*
X-1402900Y1158413D01*
G01X-1402662Y1158763D02*
X-1402802Y1158597D01*
G01X-1391900Y1155905D02*
X-1391985Y1155877D01*
G01X-1391819Y1155938D02*
X-1391900Y1155905D01*
G01X-1391740Y1155976D02*
X-1391819Y1155938D01*
G01X-1391664Y1156019D02*
X-1391740Y1155976D01*
G01X-1391591Y1156066D02*
X-1391664Y1156019D01*
G01X-1391525Y1156114D02*
X-1391591Y1156066D01*
G01X-1391021Y1158879D02*
X-1391003Y1158882D01*
G01X-1391041Y1158869D02*
X-1391021Y1158879D01*
G01X-1391064Y1158853D02*
X-1391041Y1158869D01*
G01X-1393298Y1159413D02*
X-1393139Y1159432D01*
G01X-1393449Y1159356D02*
X-1393298Y1159413D01*
G01X-1393582Y1159265D02*
X-1393449Y1159356D01*
G01X-1389358Y1159413D02*
X-1389199Y1159432D01*
G01X-1389509Y1159356D02*
X-1389358Y1159413D01*
G01X-1389642Y1159265D02*
X-1389509Y1159356D01*
G01X-1393170Y1158879D02*
X-1393139Y1158882D01*
G01X-1393199Y1158869D02*
X-1393170Y1158879D01*
G01X-1393225Y1158853D02*
X-1393199Y1158869D01*
G01X-1387960Y1155905D02*
X-1388045Y1155877D01*
G01X-1387879Y1155938D02*
X-1387960Y1155905D01*
G01X-1387800Y1155976D02*
X-1387879Y1155938D01*
G01X-1387724Y1156019D02*
X-1387800Y1155976D01*
G01X-1387651Y1156066D02*
X-1387724Y1156019D01*
G01X-1387585Y1156114D02*
X-1387651Y1156066D01*
G01X-1394704Y1150676D02*
X-1394619Y1150705D01*
G01X-1394785Y1150643D02*
X-1394704Y1150676D01*
G01X-1394864Y1150605D02*
X-1394785Y1150643D01*
G01X-1394940Y1150563D02*
X-1394864Y1150605D01*
G01X-1395013Y1150515D02*
X-1394940Y1150563D01*
G01X-1395079Y1150467D02*
X-1395013Y1150515D01*
G01X-1384020Y1155905D02*
X-1384105Y1155877D01*
G01X-1383939Y1155938D02*
X-1384020Y1155905D01*
G01X-1383860Y1155976D02*
X-1383939Y1155938D01*
G01X-1383784Y1156019D02*
X-1383860Y1155976D01*
G01X-1383711Y1156066D02*
X-1383784Y1156019D01*
G01X-1383645Y1156114D02*
X-1383711Y1156066D01*
G01X-1390764Y1150676D02*
X-1390679Y1150705D01*
G01X-1390845Y1150643D02*
X-1390764Y1150676D01*
G01X-1390924Y1150605D02*
X-1390845Y1150643D01*
G01X-1391000Y1150563D02*
X-1390924Y1150605D01*
G01X-1391073Y1150515D02*
X-1391000Y1150563D01*
G01X-1391139Y1150467D02*
X-1391073Y1150515D01*
G01X-1380080Y1155905D02*
X-1380165Y1155877D01*
G01X-1379999Y1155938D02*
X-1380080Y1155905D01*
G01X-1379920Y1155976D02*
X-1379999Y1155938D01*
G01X-1379844Y1156019D02*
X-1379920Y1155976D01*
G01X-1379771Y1156066D02*
X-1379844Y1156019D01*
G01X-1379705Y1156114D02*
X-1379771Y1156066D01*
G01X-1386824Y1150676D02*
X-1386739Y1150705D01*
G01X-1386905Y1150643D02*
X-1386824Y1150676D01*
G01X-1386984Y1150605D02*
X-1386905Y1150643D01*
G01X-1387060Y1150563D02*
X-1386984Y1150605D01*
G01X-1387133Y1150515D02*
X-1387060Y1150563D01*
G01X-1387199Y1150467D02*
X-1387133Y1150515D01*
G01X-1376140Y1155905D02*
X-1376225Y1155877D01*
G01X-1376059Y1155938D02*
X-1376140Y1155905D01*
G01X-1375980Y1155976D02*
X-1376059Y1155938D01*
G01X-1375904Y1156019D02*
X-1375980Y1155976D01*
G01X-1375831Y1156066D02*
X-1375904Y1156019D01*
G01X-1375765Y1156114D02*
X-1375831Y1156066D01*
G01X-1382884Y1150676D02*
X-1382799Y1150705D01*
G01X-1382965Y1150643D02*
X-1382884Y1150676D01*
G01X-1383044Y1150605D02*
X-1382965Y1150643D01*
G01X-1383120Y1150563D02*
X-1383044Y1150605D01*
G01X-1383193Y1150515D02*
X-1383120Y1150563D01*
G01X-1383259Y1150467D02*
X-1383193Y1150515D01*
G01X-1378944Y1150676D02*
X-1378859Y1150705D01*
G01X-1379025Y1150643D02*
X-1378944Y1150676D01*
G01X-1379104Y1150605D02*
X-1379025Y1150643D01*
G01X-1379180Y1150563D02*
X-1379104Y1150605D01*
G01X-1379253Y1150515D02*
X-1379180Y1150563D01*
G01X-1379319Y1150467D02*
X-1379253Y1150515D01*
G01X-1375004Y1150676D02*
X-1374919Y1150705D01*
G01X-1375085Y1150643D02*
X-1375004Y1150676D01*
G01X-1375164Y1150605D02*
X-1375085Y1150643D01*
G01X-1375240Y1150563D02*
X-1375164Y1150605D01*
G01X-1375313Y1150515D02*
X-1375240Y1150563D01*
G01X-1375379Y1150467D02*
X-1375313Y1150515D01*
G01X-1387081Y1158879D02*
X-1387063Y1158882D01*
G01X-1387101Y1158869D02*
X-1387081Y1158879D01*
G01X-1387124Y1158853D02*
X-1387101Y1158869D01*
G01X-1383141Y1158879D02*
X-1383123Y1158882D01*
G01X-1383161Y1158869D02*
X-1383141Y1158879D01*
G01X-1383184Y1158853D02*
X-1383161Y1158869D01*
G01X-1395582Y1147702D02*
X-1395600Y1147699D01*
G01X-1395563Y1147712D02*
X-1395582Y1147702D01*
G01X-1395540Y1147729D02*
X-1395563Y1147712D01*
G01X-1379201Y1158879D02*
X-1379183Y1158882D01*
G01X-1379221Y1158869D02*
X-1379201Y1158879D01*
G01X-1379244Y1158853D02*
X-1379221Y1158869D01*
G01X-1391642Y1147702D02*
X-1391660Y1147699D01*
G01X-1391623Y1147712D02*
X-1391642Y1147702D01*
G01X-1391600Y1147729D02*
X-1391623Y1147712D01*
G01X-1375261Y1158879D02*
X-1375243Y1158882D01*
G01X-1375281Y1158869D02*
X-1375261Y1158879D01*
G01X-1375304Y1158853D02*
X-1375281Y1158869D01*
G01X-1387702Y1147702D02*
X-1387720Y1147699D01*
G01X-1387683Y1147712D02*
X-1387702Y1147702D01*
G01X-1387660Y1147729D02*
X-1387683Y1147712D01*
G01X-1383762Y1147702D02*
X-1383780Y1147699D01*
G01X-1383743Y1147712D02*
X-1383762Y1147702D01*
G01X-1383720Y1147729D02*
X-1383743Y1147712D01*
G01X-1379822Y1147702D02*
X-1379840Y1147699D01*
G01X-1379803Y1147712D02*
X-1379822Y1147702D01*
G01X-1379780Y1147729D02*
X-1379803Y1147712D01*
G01X-1375882Y1147702D02*
X-1375900Y1147699D01*
G01X-1375863Y1147712D02*
X-1375882Y1147702D01*
G01X-1375840Y1147729D02*
X-1375863Y1147712D01*
G01X-1385418Y1159413D02*
X-1385259Y1159432D01*
G01X-1385569Y1159356D02*
X-1385418Y1159413D01*
G01X-1385702Y1159265D02*
X-1385569Y1159356D01*
G01X-1381478Y1159413D02*
X-1381319Y1159432D01*
G01X-1381629Y1159356D02*
X-1381478Y1159413D01*
G01X-1381762Y1159265D02*
X-1381629Y1159356D01*
G01X-1377538Y1159413D02*
X-1377379Y1159432D01*
G01X-1377689Y1159356D02*
X-1377538Y1159413D01*
G01X-1377822Y1159265D02*
X-1377689Y1159356D01*
G01X-1393305Y1147168D02*
X-1393465Y1147149D01*
G01X-1393155Y1147225D02*
X-1393305Y1147168D01*
G01X-1393022Y1147317D02*
X-1393155Y1147225D01*
G01X-1389365Y1147168D02*
X-1389525Y1147149D01*
G01X-1389215Y1147225D02*
X-1389365Y1147168D01*
G01X-1389082Y1147317D02*
X-1389215Y1147225D01*
G01X-1385425Y1147168D02*
X-1385585Y1147149D01*
G01X-1385275Y1147225D02*
X-1385425Y1147168D01*
G01X-1385142Y1147317D02*
X-1385275Y1147225D01*
G01X-1381485Y1147168D02*
X-1381645Y1147149D01*
G01X-1381335Y1147225D02*
X-1381485Y1147168D01*
G01X-1381202Y1147317D02*
X-1381335Y1147225D01*
G01X-1377545Y1147168D02*
X-1377705Y1147149D01*
G01X-1377395Y1147225D02*
X-1377545Y1147168D01*
G01X-1377262Y1147317D02*
X-1377395Y1147225D01*
G01X-1373605Y1147168D02*
X-1373765Y1147149D01*
G01X-1373455Y1147225D02*
X-1373605Y1147168D01*
G01X-1373322Y1147317D02*
X-1373455Y1147225D01*
G01X-1389230Y1158879D02*
X-1389199Y1158882D01*
G01X-1389259Y1158869D02*
X-1389230Y1158879D01*
G01X-1389285Y1158853D02*
X-1389259Y1158869D01*
G01X-1385290Y1158879D02*
X-1385259Y1158882D01*
G01X-1385319Y1158869D02*
X-1385290Y1158879D01*
G01X-1385345Y1158853D02*
X-1385319Y1158869D01*
G01X-1381350Y1158879D02*
X-1381319Y1158882D01*
G01X-1381379Y1158869D02*
X-1381350Y1158879D01*
G01X-1381405Y1158853D02*
X-1381379Y1158869D01*
G01X-1377410Y1158879D02*
X-1377379Y1158882D01*
G01X-1377439Y1158869D02*
X-1377410Y1158879D01*
G01X-1377465Y1158853D02*
X-1377439Y1158869D01*
G01X-1393434Y1147702D02*
X-1393465Y1147699D01*
G01X-1393405Y1147712D02*
X-1393434Y1147702D01*
G01X-1393379Y1147729D02*
X-1393405Y1147712D01*
G01X-1389494Y1147702D02*
X-1389525Y1147699D01*
G01X-1389465Y1147712D02*
X-1389494Y1147702D01*
G01X-1389439Y1147729D02*
X-1389465Y1147712D01*
G01X-1385554Y1147702D02*
X-1385585Y1147699D01*
G01X-1385525Y1147712D02*
X-1385554Y1147702D01*
G01X-1385499Y1147729D02*
X-1385525Y1147712D01*
G01X-1381614Y1147702D02*
X-1381645Y1147699D01*
G01X-1381585Y1147712D02*
X-1381614Y1147702D01*
G01X-1381559Y1147729D02*
X-1381585Y1147712D01*
G01X-1377674Y1147702D02*
X-1377705Y1147699D01*
G01X-1377645Y1147712D02*
X-1377674Y1147702D01*
G01X-1377619Y1147729D02*
X-1377645Y1147712D01*
G01X-1373734Y1147702D02*
X-1373765Y1147699D01*
G01X-1373705Y1147712D02*
X-1373734Y1147702D01*
G01X-1373679Y1147729D02*
X-1373705Y1147712D01*
G01X-1391900Y1155624D02*
X-1391985Y1155601D01*
G01X-1391819Y1155651D02*
X-1391900Y1155624D01*
G01X-1391740Y1155682D02*
X-1391819Y1155651D01*
G01X-1391664Y1155717D02*
X-1391740Y1155682D01*
G01X-1391591Y1155755D02*
X-1391664Y1155717D01*
G01X-1391525Y1155795D02*
X-1391591Y1155755D01*
G01X-1387960Y1155624D02*
X-1388045Y1155601D01*
G01X-1387879Y1155651D02*
X-1387960Y1155624D01*
G01X-1387800Y1155682D02*
X-1387879Y1155651D01*
G01X-1387724Y1155717D02*
X-1387800Y1155682D01*
G01X-1387651Y1155755D02*
X-1387724Y1155717D01*
G01X-1387585Y1155795D02*
X-1387651Y1155755D01*
G01X-1394704Y1150957D02*
X-1394619Y1150981D01*
G01X-1394785Y1150930D02*
X-1394704Y1150957D01*
G01X-1394864Y1150899D02*
X-1394785Y1150930D01*
G01X-1394940Y1150864D02*
X-1394864Y1150899D01*
G01X-1395013Y1150826D02*
X-1394940Y1150864D01*
G01X-1395079Y1150786D02*
X-1395013Y1150826D01*
G01X-1384020Y1155624D02*
X-1384105Y1155601D01*
G01X-1383939Y1155651D02*
X-1384020Y1155624D01*
G01X-1383860Y1155682D02*
X-1383939Y1155651D01*
G01X-1383784Y1155717D02*
X-1383860Y1155682D01*
G01X-1383711Y1155755D02*
X-1383784Y1155717D01*
G01X-1383645Y1155795D02*
X-1383711Y1155755D01*
G01X-1390764Y1150957D02*
X-1390679Y1150981D01*
G01X-1390845Y1150930D02*
X-1390764Y1150957D01*
G01X-1390924Y1150899D02*
X-1390845Y1150930D01*
G01X-1391000Y1150864D02*
X-1390924Y1150899D01*
G01X-1391073Y1150826D02*
X-1391000Y1150864D01*
G01X-1391139Y1150786D02*
X-1391073Y1150826D01*
G01X-1380080Y1155624D02*
X-1380165Y1155601D01*
G01X-1379999Y1155651D02*
X-1380080Y1155624D01*
G01X-1379920Y1155682D02*
X-1379999Y1155651D01*
G01X-1379844Y1155717D02*
X-1379920Y1155682D01*
G01X-1379771Y1155755D02*
X-1379844Y1155717D01*
G01X-1379705Y1155795D02*
X-1379771Y1155755D01*
G01X-1386824Y1150957D02*
X-1386739Y1150981D01*
G01X-1386905Y1150930D02*
X-1386824Y1150957D01*
G01X-1386984Y1150899D02*
X-1386905Y1150930D01*
G01X-1387060Y1150864D02*
X-1386984Y1150899D01*
G01X-1387133Y1150826D02*
X-1387060Y1150864D01*
G01X-1387199Y1150786D02*
X-1387133Y1150826D01*
G01X-1376140Y1155624D02*
X-1376225Y1155601D01*
G01X-1376059Y1155651D02*
X-1376140Y1155624D01*
G01X-1375980Y1155682D02*
X-1376059Y1155651D01*
G01X-1375904Y1155717D02*
X-1375980Y1155682D01*
G01X-1375831Y1155755D02*
X-1375904Y1155717D01*
G01X-1375765Y1155795D02*
X-1375831Y1155755D01*
G01X-1382884Y1150957D02*
X-1382799Y1150981D01*
G01X-1382965Y1150930D02*
X-1382884Y1150957D01*
G01X-1383044Y1150899D02*
X-1382965Y1150930D01*
G01X-1383120Y1150864D02*
X-1383044Y1150899D01*
G01X-1383193Y1150826D02*
X-1383120Y1150864D01*
G01X-1383259Y1150786D02*
X-1383193Y1150826D01*
G01X-1378944Y1150957D02*
X-1378859Y1150981D01*
G01X-1379025Y1150930D02*
X-1378944Y1150957D01*
G01X-1379104Y1150899D02*
X-1379025Y1150930D01*
G01X-1379180Y1150864D02*
X-1379104Y1150899D01*
G01X-1379253Y1150826D02*
X-1379180Y1150864D01*
G01X-1379319Y1150786D02*
X-1379253Y1150826D01*
G01X-1375004Y1150957D02*
X-1374919Y1150981D01*
G01X-1375085Y1150930D02*
X-1375004Y1150957D01*
G01X-1375164Y1150899D02*
X-1375085Y1150930D01*
G01X-1375240Y1150864D02*
X-1375164Y1150899D01*
G01X-1375313Y1150826D02*
X-1375240Y1150864D01*
G01X-1375379Y1150786D02*
X-1375313Y1150826D01*
G01X-1391596Y1155611D02*
X-1391525Y1155663D01*
G01X-1391670Y1155564D02*
X-1391596Y1155611D01*
G01X-1391746Y1155522D02*
X-1391670Y1155564D01*
G01X-1391825Y1155485D02*
X-1391746Y1155522D01*
G01X-1391906Y1155452D02*
X-1391825Y1155485D01*
G01X-1391985Y1155426D02*
X-1391906Y1155452D01*
G01X-1387656Y1155611D02*
X-1387585Y1155663D01*
G01X-1387730Y1155564D02*
X-1387656Y1155611D01*
G01X-1387806Y1155522D02*
X-1387730Y1155564D01*
G01X-1387885Y1155485D02*
X-1387806Y1155522D01*
G01X-1387966Y1155452D02*
X-1387885Y1155485D01*
G01X-1388045Y1155426D02*
X-1387966Y1155452D01*
G01X-1383716Y1155611D02*
X-1383645Y1155663D01*
G01X-1383790Y1155564D02*
X-1383716Y1155611D01*
G01X-1383866Y1155522D02*
X-1383790Y1155564D01*
G01X-1383945Y1155485D02*
X-1383866Y1155522D01*
G01X-1384026Y1155452D02*
X-1383945Y1155485D01*
G01X-1384105Y1155426D02*
X-1384026Y1155452D01*
G01X-1395007Y1150970D02*
X-1395079Y1150918D01*
G01X-1394934Y1151017D02*
X-1395007Y1150970D01*
G01X-1394858Y1151059D02*
X-1394934Y1151017D01*
G01X-1394779Y1151097D02*
X-1394858Y1151059D01*
G01X-1394697Y1151129D02*
X-1394779Y1151097D01*
G01X-1394619Y1151156D02*
X-1394697Y1151129D01*
G01X-1379776Y1155611D02*
X-1379705Y1155663D01*
G01X-1379850Y1155564D02*
X-1379776Y1155611D01*
G01X-1379926Y1155522D02*
X-1379850Y1155564D01*
G01X-1380005Y1155485D02*
X-1379926Y1155522D01*
G01X-1380086Y1155452D02*
X-1380005Y1155485D01*
G01X-1380165Y1155426D02*
X-1380086Y1155452D01*
G01X-1391067Y1150970D02*
X-1391139Y1150918D01*
G01X-1390994Y1151017D02*
X-1391067Y1150970D01*
G01X-1390918Y1151059D02*
X-1390994Y1151017D01*
G01X-1390839Y1151097D02*
X-1390918Y1151059D01*
G01X-1390757Y1151129D02*
X-1390839Y1151097D01*
G01X-1390679Y1151156D02*
X-1390757Y1151129D01*
G01X-1375836Y1155611D02*
X-1375765Y1155663D01*
G01X-1375910Y1155564D02*
X-1375836Y1155611D01*
G01X-1375986Y1155522D02*
X-1375910Y1155564D01*
G01X-1376065Y1155485D02*
X-1375986Y1155522D01*
G01X-1376146Y1155452D02*
X-1376065Y1155485D01*
G01X-1376225Y1155426D02*
X-1376146Y1155452D01*
G01X-1387127Y1150970D02*
X-1387199Y1150918D01*
G01X-1387054Y1151017D02*
X-1387127Y1150970D01*
G01X-1386978Y1151059D02*
X-1387054Y1151017D01*
G01X-1386899Y1151097D02*
X-1386978Y1151059D01*
G01X-1386817Y1151129D02*
X-1386899Y1151097D01*
G01X-1386739Y1151156D02*
X-1386817Y1151129D01*
G01X-1383187Y1150970D02*
X-1383259Y1150918D01*
G01X-1383114Y1151017D02*
X-1383187Y1150970D01*
G01X-1383038Y1151059D02*
X-1383114Y1151017D01*
G01X-1382959Y1151097D02*
X-1383038Y1151059D01*
G01X-1382877Y1151129D02*
X-1382959Y1151097D01*
G01X-1382799Y1151156D02*
X-1382877Y1151129D01*
G01X-1379247Y1150970D02*
X-1379319Y1150918D01*
G01X-1379174Y1151017D02*
X-1379247Y1150970D01*
G01X-1379098Y1151059D02*
X-1379174Y1151017D01*
G01X-1379019Y1151097D02*
X-1379098Y1151059D01*
G01X-1378937Y1151129D02*
X-1379019Y1151097D01*
G01X-1378859Y1151156D02*
X-1378937Y1151129D01*
G01X-1375307Y1150970D02*
X-1375379Y1150918D01*
G01X-1375234Y1151017D02*
X-1375307Y1150970D01*
G01X-1375158Y1151059D02*
X-1375234Y1151017D01*
G01X-1375079Y1151097D02*
X-1375158Y1151059D01*
G01X-1374997Y1151129D02*
X-1375079Y1151097D01*
G01X-1374919Y1151156D02*
X-1374997Y1151129D01*
G01X-1395587Y1147665D02*
X-1395557Y1147708D01*
G01X-1395599Y1147634D02*
X-1395587Y1147665D01*
G01X-1395600Y1147623D02*
X-1395599Y1147634D01*
G01X-1391017Y1158916D02*
X-1391046Y1158873D01*
G01X-1391005Y1158947D02*
X-1391017Y1158916D01*
G01X-1391003Y1158958D02*
X-1391005Y1158947D01*
G01X-1391647Y1147665D02*
X-1391617Y1147708D01*
G01X-1391659Y1147634D02*
X-1391647Y1147665D01*
G01X-1391660Y1147623D02*
X-1391659Y1147634D01*
G01X-1387077Y1158916D02*
X-1387106Y1158873D01*
G01X-1387065Y1158947D02*
X-1387077Y1158916D01*
G01X-1387063Y1158958D02*
X-1387065Y1158947D01*
G01X-1387707Y1147665D02*
X-1387677Y1147708D01*
G01X-1387719Y1147634D02*
X-1387707Y1147665D01*
G01X-1387720Y1147623D02*
X-1387719Y1147634D01*
G01X-1383137Y1158916D02*
X-1383166Y1158873D01*
G01X-1383125Y1158947D02*
X-1383137Y1158916D01*
G01X-1383123Y1158958D02*
X-1383125Y1158947D01*
G01X-1383767Y1147665D02*
X-1383737Y1147708D01*
G01X-1383779Y1147634D02*
X-1383767Y1147665D01*
G01X-1383780Y1147623D02*
X-1383779Y1147634D01*
G01X-1379197Y1158916D02*
X-1379226Y1158873D01*
G01X-1379185Y1158947D02*
X-1379197Y1158916D01*
G01X-1379183Y1158958D02*
X-1379185Y1158947D01*
G01X-1379827Y1147665D02*
X-1379797Y1147708D01*
G01X-1379839Y1147634D02*
X-1379827Y1147665D01*
G01X-1379840Y1147623D02*
X-1379839Y1147634D01*
G01X-1375257Y1158916D02*
X-1375286Y1158873D01*
G01X-1375245Y1158947D02*
X-1375257Y1158916D01*
G01X-1375243Y1158958D02*
X-1375245Y1158947D01*
G01X-1375887Y1147665D02*
X-1375857Y1147708D01*
G01X-1375899Y1147634D02*
X-1375887Y1147665D01*
G01X-1375900Y1147623D02*
X-1375899Y1147634D01*
G01X-1393457Y1147149D02*
X-1393454D01*
G01X-1393460D02*
X-1393457D01*
G01X-1393462Y1147150D02*
X-1393460Y1147149D01*
G01X-1393464Y1147151D02*
X-1393462Y1147150D01*
G01X-1393464Y1147152D02*
Y1147151D01*
G01X-1393465Y1147153D02*
X-1393464Y1147152D01*
G01X-1393146Y1159432D02*
X-1393150D01*
G01X-1393144D02*
X-1393146D01*
G01X-1393142D02*
X-1393144D01*
G01X-1393140Y1159431D02*
X-1393142Y1159432D01*
G01X-1393139Y1159430D02*
X-1393140Y1159431D01*
G01X-1393139Y1159429D02*
Y1159430D01*
G01X-1389517Y1147149D02*
X-1389514D01*
G01X-1389520D02*
X-1389517D01*
G01X-1389522Y1147150D02*
X-1389520Y1147149D01*
G01X-1389524Y1147151D02*
X-1389522Y1147150D01*
G01X-1389524Y1147152D02*
Y1147151D01*
G01X-1389525Y1147153D02*
X-1389524Y1147152D01*
G01X-1389206Y1159432D02*
X-1389210D01*
G01X-1389204D02*
X-1389206D01*
G01X-1389202D02*
X-1389204D01*
G01X-1389200Y1159431D02*
X-1389202Y1159432D01*
G01X-1389199Y1159430D02*
X-1389200Y1159431D01*
G01X-1389199Y1159429D02*
Y1159430D01*
G01X-1385577Y1147149D02*
X-1385574D01*
G01X-1385580D02*
X-1385577D01*
G01X-1385582Y1147150D02*
X-1385580Y1147149D01*
G01X-1385584Y1147151D02*
X-1385582Y1147150D01*
G01X-1385584Y1147152D02*
Y1147151D01*
G01X-1385585Y1147153D02*
X-1385584Y1147152D01*
G01X-1385266Y1159432D02*
X-1385270D01*
G01X-1385264D02*
X-1385266D01*
G01X-1385262D02*
X-1385264D01*
G01X-1385260Y1159431D02*
X-1385262Y1159432D01*
G01X-1385259Y1159430D02*
X-1385260Y1159431D01*
G01X-1385259Y1159429D02*
Y1159430D01*
G01X-1381637Y1147149D02*
X-1381634D01*
G01X-1381640D02*
X-1381637D01*
G01X-1381642Y1147150D02*
X-1381640Y1147149D01*
G01X-1381644Y1147151D02*
X-1381642Y1147150D01*
G01X-1381644Y1147152D02*
Y1147151D01*
G01X-1381645Y1147153D02*
X-1381644Y1147152D01*
G01X-1381326Y1159432D02*
X-1381330D01*
G01X-1381324D02*
X-1381326D01*
G01X-1381322D02*
X-1381324D01*
G01X-1381320Y1159431D02*
X-1381322Y1159432D01*
G01X-1381319Y1159430D02*
X-1381320Y1159431D01*
G01X-1381319Y1159429D02*
Y1159430D01*
G01X-1377697Y1147149D02*
X-1377694D01*
G01X-1377700D02*
X-1377697D01*
G01X-1377702Y1147150D02*
X-1377700Y1147149D01*
G01X-1377704Y1147151D02*
X-1377702Y1147150D01*
G01X-1377704Y1147152D02*
Y1147151D01*
G01X-1377705Y1147153D02*
X-1377704Y1147152D01*
G01X-1377386Y1159432D02*
X-1377390D01*
G01X-1377384D02*
X-1377386D01*
G01X-1377382D02*
X-1377384D01*
G01X-1377380Y1159431D02*
X-1377382Y1159432D01*
G01X-1377379Y1159430D02*
X-1377380Y1159431D01*
G01X-1377379Y1159429D02*
Y1159430D01*
G01X-1373757Y1147149D02*
X-1373754D01*
G01X-1373760D02*
X-1373757D01*
G01X-1373762Y1147150D02*
X-1373760Y1147149D01*
G01X-1373764Y1147151D02*
X-1373762Y1147150D01*
G01X-1373764Y1147152D02*
Y1147151D01*
G01X-1373765Y1147153D02*
X-1373764Y1147152D01*
G01X-1392945Y1147634D02*
X-1392943Y1147623D01*
G01X-1392957Y1147665D02*
X-1392945Y1147634D01*
G01X-1392986Y1147708D02*
X-1392957Y1147665D01*
G01X-1389005Y1147634D02*
X-1389003Y1147623D01*
G01X-1389017Y1147665D02*
X-1389005Y1147634D01*
G01X-1389046Y1147708D02*
X-1389017Y1147665D01*
G01X-1393659Y1158947D02*
X-1393660Y1158958D01*
G01X-1393647Y1158916D02*
X-1393659Y1158947D01*
G01X-1393617Y1158873D02*
X-1393647Y1158916D01*
G01X-1385065Y1147634D02*
X-1385063Y1147623D01*
G01X-1385077Y1147665D02*
X-1385065Y1147634D01*
G01X-1385106Y1147708D02*
X-1385077Y1147665D01*
G01X-1389719Y1158947D02*
X-1389720Y1158958D01*
G01X-1389707Y1158916D02*
X-1389719Y1158947D01*
G01X-1389677Y1158873D02*
X-1389707Y1158916D01*
G01X-1381125Y1147634D02*
X-1381123Y1147623D01*
G01X-1381137Y1147665D02*
X-1381125Y1147634D01*
G01X-1381166Y1147708D02*
X-1381137Y1147665D01*
G01X-1402955Y1148357D02*
X-1402972Y1148542D01*
G01X-1402900Y1148169D02*
X-1402955Y1148357D01*
G01X-1402802Y1147985D02*
X-1402900Y1148169D01*
G01X-1402662Y1147818D02*
X-1402802Y1147985D01*
G01X-1385779Y1158947D02*
X-1385780Y1158958D01*
G01X-1385767Y1158916D02*
X-1385779Y1158947D01*
G01X-1385737Y1158873D02*
X-1385767Y1158916D01*
G01X-1377185Y1147634D02*
X-1377183Y1147623D01*
G01X-1377197Y1147665D02*
X-1377185Y1147634D01*
G01X-1377226Y1147708D02*
X-1377197Y1147665D01*
G01X-1381839Y1158947D02*
X-1381840Y1158958D01*
G01X-1381827Y1158916D02*
X-1381839Y1158947D01*
G01X-1381797Y1158873D02*
X-1381827Y1158916D01*
G01X-1373245Y1147634D02*
X-1373243Y1147623D01*
G01X-1373257Y1147665D02*
X-1373245Y1147634D01*
G01X-1373286Y1147708D02*
X-1373257Y1147665D01*
G01X-1377899Y1158947D02*
X-1377900Y1158958D01*
G01X-1377887Y1158916D02*
X-1377899Y1158947D01*
G01X-1377857Y1158873D02*
X-1377887Y1158916D01*
G01X-1379951Y1147168D02*
X-1379840Y1147149D01*
G01X-1380052Y1147225D02*
X-1379951Y1147168D01*
G01X-1380136Y1147317D02*
X-1380052Y1147225D01*
G01X-1376011Y1147168D02*
X-1375900Y1147149D01*
G01X-1376112Y1147225D02*
X-1376011Y1147168D01*
G01X-1376196Y1147317D02*
X-1376112Y1147225D01*
G01X-1383013Y1159413D02*
X-1383123Y1159432D01*
G01X-1382911Y1159356D02*
X-1383013Y1159413D01*
G01X-1382827Y1159265D02*
X-1382911Y1159356D01*
G01X-1379073Y1159413D02*
X-1379183Y1159432D01*
G01X-1378971Y1159356D02*
X-1379073Y1159413D01*
G01X-1378887Y1159265D02*
X-1378971Y1159356D01*
G01X-1375133Y1159413D02*
X-1375243Y1159432D01*
G01X-1375031Y1159356D02*
X-1375133Y1159413D01*
G01X-1374947Y1159265D02*
X-1375031Y1159356D01*
G01X-1393460Y1147699D02*
X-1393454D01*
G01X-1393464Y1147700D02*
X-1393460Y1147699D01*
G01X-1393465Y1147701D02*
X-1393464Y1147700D01*
G01X-1389520Y1147699D02*
X-1389514D01*
G01X-1389524Y1147700D02*
X-1389520Y1147699D01*
G01X-1389525Y1147701D02*
X-1389524Y1147700D01*
G01X-1385580Y1147699D02*
X-1385574D01*
G01X-1385584Y1147700D02*
X-1385580Y1147699D01*
G01X-1385585Y1147701D02*
X-1385584Y1147700D01*
G01X-1393144Y1158882D02*
X-1393150D01*
G01X-1393140Y1158881D02*
X-1393144Y1158882D01*
G01X-1393139Y1158880D02*
X-1393140Y1158881D01*
G01X-1381640Y1147699D02*
X-1381634D01*
G01X-1381644Y1147700D02*
X-1381640Y1147699D01*
G01X-1381645Y1147701D02*
X-1381644Y1147700D01*
G01X-1389204Y1158882D02*
X-1389210D01*
G01X-1389200Y1158881D02*
X-1389204Y1158882D01*
G01X-1389199Y1158880D02*
X-1389200Y1158881D01*
G01X-1377700Y1147699D02*
X-1377694D01*
G01X-1377704Y1147700D02*
X-1377700Y1147699D01*
G01X-1377705Y1147701D02*
X-1377704Y1147700D01*
G01X-1385264Y1158882D02*
X-1385270D01*
G01X-1385260Y1158881D02*
X-1385264Y1158882D01*
G01X-1385259Y1158880D02*
X-1385260Y1158881D01*
G01X-1373760Y1147699D02*
X-1373754D01*
G01X-1373764Y1147700D02*
X-1373760Y1147699D01*
G01X-1373765Y1147701D02*
X-1373764Y1147700D01*
G01X-1381324Y1158882D02*
X-1381330D01*
G01X-1381320Y1158881D02*
X-1381324Y1158882D01*
G01X-1381319Y1158880D02*
X-1381320Y1158881D01*
G01X-1377384Y1158882D02*
X-1377390D01*
G01X-1377380Y1158881D02*
X-1377384Y1158882D01*
G01X-1377379Y1158880D02*
X-1377380Y1158881D01*
G01X-1393829Y1148204D02*
X-1393910Y1148226D01*
G01X-1393752Y1148179D02*
X-1393829Y1148204D01*
G01X-1393673Y1148148D02*
X-1393752Y1148179D01*
G01X-1393601Y1148115D02*
X-1393673Y1148148D01*
G01X-1393532Y1148080D02*
X-1393601Y1148115D01*
G01X-1393465Y1148041D02*
X-1393532Y1148080D01*
G01X-1393829Y1151128D02*
X-1393910Y1151156D01*
G01X-1393752Y1151097D02*
X-1393829Y1151128D01*
G01X-1393673Y1151060D02*
X-1393752Y1151097D01*
G01X-1393601Y1151020D02*
X-1393673Y1151060D01*
G01X-1393532Y1150977D02*
X-1393601Y1151020D01*
G01X-1393465Y1150929D02*
X-1393532Y1150977D01*
G01X-1389889Y1151128D02*
X-1389970Y1151156D01*
G01X-1389812Y1151097D02*
X-1389889Y1151128D01*
G01X-1389733Y1151060D02*
X-1389812Y1151097D01*
G01X-1389661Y1151020D02*
X-1389733Y1151060D01*
G01X-1389592Y1150977D02*
X-1389661Y1151020D01*
G01X-1389525Y1150929D02*
X-1389592Y1150977D01*
G01X-1392775Y1155453D02*
X-1392693Y1155426D01*
G01X-1392851Y1155484D02*
X-1392775Y1155453D01*
G01X-1392930Y1155521D02*
X-1392851Y1155484D01*
G01X-1393003Y1155561D02*
X-1392930Y1155521D01*
G01X-1393072Y1155605D02*
X-1393003Y1155561D01*
G01X-1393139Y1155652D02*
X-1393072Y1155605D01*
G01X-1385949Y1151128D02*
X-1386030Y1151156D01*
G01X-1385872Y1151097D02*
X-1385949Y1151128D01*
G01X-1385793Y1151060D02*
X-1385872Y1151097D01*
G01X-1385721Y1151020D02*
X-1385793Y1151060D01*
G01X-1385652Y1150977D02*
X-1385721Y1151020D01*
G01X-1385585Y1150929D02*
X-1385652Y1150977D01*
G01X-1388835Y1155453D02*
X-1388753Y1155426D01*
G01X-1388911Y1155484D02*
X-1388835Y1155453D01*
G01X-1388990Y1155521D02*
X-1388911Y1155484D01*
G01X-1389063Y1155561D02*
X-1388990Y1155521D01*
G01X-1389132Y1155605D02*
X-1389063Y1155561D01*
G01X-1389199Y1155652D02*
X-1389132Y1155605D01*
G01X-1382009Y1151128D02*
X-1382090Y1151156D01*
G01X-1381932Y1151097D02*
X-1382009Y1151128D01*
G01X-1381853Y1151060D02*
X-1381932Y1151097D01*
G01X-1381781Y1151020D02*
X-1381853Y1151060D01*
G01X-1381712Y1150977D02*
X-1381781Y1151020D01*
G01X-1381645Y1150929D02*
X-1381712Y1150977D01*
G01X-1384895Y1155453D02*
X-1384813Y1155426D01*
G01X-1384971Y1155484D02*
X-1384895Y1155453D01*
G01X-1385050Y1155521D02*
X-1384971Y1155484D01*
G01X-1385123Y1155561D02*
X-1385050Y1155521D01*
G01X-1385192Y1155605D02*
X-1385123Y1155561D01*
G01X-1385259Y1155652D02*
X-1385192Y1155605D01*
G01X-1378069Y1151128D02*
X-1378150Y1151156D01*
G01X-1377992Y1151097D02*
X-1378069Y1151128D01*
G01X-1377913Y1151060D02*
X-1377992Y1151097D01*
G01X-1377841Y1151020D02*
X-1377913Y1151060D01*
G01X-1377772Y1150977D02*
X-1377841Y1151020D01*
G01X-1377705Y1150929D02*
X-1377772Y1150977D01*
G01X-1380955Y1155453D02*
X-1380873Y1155426D01*
G01X-1381031Y1155484D02*
X-1380955Y1155453D01*
G01X-1381110Y1155521D02*
X-1381031Y1155484D01*
G01X-1381183Y1155561D02*
X-1381110Y1155521D01*
G01X-1381252Y1155605D02*
X-1381183Y1155561D01*
G01X-1381319Y1155652D02*
X-1381252Y1155605D01*
G01X-1374129Y1151128D02*
X-1374210Y1151156D01*
G01X-1374052Y1151097D02*
X-1374129Y1151128D01*
G01X-1373973Y1151060D02*
X-1374052Y1151097D01*
G01X-1373901Y1151020D02*
X-1373973Y1151060D01*
G01X-1373832Y1150977D02*
X-1373901Y1151020D01*
G01X-1373765Y1150929D02*
X-1373832Y1150977D01*
G01X-1377015Y1155453D02*
X-1376933Y1155426D01*
G01X-1377091Y1155484D02*
X-1377015Y1155453D01*
G01X-1377170Y1155521D02*
X-1377091Y1155484D01*
G01X-1377243Y1155561D02*
X-1377170Y1155521D01*
G01X-1377312Y1155605D02*
X-1377243Y1155561D01*
G01X-1377379Y1155652D02*
X-1377312Y1155605D01*
G01X-1402344Y1147301D02*
X-1402198Y1147291D01*
G01X-1402473Y1147311D02*
X-1402344Y1147301D01*
G01X-1402575Y1147322D02*
X-1402473Y1147311D01*
G01X-1402640Y1147332D02*
X-1402575Y1147322D01*
G01X-1402662Y1147342D02*
X-1402640Y1147332D01*
G01X-1389889Y1148204D02*
X-1389970Y1148226D01*
G01X-1389812Y1148179D02*
X-1389889Y1148204D01*
G01X-1389733Y1148148D02*
X-1389812Y1148179D01*
G01X-1389661Y1148115D02*
X-1389733Y1148148D01*
G01X-1389592Y1148080D02*
X-1389661Y1148115D01*
G01X-1389525Y1148041D02*
X-1389592Y1148080D01*
G01X-1385949Y1148204D02*
X-1386030Y1148226D01*
G01X-1385872Y1148179D02*
X-1385949Y1148204D01*
G01X-1385793Y1148148D02*
X-1385872Y1148179D01*
G01X-1385721Y1148115D02*
X-1385793Y1148148D01*
G01X-1385652Y1148080D02*
X-1385721Y1148115D01*
G01X-1385585Y1148041D02*
X-1385652Y1148080D01*
G01X-1382009Y1148204D02*
X-1382090Y1148226D01*
G01X-1381932Y1148179D02*
X-1382009Y1148204D01*
G01X-1381853Y1148148D02*
X-1381932Y1148179D01*
G01X-1381781Y1148115D02*
X-1381853Y1148148D01*
G01X-1381712Y1148080D02*
X-1381781Y1148115D01*
G01X-1381645Y1148041D02*
X-1381712Y1148080D01*
G01X-1378069Y1148204D02*
X-1378150Y1148226D01*
G01X-1377992Y1148179D02*
X-1378069Y1148204D01*
G01X-1377913Y1148148D02*
X-1377992Y1148179D01*
G01X-1377841Y1148115D02*
X-1377913Y1148148D01*
G01X-1377772Y1148080D02*
X-1377841Y1148115D01*
G01X-1377705Y1148041D02*
X-1377772Y1148080D01*
G01X-1392775Y1158377D02*
X-1392693Y1158355D01*
G01X-1392851Y1158403D02*
X-1392775Y1158377D01*
G01X-1392930Y1158433D02*
X-1392851Y1158403D01*
G01X-1393003Y1158466D02*
X-1392930Y1158433D01*
G01X-1393072Y1158502D02*
X-1393003Y1158466D01*
G01X-1393139Y1158541D02*
X-1393072Y1158502D01*
G01X-1374129Y1148204D02*
X-1374210Y1148226D01*
G01X-1374052Y1148179D02*
X-1374129Y1148204D01*
G01X-1373973Y1148148D02*
X-1374052Y1148179D01*
G01X-1373901Y1148115D02*
X-1373973Y1148148D01*
G01X-1373832Y1148080D02*
X-1373901Y1148115D01*
G01X-1373765Y1148041D02*
X-1373832Y1148080D01*
G01X-1388835Y1158377D02*
X-1388753Y1158355D01*
G01X-1388911Y1158403D02*
X-1388835Y1158377D01*
G01X-1388990Y1158433D02*
X-1388911Y1158403D01*
G01X-1389063Y1158466D02*
X-1388990Y1158433D01*
G01X-1389132Y1158502D02*
X-1389063Y1158466D01*
G01X-1389199Y1158541D02*
X-1389132Y1158502D01*
G01X-1384895Y1158377D02*
X-1384813Y1158355D01*
G01X-1384971Y1158403D02*
X-1384895Y1158377D01*
G01X-1385050Y1158433D02*
X-1384971Y1158403D01*
G01X-1385123Y1158466D02*
X-1385050Y1158433D01*
G01X-1385192Y1158502D02*
X-1385123Y1158466D01*
G01X-1385259Y1158541D02*
X-1385192Y1158502D01*
G01X-1380955Y1158377D02*
X-1380873Y1158355D01*
G01X-1381031Y1158403D02*
X-1380955Y1158377D01*
G01X-1381110Y1158433D02*
X-1381031Y1158403D01*
G01X-1381183Y1158466D02*
X-1381110Y1158433D01*
G01X-1381252Y1158502D02*
X-1381183Y1158466D01*
G01X-1381319Y1158541D02*
X-1381252Y1158502D01*
G01X-1377015Y1158377D02*
X-1376933Y1158355D01*
G01X-1377091Y1158403D02*
X-1377015Y1158377D01*
G01X-1377170Y1158433D02*
X-1377091Y1158403D01*
G01X-1377243Y1158466D02*
X-1377170Y1158433D01*
G01X-1377312Y1158502D02*
X-1377243Y1158466D01*
G01X-1377379Y1158541D02*
X-1377312Y1158502D01*
G01X-1393534Y1150527D02*
X-1393465Y1150478D01*
G01X-1393604Y1150571D02*
X-1393534Y1150527D01*
G01X-1393681Y1150613D02*
X-1393604Y1150571D01*
G01X-1393755Y1150648D02*
X-1393681Y1150613D01*
G01X-1393832Y1150678D02*
X-1393755Y1150648D01*
G01X-1393910Y1150705D02*
X-1393832Y1150678D01*
G01X-1389594Y1150527D02*
X-1389525Y1150478D01*
G01X-1389664Y1150571D02*
X-1389594Y1150527D01*
G01X-1389741Y1150613D02*
X-1389664Y1150571D01*
G01X-1389815Y1150648D02*
X-1389741Y1150613D01*
G01X-1389892Y1150678D02*
X-1389815Y1150648D01*
G01X-1389970Y1150705D02*
X-1389892Y1150678D01*
G01X-1385654Y1150527D02*
X-1385585Y1150478D01*
G01X-1385724Y1150571D02*
X-1385654Y1150527D01*
G01X-1385801Y1150613D02*
X-1385724Y1150571D01*
G01X-1385875Y1150648D02*
X-1385801Y1150613D01*
G01X-1385952Y1150678D02*
X-1385875Y1150648D01*
G01X-1386030Y1150705D02*
X-1385952Y1150678D01*
G01X-1381714Y1150527D02*
X-1381645Y1150478D01*
G01X-1381784Y1150571D02*
X-1381714Y1150527D01*
G01X-1381861Y1150613D02*
X-1381784Y1150571D01*
G01X-1381935Y1150648D02*
X-1381861Y1150613D01*
G01X-1382012Y1150678D02*
X-1381935Y1150648D01*
G01X-1382090Y1150705D02*
X-1382012Y1150678D01*
G01X-1392981Y1147712D02*
X-1393004Y1147729D01*
G01X-1392961Y1147702D02*
X-1392981Y1147712D01*
G01X-1392943Y1147699D02*
X-1392961Y1147702D01*
G01X-1389041Y1147712D02*
X-1389064Y1147729D01*
G01X-1389021Y1147702D02*
X-1389041Y1147712D01*
G01X-1389003Y1147699D02*
X-1389021Y1147702D01*
G01X-1385101Y1147712D02*
X-1385124Y1147729D01*
G01X-1385081Y1147702D02*
X-1385101Y1147712D01*
G01X-1385063Y1147699D02*
X-1385081Y1147702D01*
G01X-1381161Y1147712D02*
X-1381184Y1147729D01*
G01X-1381141Y1147702D02*
X-1381161Y1147712D01*
G01X-1381123Y1147699D02*
X-1381141Y1147702D01*
G01X-1377221Y1147712D02*
X-1377244Y1147729D01*
G01X-1377201Y1147702D02*
X-1377221Y1147712D01*
G01X-1377183Y1147699D02*
X-1377201Y1147702D01*
G01X-1402730Y1147308D02*
X-1402239Y1147291D01*
G01X-1402931Y1147316D02*
X-1402730Y1147308D01*
G01X-1403084Y1147325D02*
X-1402931Y1147316D01*
G01X-1403179Y1147334D02*
X-1403084Y1147325D01*
G01X-1403212Y1147342D02*
X-1403179Y1147334D01*
G01X-1393534Y1150836D02*
X-1393465Y1150795D01*
G01X-1393604Y1150871D02*
X-1393534Y1150836D01*
G01X-1393681Y1150905D02*
X-1393604Y1150871D01*
G01X-1393755Y1150934D02*
X-1393681Y1150905D01*
G01X-1393832Y1150959D02*
X-1393755Y1150934D01*
G01X-1393910Y1150981D02*
X-1393832Y1150959D01*
G01X-1389594Y1150836D02*
X-1389525Y1150795D01*
G01X-1389664Y1150871D02*
X-1389594Y1150836D01*
G01X-1389741Y1150905D02*
X-1389664Y1150871D01*
G01X-1389815Y1150934D02*
X-1389741Y1150905D01*
G01X-1389892Y1150959D02*
X-1389815Y1150934D01*
G01X-1389970Y1150981D02*
X-1389892Y1150959D01*
G01X-1385654Y1150836D02*
X-1385585Y1150795D01*
G01X-1385724Y1150871D02*
X-1385654Y1150836D01*
G01X-1385801Y1150905D02*
X-1385724Y1150871D01*
G01X-1385875Y1150934D02*
X-1385801Y1150905D01*
G01X-1385952Y1150959D02*
X-1385875Y1150934D01*
G01X-1386030Y1150981D02*
X-1385952Y1150959D01*
G01X-1381714Y1150836D02*
X-1381645Y1150795D01*
G01X-1381784Y1150871D02*
X-1381714Y1150836D01*
G01X-1381861Y1150905D02*
X-1381784Y1150871D01*
G01X-1381935Y1150934D02*
X-1381861Y1150905D01*
G01X-1382012Y1150959D02*
X-1381935Y1150934D01*
G01X-1382090Y1150981D02*
X-1382012Y1150959D01*
G01X-1377774Y1150836D02*
X-1377705Y1150795D01*
G01X-1377844Y1150871D02*
X-1377774Y1150836D01*
G01X-1377921Y1150905D02*
X-1377844Y1150871D01*
G01X-1377995Y1150934D02*
X-1377921Y1150905D01*
G01X-1378072Y1150959D02*
X-1377995Y1150934D01*
G01X-1378150Y1150981D02*
X-1378072Y1150959D01*
G01X-1393069Y1155746D02*
X-1393139Y1155786D01*
G01X-1393000Y1155710D02*
X-1393069Y1155746D01*
G01X-1392923Y1155676D02*
X-1393000Y1155710D01*
G01X-1392848Y1155647D02*
X-1392923Y1155676D01*
G01X-1392772Y1155622D02*
X-1392848Y1155647D01*
G01X-1392693Y1155601D02*
X-1392772Y1155622D01*
G01X-1373834Y1150836D02*
X-1373765Y1150795D01*
G01X-1373904Y1150871D02*
X-1373834Y1150836D01*
G01X-1373981Y1150905D02*
X-1373904Y1150871D01*
G01X-1374055Y1150934D02*
X-1373981Y1150905D01*
G01X-1374132Y1150959D02*
X-1374055Y1150934D01*
G01X-1374210Y1150981D02*
X-1374132Y1150959D01*
G01X-1389129Y1155746D02*
X-1389199Y1155786D01*
G01X-1389060Y1155710D02*
X-1389129Y1155746D01*
G01X-1388983Y1155676D02*
X-1389060Y1155710D01*
G01X-1388908Y1155647D02*
X-1388983Y1155676D01*
G01X-1388832Y1155622D02*
X-1388908Y1155647D01*
G01X-1388753Y1155601D02*
X-1388832Y1155622D01*
G01X-1385189Y1155746D02*
X-1385259Y1155786D01*
G01X-1385120Y1155710D02*
X-1385189Y1155746D01*
G01X-1385043Y1155676D02*
X-1385120Y1155710D01*
G01X-1384968Y1155647D02*
X-1385043Y1155676D01*
G01X-1384892Y1155622D02*
X-1384968Y1155647D01*
G01X-1384813Y1155601D02*
X-1384892Y1155622D01*
G01X-1381249Y1155746D02*
X-1381319Y1155786D01*
G01X-1381180Y1155710D02*
X-1381249Y1155746D01*
G01X-1381103Y1155676D02*
X-1381180Y1155710D01*
G01X-1381028Y1155647D02*
X-1381103Y1155676D01*
G01X-1380952Y1155622D02*
X-1381028Y1155647D01*
G01X-1380873Y1155601D02*
X-1380952Y1155622D01*
G01X-1377309Y1155746D02*
X-1377379Y1155786D01*
G01X-1377240Y1155710D02*
X-1377309Y1155746D01*
G01X-1377163Y1155676D02*
X-1377240Y1155710D01*
G01X-1377088Y1155647D02*
X-1377163Y1155676D01*
G01X-1377012Y1155622D02*
X-1377088Y1155647D01*
G01X-1376933Y1155601D02*
X-1377012Y1155622D01*
G01X-1377774Y1150527D02*
X-1377705Y1150478D01*
G01X-1377844Y1150571D02*
X-1377774Y1150527D01*
G01X-1377921Y1150613D02*
X-1377844Y1150571D01*
G01X-1377995Y1150648D02*
X-1377921Y1150613D01*
G01X-1378072Y1150678D02*
X-1377995Y1150648D01*
G01X-1378150Y1150705D02*
X-1378072Y1150678D01*
G01X-1393069Y1156054D02*
X-1393139Y1156103D01*
G01X-1393000Y1156010D02*
X-1393069Y1156054D01*
G01X-1392923Y1155969D02*
X-1393000Y1156010D01*
G01X-1392848Y1155934D02*
X-1392923Y1155969D01*
G01X-1392772Y1155903D02*
X-1392848Y1155934D01*
G01X-1392693Y1155877D02*
X-1392772Y1155903D01*
G01X-1373834Y1150527D02*
X-1373765Y1150478D01*
G01X-1373904Y1150571D02*
X-1373834Y1150527D01*
G01X-1373981Y1150613D02*
X-1373904Y1150571D01*
G01X-1374055Y1150648D02*
X-1373981Y1150613D01*
G01X-1374132Y1150678D02*
X-1374055Y1150648D01*
G01X-1374210Y1150705D02*
X-1374132Y1150678D01*
G01X-1389129Y1156054D02*
X-1389199Y1156103D01*
G01X-1389060Y1156010D02*
X-1389129Y1156054D01*
G01X-1388983Y1155969D02*
X-1389060Y1156010D01*
G01X-1388908Y1155934D02*
X-1388983Y1155969D01*
G01X-1388832Y1155903D02*
X-1388908Y1155934D01*
G01X-1388753Y1155877D02*
X-1388832Y1155903D01*
G01X-1385189Y1156054D02*
X-1385259Y1156103D01*
G01X-1385120Y1156010D02*
X-1385189Y1156054D01*
G01X-1385043Y1155969D02*
X-1385120Y1156010D01*
G01X-1384968Y1155934D02*
X-1385043Y1155969D01*
G01X-1384892Y1155903D02*
X-1384968Y1155934D01*
G01X-1384813Y1155877D02*
X-1384892Y1155903D01*
G01X-1381249Y1156054D02*
X-1381319Y1156103D01*
G01X-1381180Y1156010D02*
X-1381249Y1156054D01*
G01X-1381103Y1155969D02*
X-1381180Y1156010D01*
G01X-1381028Y1155934D02*
X-1381103Y1155969D01*
G01X-1380952Y1155903D02*
X-1381028Y1155934D01*
G01X-1380873Y1155877D02*
X-1380952Y1155903D01*
G01X-1377309Y1156054D02*
X-1377379Y1156103D01*
G01X-1377240Y1156010D02*
X-1377309Y1156054D01*
G01X-1377163Y1155969D02*
X-1377240Y1156010D01*
G01X-1377088Y1155934D02*
X-1377163Y1155969D01*
G01X-1377012Y1155903D02*
X-1377088Y1155934D01*
G01X-1376933Y1155877D02*
X-1377012Y1155903D01*
G01X-1395139Y1147712D02*
X-1395165Y1147729D01*
G01X-1395110Y1147702D02*
X-1395139Y1147712D01*
G01X-1395079Y1147699D02*
X-1395110Y1147702D01*
G01X-1391199Y1147712D02*
X-1391225Y1147729D01*
G01X-1391170Y1147702D02*
X-1391199Y1147712D01*
G01X-1391139Y1147699D02*
X-1391170Y1147702D01*
G01X-1387259Y1147712D02*
X-1387285Y1147729D01*
G01X-1387230Y1147702D02*
X-1387259Y1147712D01*
G01X-1387199Y1147699D02*
X-1387230Y1147702D01*
G01X-1383319Y1147712D02*
X-1383345Y1147729D01*
G01X-1383290Y1147702D02*
X-1383319Y1147712D01*
G01X-1383259Y1147699D02*
X-1383290Y1147702D01*
G01X-1379379Y1147712D02*
X-1379405Y1147729D01*
G01X-1379350Y1147702D02*
X-1379379Y1147712D01*
G01X-1379319Y1147699D02*
X-1379350Y1147702D01*
G01X-1375439Y1147712D02*
X-1375465Y1147729D01*
G01X-1375410Y1147702D02*
X-1375439Y1147712D01*
G01X-1375379Y1147699D02*
X-1375410Y1147702D01*
G01X-1391465Y1158869D02*
X-1391439Y1158853D01*
G01X-1391494Y1158879D02*
X-1391465Y1158869D01*
G01X-1391525Y1158882D02*
X-1391494Y1158879D01*
G01X-1387525Y1158869D02*
X-1387499Y1158853D01*
G01X-1387554Y1158879D02*
X-1387525Y1158869D01*
G01X-1387585Y1158882D02*
X-1387554Y1158879D01*
G01X-1383585Y1158869D02*
X-1383559Y1158853D01*
G01X-1383614Y1158879D02*
X-1383585Y1158869D01*
G01X-1383645Y1158882D02*
X-1383614Y1158879D01*
G01X-1379645Y1158869D02*
X-1379619Y1158853D01*
G01X-1379674Y1158879D02*
X-1379645Y1158869D01*
G01X-1379705Y1158882D02*
X-1379674Y1158879D01*
G01X-1375705Y1158869D02*
X-1375679Y1158853D01*
G01X-1375734Y1158879D02*
X-1375705Y1158869D01*
G01X-1375765Y1158882D02*
X-1375734Y1158879D01*
G01X-1395389Y1147225D02*
X-1395522Y1147317D01*
G01X-1395238Y1147168D02*
X-1395389Y1147225D01*
G01X-1395079Y1147149D02*
X-1395238Y1147168D01*
G01X-1391449Y1147225D02*
X-1391582Y1147317D01*
G01X-1391298Y1147168D02*
X-1391449Y1147225D01*
G01X-1391139Y1147149D02*
X-1391298Y1147168D01*
G01X-1387509Y1147225D02*
X-1387642Y1147317D01*
G01X-1387358Y1147168D02*
X-1387509Y1147225D01*
G01X-1387199Y1147149D02*
X-1387358Y1147168D01*
G01X-1383569Y1147225D02*
X-1383702Y1147317D01*
G01X-1383418Y1147168D02*
X-1383569Y1147225D01*
G01X-1383259Y1147149D02*
X-1383418Y1147168D01*
G01X-1379629Y1147225D02*
X-1379762Y1147317D01*
G01X-1379478Y1147168D02*
X-1379629Y1147225D01*
G01X-1379319Y1147149D02*
X-1379478Y1147168D01*
G01X-1375689Y1147225D02*
X-1375822Y1147317D01*
G01X-1375538Y1147168D02*
X-1375689Y1147225D01*
G01X-1375379Y1147149D02*
X-1375538Y1147168D01*
G01X-1391215Y1159356D02*
X-1391082Y1159265D01*
G01X-1391365Y1159413D02*
X-1391215Y1159356D01*
G01X-1391525Y1159432D02*
X-1391365Y1159413D01*
G01X-1387275Y1159356D02*
X-1387142Y1159265D01*
G01X-1387425Y1159413D02*
X-1387275Y1159356D01*
G01X-1387585Y1159432D02*
X-1387425Y1159413D01*
G01X-1383335Y1159356D02*
X-1383202Y1159265D01*
G01X-1383485Y1159413D02*
X-1383335Y1159356D01*
G01X-1383645Y1159432D02*
X-1383485Y1159413D01*
G01X-1379395Y1159356D02*
X-1379262Y1159265D01*
G01X-1379545Y1159413D02*
X-1379395Y1159356D01*
G01X-1379705Y1159432D02*
X-1379545Y1159413D01*
G01X-1375455Y1159356D02*
X-1375322Y1159265D01*
G01X-1375605Y1159413D02*
X-1375455Y1159356D01*
G01X-1375765Y1159432D02*
X-1375605Y1159413D01*
G01X-1373281Y1147712D02*
X-1373304Y1147729D01*
G01X-1373261Y1147702D02*
X-1373281Y1147712D01*
G01X-1373243Y1147699D02*
X-1373261Y1147702D01*
G01X-1393623Y1158869D02*
X-1393600Y1158853D01*
G01X-1393642Y1158879D02*
X-1393623Y1158869D01*
G01X-1393660Y1158882D02*
X-1393642Y1158879D01*
G01X-1389683Y1158869D02*
X-1389660Y1158853D01*
G01X-1389702Y1158879D02*
X-1389683Y1158869D01*
G01X-1389720Y1158882D02*
X-1389702Y1158879D01*
G01X-1385743Y1158869D02*
X-1385720Y1158853D01*
G01X-1385762Y1158879D02*
X-1385743Y1158869D01*
G01X-1385780Y1158882D02*
X-1385762Y1158879D01*
G01X-1381803Y1158869D02*
X-1381780Y1158853D01*
G01X-1381822Y1158879D02*
X-1381803Y1158869D01*
G01X-1381840Y1158882D02*
X-1381822Y1158879D01*
G01X-1377863Y1158869D02*
X-1377840Y1158853D01*
G01X-1377882Y1158879D02*
X-1377863Y1158869D01*
G01X-1377900Y1158882D02*
X-1377882Y1158879D01*
G01X-1402640Y1159250D02*
X-1402662Y1159239D01*
G01X-1402575Y1159260D02*
X-1402640Y1159250D01*
G01X-1402473Y1159270D02*
X-1402575Y1159260D01*
G01X-1402344Y1159280D02*
X-1402473Y1159270D01*
G01X-1402198Y1159291D02*
X-1402344Y1159280D01*
G01X-1375380Y1147700D02*
X-1375379Y1147701D01*
G01X-1375384Y1147699D02*
X-1375380Y1147700D01*
G01X-1375390Y1147699D02*
X-1375384D01*
G01X-1379320Y1147700D02*
X-1379319Y1147701D01*
G01X-1379324Y1147699D02*
X-1379320Y1147700D01*
G01X-1379330Y1147699D02*
X-1379324D01*
G01X-1383260Y1147700D02*
X-1383259Y1147701D01*
G01X-1383264Y1147699D02*
X-1383260Y1147700D01*
G01X-1383270Y1147699D02*
X-1383264D01*
G01X-1387200Y1147700D02*
X-1387199Y1147701D01*
G01X-1387204Y1147699D02*
X-1387200Y1147700D01*
G01X-1387210Y1147699D02*
X-1387204D01*
G01X-1391140Y1147700D02*
X-1391139Y1147701D01*
G01X-1391144Y1147699D02*
X-1391140Y1147700D01*
G01X-1391150Y1147699D02*
X-1391144D01*
G01X-1395080Y1147700D02*
X-1395079Y1147701D01*
G01X-1395084Y1147699D02*
X-1395080Y1147700D01*
G01X-1395090Y1147699D02*
X-1395084D01*
G01X-1375764Y1158881D02*
X-1375765Y1158880D01*
G01X-1375760Y1158882D02*
X-1375764Y1158881D01*
G01X-1375754Y1158882D02*
X-1375760D01*
G01X-1379704Y1158881D02*
X-1379705Y1158880D01*
G01X-1379700Y1158882D02*
X-1379704Y1158881D01*
G01X-1379694Y1158882D02*
X-1379700D01*
G01X-1383644Y1158881D02*
X-1383645Y1158880D01*
G01X-1383640Y1158882D02*
X-1383644Y1158881D01*
G01X-1383634Y1158882D02*
X-1383640D01*
G01X-1387584Y1158881D02*
X-1387585Y1158880D01*
G01X-1387580Y1158882D02*
X-1387584Y1158881D01*
G01X-1387574Y1158882D02*
X-1387580D01*
G01X-1391524Y1158881D02*
X-1391525Y1158880D01*
G01X-1391520Y1158882D02*
X-1391524Y1158881D01*
G01X-1391514Y1158882D02*
X-1391520D01*
G01X-1403179Y1159248D02*
X-1403212Y1159239D01*
G01X-1403084Y1159256D02*
X-1403179Y1159248D01*
G01X-1402931Y1159265D02*
X-1403084Y1159256D01*
G01X-1402731Y1159274D02*
X-1402931Y1159265D01*
G01X-1375379Y1147151D02*
Y1147153D01*
G01X-1375380Y1147150D02*
X-1375379Y1147151D01*
G01X-1375382Y1147150D02*
X-1375380D01*
G01X-1375384Y1147149D02*
X-1375382Y1147150D01*
G01X-1375387Y1147149D02*
X-1375384D01*
G01X-1375390D02*
X-1375387D01*
G01X-1379319Y1147151D02*
Y1147153D01*
G01X-1379320Y1147150D02*
X-1379319Y1147151D01*
G01X-1379322Y1147150D02*
X-1379320D01*
G01X-1379324Y1147149D02*
X-1379322Y1147150D01*
G01X-1379327Y1147149D02*
X-1379324D01*
G01X-1379330D02*
X-1379327D01*
G01X-1383259Y1147151D02*
Y1147153D01*
G01X-1383260Y1147150D02*
X-1383259Y1147151D01*
G01X-1383262Y1147150D02*
X-1383260D01*
G01X-1383264Y1147149D02*
X-1383262Y1147150D01*
G01X-1383267Y1147149D02*
X-1383264D01*
G01X-1383270D02*
X-1383267D01*
G01X-1387199Y1147151D02*
Y1147153D01*
G01X-1387200Y1147150D02*
X-1387199Y1147151D01*
G01X-1387202Y1147150D02*
X-1387200D01*
G01X-1387204Y1147149D02*
X-1387202Y1147150D01*
G01X-1387207Y1147149D02*
X-1387204D01*
G01X-1387210D02*
X-1387207D01*
G01X-1391139Y1147151D02*
Y1147153D01*
G01X-1391140Y1147150D02*
X-1391139Y1147151D01*
G01X-1391142Y1147150D02*
X-1391140D01*
G01X-1391144Y1147149D02*
X-1391142Y1147150D01*
G01X-1391147Y1147149D02*
X-1391144D01*
G01X-1391150D02*
X-1391147D01*
G01X-1395079Y1147151D02*
Y1147153D01*
G01X-1395080Y1147150D02*
X-1395079Y1147151D01*
G01X-1395082Y1147150D02*
X-1395080D01*
G01X-1395084Y1147149D02*
X-1395082Y1147150D01*
G01X-1395087Y1147149D02*
X-1395084D01*
G01X-1395090D02*
X-1395087D01*
G01X-1375764Y1159430D02*
X-1375765Y1159429D01*
G01X-1375763Y1159431D02*
X-1375764Y1159430D01*
G01X-1375762Y1159432D02*
X-1375763Y1159431D01*
G01X-1375760Y1159432D02*
X-1375762D01*
G01X-1375757D02*
X-1375760D01*
G01X-1375754D02*
X-1375757D01*
G01X-1379704Y1159430D02*
X-1379705Y1159429D01*
G01X-1379703Y1159431D02*
X-1379704Y1159430D01*
G01X-1379702Y1159432D02*
X-1379703Y1159431D01*
G01X-1379700Y1159432D02*
X-1379702D01*
G01X-1379697D02*
X-1379700D01*
G01X-1379694D02*
X-1379697D01*
G01X-1383644Y1159430D02*
X-1383645Y1159429D01*
G01X-1383643Y1159431D02*
X-1383644Y1159430D01*
G01X-1383642Y1159432D02*
X-1383643Y1159431D01*
G01X-1383640Y1159432D02*
X-1383642D01*
G01X-1383637D02*
X-1383640D01*
G01X-1383634D02*
X-1383637D01*
G01X-1387584Y1159430D02*
X-1387585Y1159429D01*
G01X-1387583Y1159431D02*
X-1387584Y1159430D01*
G01X-1387582Y1159432D02*
X-1387583Y1159431D01*
G01X-1387580Y1159432D02*
X-1387582D01*
G01X-1387577D02*
X-1387580D01*
G01X-1387574D02*
X-1387577D01*
G01X-1391524Y1159430D02*
X-1391525Y1159429D01*
G01X-1391523Y1159431D02*
X-1391524Y1159430D01*
G01X-1391522Y1159432D02*
X-1391523Y1159431D01*
G01X-1391520Y1159432D02*
X-1391522D01*
G01X-1391517D02*
X-1391520D01*
G01X-1391514D02*
X-1391517D01*
G01X-1402175Y1147288D02*
X-1402162Y1147286D01*
G01X-1402188Y1147289D02*
X-1402175Y1147288D01*
G01X-1402202Y1147290D02*
X-1402188Y1147289D01*
G01X-1402214Y1147290D02*
X-1402202D01*
G01X-1402226Y1147291D02*
X-1402214Y1147290D01*
G01X-1402239Y1147291D02*
X-1402226D01*
G01X-1402168Y1147288D02*
X-1402162Y1147286D01*
G01X-1402174Y1147289D02*
X-1402168Y1147288D01*
G01X-1402181Y1147290D02*
X-1402174Y1147289D01*
G01X-1402186Y1147290D02*
X-1402181D01*
G01X-1402192Y1147291D02*
X-1402186Y1147290D01*
G01X-1402198Y1147291D02*
X-1402192D01*
G01X-1375307Y1148074D02*
X-1375379Y1148032D01*
G01X-1375234Y1148113D02*
X-1375307Y1148074D01*
G01X-1375158Y1148147D02*
X-1375234Y1148113D01*
G01X-1375079Y1148178D02*
X-1375158Y1148147D01*
G01X-1374997Y1148205D02*
X-1375079Y1148178D01*
G01X-1374919Y1148226D02*
X-1374997Y1148205D01*
G01X-1379247Y1148074D02*
X-1379319Y1148032D01*
G01X-1379174Y1148113D02*
X-1379247Y1148074D01*
G01X-1379098Y1148147D02*
X-1379174Y1148113D01*
G01X-1379019Y1148178D02*
X-1379098Y1148147D01*
G01X-1378937Y1148205D02*
X-1379019Y1148178D01*
G01X-1378859Y1148226D02*
X-1378937Y1148205D01*
G01X-1383187Y1148074D02*
X-1383259Y1148032D01*
G01X-1383114Y1148113D02*
X-1383187Y1148074D01*
G01X-1383038Y1148147D02*
X-1383114Y1148113D01*
G01X-1382959Y1148178D02*
X-1383038Y1148147D01*
G01X-1382877Y1148205D02*
X-1382959Y1148178D01*
G01X-1382799Y1148226D02*
X-1382877Y1148205D01*
G01X-1387127Y1148074D02*
X-1387199Y1148032D01*
G01X-1387054Y1148113D02*
X-1387127Y1148074D01*
G01X-1386978Y1148147D02*
X-1387054Y1148113D01*
G01X-1386899Y1148178D02*
X-1386978Y1148147D01*
G01X-1386817Y1148205D02*
X-1386899Y1148178D01*
G01X-1386739Y1148226D02*
X-1386817Y1148205D01*
G01X-1391067Y1148074D02*
X-1391139Y1148032D01*
G01X-1390994Y1148113D02*
X-1391067Y1148074D01*
G01X-1390918Y1148147D02*
X-1390994Y1148113D01*
G01X-1390839Y1148178D02*
X-1390918Y1148147D01*
G01X-1390757Y1148205D02*
X-1390839Y1148178D01*
G01X-1390679Y1148226D02*
X-1390757Y1148205D01*
G01X-1395007Y1148074D02*
X-1395079Y1148032D01*
G01X-1394934Y1148113D02*
X-1395007Y1148074D01*
G01X-1394858Y1148147D02*
X-1394934Y1148113D01*
G01X-1394779Y1148178D02*
X-1394858Y1148147D01*
G01X-1394697Y1148205D02*
X-1394779Y1148178D01*
G01X-1394619Y1148226D02*
X-1394697Y1148205D01*
G01X-1375836Y1158507D02*
X-1375765Y1158550D01*
G01X-1375910Y1158469D02*
X-1375836Y1158507D01*
G01X-1375986Y1158434D02*
X-1375910Y1158469D01*
G01X-1376065Y1158403D02*
X-1375986Y1158434D01*
G01X-1376146Y1158377D02*
X-1376065Y1158403D01*
G01X-1376225Y1158355D02*
X-1376146Y1158377D01*
G01X-1379776Y1158507D02*
X-1379705Y1158550D01*
G01X-1379850Y1158469D02*
X-1379776Y1158507D01*
G01X-1379926Y1158434D02*
X-1379850Y1158469D01*
G01X-1380005Y1158403D02*
X-1379926Y1158434D01*
G01X-1380086Y1158377D02*
X-1380005Y1158403D01*
G01X-1380165Y1158355D02*
X-1380086Y1158377D01*
G01X-1383716Y1158507D02*
X-1383645Y1158550D01*
G01X-1383790Y1158469D02*
X-1383716Y1158507D01*
G01X-1383866Y1158434D02*
X-1383790Y1158469D01*
G01X-1383945Y1158403D02*
X-1383866Y1158434D01*
G01X-1384026Y1158377D02*
X-1383945Y1158403D01*
G01X-1384105Y1158355D02*
X-1384026Y1158377D01*
G01X-1387656Y1158507D02*
X-1387585Y1158550D01*
G01X-1387730Y1158469D02*
X-1387656Y1158507D01*
G01X-1387806Y1158434D02*
X-1387730Y1158469D01*
G01X-1387885Y1158403D02*
X-1387806Y1158434D01*
G01X-1387966Y1158377D02*
X-1387885Y1158403D01*
G01X-1388045Y1158355D02*
X-1387966Y1158377D01*
G01X-1391596Y1158507D02*
X-1391525Y1158550D01*
G01X-1391670Y1158469D02*
X-1391596Y1158507D01*
G01X-1391746Y1158434D02*
X-1391670Y1158469D01*
G01X-1391825Y1158403D02*
X-1391746Y1158434D01*
G01X-1391906Y1158377D02*
X-1391825Y1158403D01*
G01X-1391985Y1158355D02*
X-1391906Y1158377D01*
G01X-1402192Y1159291D02*
X-1402198D01*
G01X-1402186D02*
X-1402192D01*
G01X-1402179Y1159292D02*
X-1402186Y1159291D01*
G01X-1402174Y1159293D02*
X-1402179Y1159292D01*
G01X-1402168Y1159294D02*
X-1402174Y1159293D01*
G01X-1402162Y1159295D02*
X-1402168Y1159294D01*
G01X-1373031Y1147225D02*
X-1372947Y1147317D01*
G01X-1373133Y1147168D02*
X-1373031Y1147225D01*
G01X-1373243Y1147149D02*
X-1373133Y1147168D01*
G01X-1376971Y1147225D02*
X-1376887Y1147317D01*
G01X-1377073Y1147168D02*
X-1376971Y1147225D01*
G01X-1377183Y1147149D02*
X-1377073Y1147168D01*
G01X-1380911Y1147225D02*
X-1380827Y1147317D01*
G01X-1381013Y1147168D02*
X-1380911Y1147225D01*
G01X-1381123Y1147149D02*
X-1381013Y1147168D01*
G01X-1378112Y1159356D02*
X-1378196Y1159265D01*
G01X-1378011Y1159413D02*
X-1378112Y1159356D01*
G01X-1377900Y1159432D02*
X-1378011Y1159413D01*
G01X-1382052Y1159356D02*
X-1382136Y1159265D01*
G01X-1381951Y1159413D02*
X-1382052Y1159356D01*
G01X-1381840Y1159432D02*
X-1381951Y1159413D01*
G01X-1402225Y1159291D02*
X-1402239D01*
G01X-1402213D02*
X-1402225D01*
G01X-1402199Y1159292D02*
X-1402213Y1159291D01*
G01X-1402186Y1159293D02*
X-1402199Y1159292D01*
G01X-1402174Y1159294D02*
X-1402186Y1159293D01*
G01X-1402162Y1159295D02*
X-1402174Y1159294D01*
G01X-1371272Y1157621D02*
G03I-1250J0D01*
G01X-1376220Y1155374D02*
G03X-1375754Y1155623I-423J1352D01*
G01X-1377390Y1155612D02*
G03X-1376938Y1155374I875J1114D01*
G01X-1370631Y1150633D02*
G03X-1369969Y1151386I409J308D01*
G01X-1378864Y1151207D02*
G03X-1379330Y1150958I423J-1352D01*
G01X-1377694Y1150969D02*
G03X-1378145Y1151207I-876J-1114D01*
G01X-1374924D02*
G03X-1375390Y1150958I423J-1352D01*
G01X-1373754Y1150969D02*
G03X-1374205Y1151207I-876J-1114D01*
G01X-1380160Y1155374D02*
G03X-1379694Y1155623I-423J1352D01*
G01X-1381330Y1155612D02*
G03X-1380878Y1155374I875J1114D01*
G01X-1391980D02*
G03X-1391514Y1155623I-423J1352D01*
G01X-1393150Y1155612D02*
G03X-1392698Y1155374I875J1114D01*
G01X-1388040D02*
G03X-1387574Y1155623I-423J1352D01*
G01X-1389210Y1155612D02*
G03X-1388758Y1155374I875J1114D01*
G01X-1384100D02*
G03X-1383634Y1155623I-423J1352D01*
G01X-1385270Y1155612D02*
G03X-1384818Y1155374I875J1114D01*
G01X-1385603Y1144441D02*
G03X-1386114Y1144952I-511J0D01*
G01X-1386614D02*
G03X-1387126Y1144441I0J-512D01*
G01X-1389526D02*
G03X-1390038Y1144952I-511J0D01*
G01X-1390538D02*
G03X-1391050Y1144441I0J-512D01*
G01X-1393450D02*
G03X-1393962Y1144952I-511J0D01*
G01X-1390684Y1151207D02*
G03X-1391150Y1150958I423J-1352D01*
G01X-1389514Y1150969D02*
G03X-1389965Y1151207I-876J-1114D01*
G01X-1386744D02*
G03X-1387210Y1150958I423J-1352D01*
G01X-1385574Y1150969D02*
G03X-1386025Y1151207I-876J-1114D01*
G01X-1382804D02*
G03X-1383270Y1150958I423J-1352D01*
G01X-1381634Y1150969D02*
G03X-1382085Y1151207I-876J-1114D01*
G01X-1402159Y1159280D02*
G03X-1402212Y1159906I-53J311D01*
G01X-1404627Y1158611D02*
G03X-1404136Y1158349I315J0D01*
G01X-1395012Y1157621D02*
G03I-1250J0D01*
G01X-1402212Y1146676D02*
G03X-1402159Y1147301I0J315D01*
G01X-1404136Y1148232D02*
G03X-1404627Y1147971I-176J-261D01*
G01X-1394462Y1144952D02*
G03X-1394974Y1144441I0J-512D01*
G01X-1398815Y1151386D02*
G03X-1398152Y1150634I253J-445D01*
G01X-1394624Y1151207D02*
G03X-1395090Y1150958I423J-1352D01*
G01X-1393454Y1150969D02*
G03X-1393905Y1151207I-876J-1114D01*
G01X-1394097Y1140488D02*
X-1394314Y1140443D01*
G01X-1387042Y1159432D02*
X-1387063D01*
G01X-1390982D02*
X-1391003D01*
G01X-1383802Y1147150D02*
X-1383780Y1147149D01*
G01X-1387742Y1147150D02*
X-1387720Y1147149D01*
G01X-1391682Y1147150D02*
X-1391660Y1147149D01*
G01X-1391525Y1164482D02*
X-1393139D01*
G01X-1387585D02*
X-1389199D01*
G01X-1383645D02*
X-1385259D01*
G01X-1379705D02*
X-1381319D01*
G01X-1375765D02*
X-1377379D01*
G01X-1398712Y1163791D02*
X-1402212D01*
G01X-1366572D02*
X-1370072D01*
G01X-1383402Y1163141D02*
X-1364172D01*
G01X-1383402D02*
X-1404612D01*
G01X-1364172Y1161541D02*
X-1383402D01*
G01D02*
X-1404612D01*
G01X-1374422Y1160387D02*
X-1383402D01*
G01D02*
X-1394362D01*
G01X-1391525Y1160332D02*
X-1393139D01*
G01X-1387585D02*
X-1389199D01*
G01X-1383645D02*
X-1385259D01*
G01X-1379705D02*
X-1381319D01*
G01X-1375765D02*
X-1377379D01*
G01X-1390982Y1160191D02*
X-1393682D01*
G01X-1387042D02*
X-1389742D01*
G01X-1383102D02*
X-1383402D01*
G01D02*
X-1385802D01*
G01X-1379162D02*
X-1381862D01*
G01X-1375222D02*
X-1377922D01*
G01X-1391525Y1159982D02*
X-1393139D01*
G01X-1387585D02*
X-1389199D01*
G01X-1383645D02*
X-1385259D01*
G01X-1379705D02*
X-1381319D01*
G01X-1375765D02*
X-1377379D01*
G01X-1383402Y1159641D02*
X-1374422D01*
G01X-1394362D02*
X-1383402D01*
G01X-1391525Y1159480D02*
X-1393139D01*
G01X-1387585D02*
X-1389199D01*
G01X-1383645D02*
X-1385259D01*
G01X-1383402Y1159441D02*
X-1374422D01*
G01X-1394362D02*
X-1383402D01*
G01X-1391003Y1159432D02*
X-1393660D01*
G01X-1387063D02*
X-1389720D01*
G01X-1383123D02*
X-1385780D01*
G01X-1379183D02*
X-1381840D01*
G01X-1375243D02*
X-1377900D01*
G01X-1402239Y1159291D02*
X-1402199D01*
G01X-1375322Y1159265D02*
X-1374947D01*
G01X-1379262D02*
X-1378887D01*
G01X-1378196D02*
X-1377822D01*
G01X-1382136D02*
X-1381762D01*
G01X-1383202D02*
X-1382827D01*
G01X-1385802D02*
X-1385702D01*
G01X-1389742D02*
X-1389642D01*
G01X-1387142D02*
X-1387042D01*
G01X-1393682D02*
X-1393582D01*
G01X-1391082D02*
X-1390982D01*
G01X-1402662Y1159239D02*
X-1403212D01*
G01Y1159038D02*
X-1402662D01*
G01X-1391003Y1158882D02*
X-1393660D01*
G01X-1387063D02*
X-1389720D01*
G01X-1383123D02*
X-1385780D01*
G01X-1379183D02*
X-1381840D01*
G01X-1375243D02*
X-1377900D01*
G01X-1375679Y1158853D02*
X-1375304D01*
G01X-1379619D02*
X-1379244D01*
G01X-1377840D02*
X-1377465D01*
G01X-1381780D02*
X-1381405D01*
G01X-1383559D02*
X-1383184D01*
G01X-1385720D02*
X-1385345D01*
G01X-1389660D02*
X-1389285D01*
G01X-1387499D02*
X-1387124D01*
G01X-1393600D02*
X-1393225D01*
G01X-1391439D02*
X-1391064D01*
G01X-1391525Y1158790D02*
X-1393139D01*
G01X-1387585D02*
X-1389199D01*
G01X-1383645D02*
X-1385259D01*
G01X-1379705D02*
X-1381319D01*
G01X-1375765D02*
X-1377379D01*
G01X-1375622Y1158741D02*
X-1374422D01*
G01X-1379562D02*
X-1377522D01*
G01X-1383402D02*
X-1381462D01*
G01X-1383502D02*
X-1383402D01*
G01X-1391382D02*
X-1389342D01*
G01X-1394362D02*
X-1393282D01*
G01X-1385402D02*
X-1387442D01*
G01X-1393282Y1158526D02*
X-1394362D01*
G01X-1389342D02*
X-1391382D01*
G01X-1385402D02*
X-1387442D01*
G01X-1381462D02*
X-1383402D01*
G01D02*
X-1383502D01*
G01X-1377522D02*
X-1379562D01*
G01X-1374422D02*
X-1375622D01*
G01X-1376933Y1158355D02*
X-1376225D01*
G01X-1380873D02*
X-1380165D01*
G01X-1384813D02*
X-1384105D01*
G01X-1388753D02*
X-1388045D01*
G01X-1392693D02*
X-1391985D01*
G01X-1402972Y1158040D02*
X-1403212D01*
G01X-1391525Y1157016D02*
X-1393139D01*
G01X-1387585D02*
X-1389199D01*
G01X-1383645D02*
X-1385259D01*
G01X-1379705D02*
X-1381319D01*
G01X-1375765D02*
X-1377379D01*
G01X-1393282Y1156941D02*
X-1396783D01*
G01X-1389342D02*
X-1391382D01*
G01X-1385402D02*
X-1387442D01*
G01X-1381462D02*
X-1383402D01*
G01D02*
X-1383502D01*
G01X-1377522D02*
X-1379562D01*
G01X-1372000D02*
X-1375622D01*
G01X-1391525Y1156485D02*
X-1393139D01*
G01X-1387585D02*
X-1389199D01*
G01X-1383645D02*
X-1385259D01*
G01X-1379705D02*
X-1381319D01*
G01X-1375765D02*
X-1377379D01*
G01X-1391525Y1156035D02*
X-1393139D01*
G01X-1387585D02*
X-1389199D01*
G01X-1383645D02*
X-1385259D01*
G01X-1379705D02*
X-1381319D01*
G01X-1375765D02*
X-1377379D01*
G01Y1155956D02*
X-1375765D01*
G01X-1381319D02*
X-1379705D01*
G01X-1385259D02*
X-1383645D01*
G01X-1389199D02*
X-1387585D01*
G01X-1393139D02*
X-1391525D01*
G01X-1375622Y1155941D02*
X-1371636D01*
G01X-1383402D02*
X-1381462D01*
G01X-1383502D02*
X-1383402D01*
G01X-1393282D02*
X-1397147D01*
G01X-1391525D02*
X-1393139D01*
G01X-1389342D02*
X-1391382D01*
G01X-1387585D02*
X-1389199D01*
G01X-1385402D02*
X-1387442D01*
G01X-1383645D02*
X-1385259D01*
G01X-1379705D02*
X-1381319D01*
G01X-1377522D02*
X-1379562D01*
G01X-1375765D02*
X-1377379D01*
G01X-1376225Y1155877D02*
X-1375765D01*
G01X-1380165D02*
X-1379705D01*
G01X-1377379D02*
X-1376933D01*
G01X-1381319D02*
X-1380873D01*
G01X-1384105D02*
X-1383645D01*
G01X-1385259D02*
X-1384813D01*
G01X-1388045D02*
X-1387585D01*
G01X-1389199D02*
X-1388753D01*
G01X-1391985D02*
X-1391525D01*
G01X-1393139D02*
X-1392693D01*
G01X-1401712Y1155791D02*
X-1403212D01*
G01X-1391985Y1155601D02*
X-1392693D01*
G01X-1388045D02*
X-1388753D01*
G01X-1384105D02*
X-1384813D01*
G01X-1380165D02*
X-1380873D01*
G01X-1376225D02*
X-1376933D01*
G01X-1403662Y1155541D02*
X-1403212D01*
G01X-1402662D02*
X-1403212D01*
G01X-1376933Y1155426D02*
X-1376225D01*
G01X-1380873D02*
X-1380165D01*
G01X-1384813D02*
X-1384105D01*
G01X-1388753D02*
X-1388045D01*
G01X-1392693D02*
X-1391985D01*
G01Y1155391D02*
X-1392693D01*
G01X-1388045D02*
X-1388753D01*
G01X-1384105D02*
X-1384813D01*
G01X-1380165D02*
X-1380873D01*
G01X-1376225D02*
X-1376933D01*
G01X-1394362Y1155341D02*
X-1398162D01*
G01X-1370622D02*
X-1374422D01*
G01X-1391382Y1154491D02*
X-1393282D01*
G01X-1387442D02*
X-1389342D01*
G01X-1383502D02*
X-1385402D01*
G01X-1379562D02*
X-1381462D01*
G01X-1375622D02*
X-1377522D01*
G01X-1393322Y1152091D02*
X-1395222D01*
G01X-1389382D02*
X-1391282D01*
G01X-1385442D02*
X-1387342D01*
G01X-1381502D02*
X-1383402D01*
G01X-1377562D02*
X-1379462D01*
G01X-1373622D02*
X-1375522D01*
G01X-1374919Y1151191D02*
X-1374210D01*
G01X-1378859D02*
X-1378150D01*
G01X-1382799D02*
X-1382090D01*
G01X-1386739D02*
X-1386030D01*
G01X-1390679D02*
X-1389970D01*
G01X-1394619D02*
X-1393910D01*
G01Y1151156D02*
X-1394619D01*
G01X-1389970D02*
X-1390679D01*
G01X-1386030D02*
X-1386739D01*
G01X-1382090D02*
X-1382799D01*
G01X-1378150D02*
X-1378859D01*
G01X-1374210D02*
X-1374919D01*
G01X-1403212Y1151041D02*
X-1403662D01*
G01X-1402662D02*
X-1403212D01*
G01X-1374919Y1150981D02*
X-1374210D01*
G01X-1378859D02*
X-1378150D01*
G01X-1382799D02*
X-1382090D01*
G01X-1386739D02*
X-1386030D01*
G01X-1390679D02*
X-1389970D01*
G01X-1394619D02*
X-1393910D01*
G01X-1401712Y1150791D02*
X-1403212D01*
G01X-1394619Y1150705D02*
X-1395079D01*
G01X-1393465D02*
X-1393910D01*
G01X-1390679D02*
X-1391139D01*
G01X-1389525D02*
X-1389970D01*
G01X-1386739D02*
X-1387199D01*
G01X-1385585D02*
X-1386030D01*
G01X-1382799D02*
X-1383259D01*
G01X-1381645D02*
X-1382090D01*
G01X-1378859D02*
X-1379319D01*
G01X-1377705D02*
X-1378150D01*
G01X-1374919D02*
X-1375379D01*
G01X-1373765D02*
X-1374210D01*
G01X-1375379Y1150641D02*
X-1373765D01*
G01X-1379319D02*
X-1377705D01*
G01X-1383259D02*
X-1381645D01*
G01X-1387199D02*
X-1385585D01*
G01X-1391139D02*
X-1389525D01*
G01X-1395079D02*
X-1393465D01*
G01X-1395222D02*
X-1398162D01*
G01X-1391282D02*
X-1393322D01*
G01X-1387342D02*
X-1389382D01*
G01X-1383402D02*
X-1385442D01*
G01X-1379462D02*
X-1381502D01*
G01X-1375522D02*
X-1377562D01*
G01X-1370621D02*
X-1373622D01*
G01X-1393465Y1150625D02*
X-1395079D01*
G01X-1389525D02*
X-1391139D01*
G01X-1385585D02*
X-1387199D01*
G01X-1381645D02*
X-1383259D01*
G01X-1377705D02*
X-1379319D01*
G01X-1373765D02*
X-1375379D01*
G01Y1150546D02*
X-1373765D01*
G01X-1379319D02*
X-1377705D01*
G01X-1383259D02*
X-1381645D01*
G01X-1387199D02*
X-1385585D01*
G01X-1391139D02*
X-1389525D01*
G01X-1395079D02*
X-1393465D01*
G01X-1375379Y1150096D02*
X-1373765D01*
G01X-1379319D02*
X-1377705D01*
G01X-1383259D02*
X-1381645D01*
G01X-1387199D02*
X-1385585D01*
G01X-1391139D02*
X-1389525D01*
G01X-1395079D02*
X-1393465D01*
G01X-1373622Y1149641D02*
X-1369343D01*
G01X-1377562D02*
X-1375522D01*
G01X-1381502D02*
X-1379462D01*
G01X-1385442D02*
X-1383402D01*
G01X-1389382D02*
X-1387342D01*
G01X-1393322D02*
X-1391282D01*
G01X-1399440D02*
X-1395222D01*
G01X-1375379Y1149566D02*
X-1373765D01*
G01X-1379319D02*
X-1377705D01*
G01X-1383259D02*
X-1381645D01*
G01X-1387199D02*
X-1385585D01*
G01X-1391139D02*
X-1389525D01*
G01X-1395079D02*
X-1393465D01*
G01X-1403212Y1148542D02*
X-1402972D01*
G01X-1393910Y1148226D02*
X-1394619D01*
G01X-1389970D02*
X-1390679D01*
G01X-1386030D02*
X-1386739D01*
G01X-1382090D02*
X-1382799D01*
G01X-1378150D02*
X-1378859D01*
G01X-1374210D02*
X-1374919D01*
G01X-1373622Y1148055D02*
X-1370622D01*
G01X-1377562D02*
X-1375522D01*
G01X-1381502D02*
X-1379462D01*
G01X-1385442D02*
X-1383402D01*
G01X-1389382D02*
X-1387342D01*
G01X-1393322D02*
X-1391282D01*
G01X-1398162D02*
X-1395222D01*
G01X-1373622Y1147841D02*
X-1370622D01*
G01X-1395222D02*
X-1398162D01*
G01X-1391282D02*
X-1393322D01*
G01X-1387342D02*
X-1389382D01*
G01X-1383402D02*
X-1385442D01*
G01X-1379462D02*
X-1381502D01*
G01X-1375522D02*
X-1377562D01*
G01X-1375379Y1147792D02*
X-1373765D01*
G01X-1379319D02*
X-1377705D01*
G01X-1383259D02*
X-1381645D01*
G01X-1387199D02*
X-1385585D01*
G01X-1391139D02*
X-1389525D01*
G01X-1395079D02*
X-1393465D01*
G01X-1395165Y1147729D02*
X-1395540D01*
G01X-1393004D02*
X-1393379D01*
G01X-1391225D02*
X-1391600D01*
G01X-1389064D02*
X-1389439D01*
G01X-1387285D02*
X-1387660D01*
G01X-1385124D02*
X-1385499D01*
G01X-1381184D02*
X-1381559D01*
G01X-1383345D02*
X-1383720D01*
G01X-1377244D02*
X-1377619D01*
G01X-1379405D02*
X-1379780D01*
G01X-1375465D02*
X-1375840D01*
G01X-1373304D02*
X-1373679D01*
G01X-1392943Y1147699D02*
X-1395600D01*
G01X-1389003D02*
X-1391660D01*
G01X-1385063D02*
X-1387720D01*
G01X-1381123D02*
X-1383780D01*
G01X-1377183D02*
X-1379840D01*
G01X-1373243D02*
X-1375900D01*
G01X-1402662Y1147543D02*
X-1403212D01*
G01Y1147342D02*
X-1402662D01*
G01X-1395522Y1147317D02*
X-1395622D01*
G01X-1392922D02*
X-1393022D01*
G01X-1391582D02*
X-1391682D01*
G01X-1388982D02*
X-1389082D01*
G01X-1387642D02*
X-1387742D01*
G01X-1385042D02*
X-1385142D01*
G01X-1383702D02*
X-1383802D01*
G01X-1380827D02*
X-1381202D01*
G01X-1376887D02*
X-1377262D01*
G01X-1379762D02*
X-1380136D01*
G01X-1375822D02*
X-1376196D01*
G01X-1372947D02*
X-1373322D01*
G01X-1402198Y1147291D02*
X-1402239D01*
G01X-1392943Y1147149D02*
X-1395600D01*
G01X-1389003D02*
X-1391660D01*
G01X-1385063D02*
X-1387720D01*
G01X-1381123D02*
X-1383780D01*
G01X-1377183D02*
X-1379840D01*
G01X-1373243D02*
X-1375900D01*
G01X-1398162Y1147141D02*
X-1383402D01*
G01X-1370622D02*
X-1383402D01*
G01X-1387199Y1147101D02*
X-1385585D01*
G01X-1391139D02*
X-1389525D01*
G01X-1395079D02*
X-1393465D01*
G01X-1370622Y1146941D02*
X-1383402D01*
G01D02*
X-1398162D01*
G01X-1375379Y1146599D02*
X-1373765D01*
G01X-1379319D02*
X-1377705D01*
G01X-1383259D02*
X-1381645D01*
G01X-1387199D02*
X-1385585D01*
G01X-1391139D02*
X-1389525D01*
G01X-1395079D02*
X-1393465D01*
G01X-1375922Y1146391D02*
X-1373222D01*
G01X-1379862D02*
X-1377162D01*
G01X-1383402D02*
X-1381102D01*
G01X-1383802D02*
X-1383402D01*
G01X-1387742D02*
X-1385042D01*
G01X-1391682D02*
X-1388982D01*
G01X-1395622D02*
X-1392922D01*
G01X-1375379Y1146249D02*
X-1373765D01*
G01X-1379319D02*
X-1377705D01*
G01X-1383259D02*
X-1381645D01*
G01X-1387199D02*
X-1385585D01*
G01X-1391139D02*
X-1389525D01*
G01X-1395079D02*
X-1393465D01*
G01X-1383402Y1146194D02*
X-1370622D01*
G01X-1398162D02*
X-1383402D01*
G01X-1404612Y1145041D02*
X-1383402D01*
G01X-1364172D02*
X-1383402D01*
G01X-1393962Y1144941D02*
X-1394462D01*
G01X-1390038D02*
X-1390538D01*
G01X-1386114D02*
X-1386614D01*
G01X-1394962Y1143441D02*
X-1404612D01*
G01X-1391038D02*
X-1393462D01*
G01X-1387114D02*
X-1389538D01*
G01X-1364172D02*
X-1383402D01*
G01D02*
X-1385614D01*
G01X-1398712Y1142791D02*
X-1402212D01*
G01X-1366572D02*
X-1370072D01*
G01X-1393465Y1142099D02*
X-1395079D01*
G01X-1389525D02*
X-1391139D01*
G01X-1385585D02*
X-1387199D01*
G01X-1381645D02*
X-1383259D01*
G01X-1377705D02*
X-1379319D01*
G01X-1373765D02*
X-1375379D01*
G01X-1393140Y1141598D02*
X-1392879D01*
G01X-1395357D02*
X-1394314D01*
G01X-1394271Y1141376D02*
X-1395097D01*
G01Y1140710D02*
X-1394271D01*
G01X-1394314Y1140443D02*
X-1395097D01*
G01X-1393660Y1159432D02*
X-1393682D01*
G01X-1389720D02*
X-1389742D01*
G01X-1385780D02*
X-1385802D01*
G01X-1392943Y1147149D02*
X-1392922Y1147150D01*
G01X-1389003Y1147149D02*
X-1388982Y1147150D01*
G01X-1385063Y1147149D02*
X-1385042Y1147150D01*
G01X-1402239Y1159291D02*
X-1402731Y1159274D01*
G01X-1395622Y1147150D02*
X-1395600Y1147149D01*
G01X-1394314Y1141598D02*
X-1394097Y1141553D01*
G01X-1394140Y1141331D02*
X-1394271Y1141376D01*
G01X-1404144Y1148219D02*
X-1402662Y1147220D01*
G01X-1374889Y1158896D02*
X-1375322Y1159265D01*
G01X-1375679Y1158853D02*
X-1375246Y1158484D01*
G01X-1378829Y1158896D02*
X-1379262Y1159265D01*
G01X-1379619Y1158853D02*
X-1379186Y1158484D01*
G01X-1382769Y1158896D02*
X-1383202Y1159265D01*
G01X-1383559Y1158853D02*
X-1383427Y1158741D01*
G01X-1383402Y1158719D02*
X-1383126Y1158484D01*
G01X-1387042Y1159179D02*
X-1387142Y1159265D01*
G01X-1387499Y1158853D02*
X-1387367Y1158741D01*
G01X-1375465Y1147729D02*
X-1375898Y1148098D01*
G01X-1376254Y1147686D02*
X-1375822Y1147317D01*
G01X-1390982Y1159179D02*
X-1391082Y1159265D01*
G01X-1391439Y1158853D02*
X-1391307Y1158741D01*
G01X-1379405Y1147729D02*
X-1379838Y1148098D01*
G01X-1380194Y1147686D02*
X-1379762Y1147317D01*
G01X-1383345Y1147729D02*
X-1383477Y1147841D01*
G01X-1383802Y1147402D02*
X-1383702Y1147317D01*
G01X-1387285Y1147729D02*
X-1387417Y1147841D01*
G01X-1387742Y1147402D02*
X-1387642Y1147317D01*
G01X-1391225Y1147729D02*
X-1391357Y1147841D01*
G01X-1391682Y1147402D02*
X-1391582Y1147317D01*
G01X-1395165Y1147729D02*
X-1395297Y1147841D01*
G01X-1395622Y1147402D02*
X-1395522Y1147317D01*
G01X-1394097Y1141553D02*
X-1393923Y1141420D01*
G01X-1377822Y1159265D02*
X-1377465Y1158853D01*
G01X-1377840D02*
X-1378196Y1159265D01*
G01X-1377898Y1158484D02*
X-1378254Y1158896D01*
G01X-1381762Y1159265D02*
X-1381405Y1158853D01*
G01X-1381780D02*
X-1382136Y1159265D01*
G01X-1381838Y1158484D02*
X-1382194Y1158896D01*
G01X-1373246Y1148098D02*
X-1372889Y1147686D01*
G01X-1373304Y1147729D02*
X-1372947Y1147317D01*
G01X-1373322D02*
X-1373679Y1147729D01*
G01X-1385702Y1159265D02*
X-1385345Y1158853D01*
G01X-1385720D02*
X-1385802Y1158948D01*
G01X-1377186Y1148098D02*
X-1376829Y1147686D01*
G01X-1377244Y1147729D02*
X-1376887Y1147317D01*
G01X-1377262D02*
X-1377619Y1147729D01*
G01X-1389642Y1159265D02*
X-1389285Y1158853D01*
G01X-1389660D02*
X-1389742Y1158948D01*
G01X-1381126Y1148098D02*
X-1380769Y1147686D01*
G01X-1381184Y1147729D02*
X-1380827Y1147317D01*
G01X-1381202D02*
X-1381559Y1147729D01*
G01X-1393582Y1159265D02*
X-1393225Y1158853D01*
G01X-1393600D02*
X-1393682Y1158948D01*
G01X-1394053Y1141243D02*
X-1394140Y1141331D01*
G01X-1385124Y1147729D02*
X-1385042Y1147634D01*
G01X-1385142Y1147317D02*
X-1385499Y1147729D01*
G01X-1389064D02*
X-1388982Y1147634D01*
G01X-1389082Y1147317D02*
X-1389439Y1147729D01*
G01X-1393004D02*
X-1392922Y1147634D01*
G01X-1393022Y1147317D02*
X-1393379Y1147729D01*
G01X-1393923Y1141420D02*
X-1393792Y1141243D01*
G01X-1369343Y1149641D02*
X-1369753Y1150767D01*
G01X-1372000Y1156941D02*
X-1369975Y1151375D01*
G01X-1374947Y1159265D02*
X-1374889Y1158896D01*
G01X-1375304Y1158853D02*
X-1375246Y1158484D01*
G01X-1375840Y1147729D02*
X-1375898Y1148098D01*
G01X-1376196Y1147317D02*
X-1376254Y1147686D01*
G01X-1378887Y1159265D02*
X-1378829Y1158896D01*
G01X-1379244Y1158853D02*
X-1379186Y1158484D01*
G01X-1393792Y1141243D02*
X-1393749Y1141109D01*
G01X-1394010D02*
X-1394053Y1141243D01*
G01X-1379780Y1147729D02*
X-1379838Y1148098D01*
G01X-1380136Y1147317D02*
X-1380194Y1147686D01*
G01X-1382827Y1159265D02*
X-1382769Y1158896D01*
G01X-1383184Y1158853D02*
X-1383126Y1158484D01*
G01X-1383720Y1147729D02*
X-1383738Y1147841D01*
G01X-1387124Y1158853D02*
X-1387106Y1158741D01*
G01X-1387660Y1147729D02*
X-1387678Y1147841D01*
G01X-1391064Y1158853D02*
X-1391046Y1158741D01*
G01X-1391600Y1147729D02*
X-1391618Y1147841D01*
G01X-1395540Y1147729D02*
X-1395558Y1147841D01*
G01X-1370072Y1163791D02*
Y1142791D01*
G01X-1370622Y1161541D02*
Y1145041D01*
G01X-1373222Y1146391D02*
Y1147841D01*
G01X-1373243Y1147149D02*
Y1147699D01*
G01X-1373372Y1147149D02*
Y1147699D01*
G01X-1373516D02*
Y1147149D01*
G01X-1373622Y1152091D02*
Y1147841D01*
G01X-1373725Y1147149D02*
Y1147699D01*
G01X-1373754Y1147149D02*
Y1147699D01*
G01X-1373765Y1150955D02*
Y1142099D01*
G01X-1374210Y1151190D02*
Y1148226D01*
G01X-1374422Y1161541D02*
Y1159641D01*
G01Y1159441D02*
Y1155341D01*
G01X-1374919Y1148226D02*
Y1151190D01*
G01X-1375222Y1158741D02*
Y1160191D01*
G01X-1375243Y1158882D02*
Y1159432D01*
G01X-1375372Y1158882D02*
Y1159432D01*
G01X-1375379Y1142099D02*
Y1150944D01*
G01X-1375390Y1147699D02*
Y1147149D01*
G01X-1375419Y1147699D02*
Y1147149D01*
G01X-1375516Y1159432D02*
Y1158882D01*
G01X-1375522Y1152091D02*
Y1147841D01*
G01X-1375622Y1158741D02*
Y1154491D01*
G01X-1375627Y1147149D02*
Y1147699D01*
G01X-1375725Y1158882D02*
Y1159432D01*
G01X-1375754Y1158882D02*
Y1159432D01*
G01X-1375765Y1155638D02*
Y1164482D01*
G01X-1375772Y1147699D02*
Y1147149D01*
G01X-1375900Y1147699D02*
Y1147149D01*
G01X-1375922Y1147841D02*
Y1146391D01*
G01X-1376225Y1158355D02*
Y1155392D01*
G01X-1376933D02*
Y1158355D01*
G01X-1377162Y1147841D02*
Y1146391D01*
G01X-1377183Y1147149D02*
Y1147699D01*
G01X-1377312Y1147149D02*
Y1147699D01*
G01X-1377379Y1155626D02*
Y1164482D01*
G01X-1377390Y1159432D02*
Y1158882D01*
G01X-1377419Y1159432D02*
Y1158882D01*
G01X-1377456Y1147699D02*
Y1147149D01*
G01X-1377522Y1158741D02*
Y1154491D01*
G01X-1377562Y1152091D02*
Y1147841D01*
G01X-1377627Y1158882D02*
Y1159432D01*
G01X-1377665Y1147149D02*
Y1147699D01*
G01X-1377694Y1147149D02*
Y1147699D01*
G01X-1377705Y1150955D02*
Y1142099D01*
G01X-1377772Y1159432D02*
Y1158882D01*
G01X-1377900Y1159432D02*
Y1158882D01*
G01X-1377922Y1160191D02*
Y1158741D01*
G01X-1378150Y1151190D02*
Y1148226D01*
G01X-1378859D02*
Y1151190D01*
G01X-1379162Y1158741D02*
Y1160191D01*
G01X-1379183Y1158882D02*
Y1159432D01*
G01X-1379312Y1158882D02*
Y1159432D01*
G01X-1379319Y1142099D02*
Y1150944D01*
G01X-1379330Y1147699D02*
Y1147149D01*
G01X-1379359Y1147699D02*
Y1147149D01*
G01X-1379456Y1159432D02*
Y1158882D01*
G01X-1379462Y1152091D02*
Y1147841D01*
G01X-1379562Y1158741D02*
Y1154491D01*
G01X-1379567Y1147149D02*
Y1147699D01*
G01X-1379665Y1158882D02*
Y1159432D01*
G01X-1379694Y1158882D02*
Y1159432D01*
G01X-1379705Y1155638D02*
Y1164482D01*
G01X-1379712Y1147699D02*
Y1147149D01*
G01X-1379840Y1147699D02*
Y1147149D01*
G01X-1379862Y1147841D02*
Y1146391D01*
G01X-1380165Y1158355D02*
Y1155392D01*
G01X-1380873D02*
Y1158355D01*
G01X-1381102Y1147841D02*
Y1146391D01*
G01X-1381123Y1147149D02*
Y1147699D01*
G01X-1381252Y1147149D02*
Y1147699D01*
G01X-1381319Y1155626D02*
Y1164482D01*
G01X-1381330Y1159432D02*
Y1158882D01*
G01X-1381359Y1159432D02*
Y1158882D01*
G01X-1381396Y1147699D02*
Y1147149D01*
G01X-1381462Y1158741D02*
Y1154491D01*
G01X-1381502Y1152091D02*
Y1147841D01*
G01X-1381567Y1158882D02*
Y1159432D01*
G01X-1381605Y1147149D02*
Y1147699D01*
G01X-1381634Y1147149D02*
Y1147699D01*
G01X-1381645Y1150955D02*
Y1142099D01*
G01X-1381712Y1159432D02*
Y1158882D01*
G01X-1381840Y1159432D02*
Y1158882D01*
G01X-1381862Y1160191D02*
Y1158741D01*
G01X-1382090Y1151190D02*
Y1148226D01*
G01X-1382799D02*
Y1151190D01*
G01X-1383102Y1158741D02*
Y1160191D01*
G01X-1383123Y1158882D02*
Y1159432D01*
G01X-1383252Y1158882D02*
Y1159432D01*
G01X-1383259Y1142099D02*
Y1150944D01*
G01X-1383270Y1147699D02*
Y1147149D01*
G01X-1383299Y1147699D02*
Y1147149D01*
G01X-1383396Y1159432D02*
Y1158882D01*
G01X-1383402Y1147141D02*
Y1143441D01*
G01Y1158741D02*
Y1147841D01*
G01Y1163141D02*
Y1159441D01*
G01X-1383502Y1158741D02*
Y1154491D01*
G01X-1383507Y1147149D02*
Y1147699D01*
G01X-1383605Y1158882D02*
Y1159432D01*
G01X-1383634Y1158882D02*
Y1159432D01*
G01X-1383645Y1155638D02*
Y1164482D01*
G01X-1383652Y1147699D02*
Y1147149D01*
G01X-1383780Y1147699D02*
Y1147149D01*
G01X-1383802Y1147841D02*
Y1146391D01*
G01X-1384105Y1158355D02*
Y1155392D01*
G01X-1384813D02*
Y1158355D01*
G01X-1385042Y1147841D02*
Y1146391D01*
G01X-1385063Y1147149D02*
Y1147699D01*
G01X-1385192Y1147149D02*
Y1147699D01*
G01X-1385259Y1155626D02*
Y1164482D01*
G01X-1385270Y1159432D02*
Y1158882D01*
G01X-1385299Y1159432D02*
Y1158882D01*
G01X-1385336Y1147699D02*
Y1147149D01*
G01X-1385402Y1158741D02*
Y1154491D01*
G01X-1385442Y1152091D02*
Y1147841D01*
G01X-1385507Y1158882D02*
Y1159432D01*
G01X-1385545Y1147149D02*
Y1147699D01*
G01X-1385574Y1147149D02*
Y1147699D01*
G01X-1385585Y1150955D02*
Y1142099D01*
G01X-1385614Y1143441D02*
Y1144441D01*
G01X-1385652Y1159432D02*
Y1158882D01*
G01X-1385780Y1159432D02*
Y1158882D01*
G01X-1385802Y1160191D02*
Y1158741D01*
G01X-1386030Y1151190D02*
Y1148226D01*
G01X-1386739D02*
Y1151190D01*
G01X-1387042Y1158741D02*
Y1160191D01*
G01X-1387063Y1158882D02*
Y1159432D01*
G01X-1387114Y1144441D02*
Y1143441D01*
G01X-1387192Y1158882D02*
Y1159432D01*
G01X-1387199Y1142099D02*
Y1150944D01*
G01X-1387210Y1147699D02*
Y1147149D01*
G01X-1387239Y1147699D02*
Y1147149D01*
G01X-1387336Y1159432D02*
Y1158882D01*
G01X-1387342Y1152091D02*
Y1147841D01*
G01X-1387442Y1158741D02*
Y1154491D01*
G01X-1387447Y1147149D02*
Y1147699D01*
G01X-1387545Y1158882D02*
Y1159432D01*
G01X-1387574Y1158882D02*
Y1159432D01*
G01X-1387585Y1155638D02*
Y1164482D01*
G01X-1387592Y1147699D02*
Y1147149D01*
G01X-1387720Y1147699D02*
Y1147149D01*
G01X-1387742Y1147841D02*
Y1146391D01*
G01X-1388045Y1158355D02*
Y1155392D01*
G01X-1388753D02*
Y1158355D01*
G01X-1388982Y1147841D02*
Y1146391D01*
G01X-1389003Y1147149D02*
Y1147699D01*
G01X-1389132Y1147149D02*
Y1147699D01*
G01X-1389199Y1155626D02*
Y1164482D01*
G01X-1389210Y1159432D02*
Y1158882D01*
G01X-1389239Y1159432D02*
Y1158882D01*
G01X-1389276Y1147699D02*
Y1147149D01*
G01X-1389342Y1158741D02*
Y1154491D01*
G01X-1389382Y1152091D02*
Y1147841D01*
G01X-1389447Y1158882D02*
Y1159432D01*
G01X-1389485Y1147149D02*
Y1147699D01*
G01X-1389514Y1147149D02*
Y1147699D01*
G01X-1389525Y1150955D02*
Y1142099D01*
G01X-1389538Y1143441D02*
Y1144441D01*
G01X-1389592Y1159432D02*
Y1158882D01*
G01X-1389720Y1159432D02*
Y1158882D01*
G01X-1389742Y1160191D02*
Y1158741D01*
G01X-1389970Y1151190D02*
Y1148226D01*
G01X-1390679D02*
Y1151190D01*
G01X-1390982Y1158741D02*
Y1160191D01*
G01X-1391003Y1158882D02*
Y1159432D01*
G01X-1391038Y1144441D02*
Y1143441D01*
G01X-1391132Y1158882D02*
Y1159432D01*
G01X-1391139Y1142099D02*
Y1150944D01*
G01X-1391150Y1147699D02*
Y1147149D01*
G01X-1391179Y1147699D02*
Y1147149D01*
G01X-1391276Y1159432D02*
Y1158882D01*
G01X-1391282Y1152091D02*
Y1147841D01*
G01X-1391382Y1158741D02*
Y1154491D01*
G01X-1391387Y1147149D02*
Y1147699D01*
G01X-1391485Y1158882D02*
Y1159432D01*
G01X-1391514Y1158882D02*
Y1159432D01*
G01X-1391525Y1155638D02*
Y1164482D01*
G01X-1391532Y1147699D02*
Y1147149D01*
G01X-1391660Y1147699D02*
Y1147149D01*
G01X-1391682Y1147841D02*
Y1146391D01*
G01X-1391985Y1158355D02*
Y1155392D01*
G01X-1392693D02*
Y1158355D01*
G01X-1392922Y1147841D02*
Y1146391D01*
G01X-1392943Y1147149D02*
Y1147699D01*
G01X-1393072Y1147149D02*
Y1147699D01*
G01X-1393139Y1155626D02*
Y1164482D01*
G01X-1393150Y1159432D02*
Y1158882D01*
G01X-1393179Y1159432D02*
Y1158882D01*
G01X-1393216Y1147699D02*
Y1147149D01*
G01X-1393282Y1158741D02*
Y1154491D01*
G01X-1393322Y1152091D02*
Y1147841D01*
G01X-1393387Y1158882D02*
Y1159432D01*
G01X-1393401Y1140932D02*
Y1141287D01*
G01X-1393425Y1147149D02*
Y1147699D01*
G01X-1393454Y1147149D02*
Y1147699D01*
G01X-1393462Y1143441D02*
Y1144441D01*
G01X-1393465Y1150955D02*
Y1142099D01*
G01X-1393532Y1159432D02*
Y1158882D01*
G01X-1393660Y1159432D02*
Y1158882D01*
G01X-1393682Y1160191D02*
Y1158741D01*
G01X-1393749Y1141109D02*
Y1140932D01*
G01X-1393910Y1151190D02*
Y1148226D01*
G01X-1394010Y1140976D02*
Y1141109D01*
G01X-1394362Y1161541D02*
Y1159641D01*
G01Y1159441D02*
Y1155341D01*
G01X-1394619Y1148226D02*
Y1151190D01*
G01X-1394962Y1144441D02*
Y1143441D01*
G01X-1395079Y1142099D02*
Y1150944D01*
G01X-1395090Y1147699D02*
Y1147149D01*
G01X-1395097Y1141376D02*
Y1140710D01*
G01X-1395119Y1147699D02*
Y1147149D01*
G01X-1395222Y1152091D02*
Y1147841D01*
G01X-1395327Y1147149D02*
Y1147699D01*
G01X-1395472D02*
Y1147149D01*
G01X-1395600Y1147699D02*
Y1147149D01*
G01X-1395622Y1147841D02*
Y1146391D01*
G01X-1398162Y1161541D02*
Y1145041D01*
G01X-1398712Y1142791D02*
Y1163791D01*
G01X-1401652Y1161541D02*
Y1145041D01*
G01X-1401712Y1155791D02*
Y1150791D01*
G01X-1401952Y1143441D02*
Y1163141D01*
G01X-1402162Y1155791D02*
Y1159295D01*
G01Y1147286D02*
Y1150791D01*
G01X-1402212Y1146691D02*
Y1142791D01*
G01Y1163791D02*
Y1159891D01*
G01X-1402662Y1159362D02*
Y1147220D01*
G01X-1402809Y1151041D02*
Y1155541D01*
G01X-1402972Y1151041D02*
Y1148542D01*
G01Y1158040D02*
Y1155541D01*
G01X-1403031Y1151041D02*
Y1155541D01*
G01X-1403212Y1159239D02*
Y1147342D01*
G01X-1403286Y1151041D02*
Y1155541D01*
G01X-1403454Y1151041D02*
Y1155541D01*
G01X-1403662Y1151041D02*
Y1155541D01*
G01X-1404612Y1147971D02*
Y1143441D01*
G01Y1163141D02*
Y1158611D01*
G01X-1372889Y1147686D02*
X-1372947Y1147317D01*
G01X-1373246Y1148098D02*
X-1373304Y1147729D01*
G01X-1376829Y1147686D02*
X-1376887Y1147317D01*
G01X-1377186Y1148098D02*
X-1377244Y1147729D01*
G01X-1377898Y1158484D02*
X-1377840Y1158853D01*
G01X-1378254Y1158896D02*
X-1378196Y1159265D01*
G01X-1380769Y1147686D02*
X-1380827Y1147317D01*
G01X-1381126Y1148098D02*
X-1381184Y1147729D01*
G01X-1381838Y1158484D02*
X-1381780Y1158853D01*
G01X-1382194Y1158896D02*
X-1382136Y1159265D01*
G01X-1385106Y1147841D02*
X-1385124Y1147729D01*
G01X-1385738Y1158741D02*
X-1385720Y1158853D01*
G01X-1389046Y1147841D02*
X-1389064Y1147729D01*
G01X-1389678Y1158741D02*
X-1389660Y1158853D01*
G01X-1392986Y1147841D02*
X-1393004Y1147729D01*
G01X-1393618Y1158741D02*
X-1393600Y1158853D01*
G01X-1399031Y1150767D02*
X-1399440Y1149641D01*
G01X-1396783Y1156941D02*
X-1398809Y1151375D01*
G01X-1393749Y1140932D02*
X-1393792Y1140799D01*
G01X-1394053Y1140843D02*
X-1394010Y1140976D01*
G01X-1394271Y1140710D02*
X-1394140Y1140754D01*
G01X-1393923Y1140621D02*
X-1394097Y1140488D01*
G01X-1373322Y1147317D02*
X-1372889Y1147686D01*
G01X-1373679Y1147729D02*
X-1373246Y1148098D01*
G01X-1377262Y1147317D02*
X-1376829Y1147686D01*
G01X-1377619Y1147729D02*
X-1377186Y1148098D01*
G01X-1381202Y1147317D02*
X-1380769Y1147686D01*
G01X-1381559Y1147729D02*
X-1381126Y1148098D01*
G01X-1385142Y1147317D02*
X-1385042Y1147402D01*
G01X-1385499Y1147729D02*
X-1385367Y1147841D01*
G01X-1389082Y1147317D02*
X-1388982Y1147402D01*
G01X-1389439Y1147729D02*
X-1389307Y1147841D01*
G01X-1377465Y1158853D02*
X-1377898Y1158484D01*
G01X-1377822Y1159265D02*
X-1378254Y1158896D01*
G01X-1393022Y1147317D02*
X-1392922Y1147402D01*
G01X-1393379Y1147729D02*
X-1393247Y1147841D01*
G01X-1381405Y1158853D02*
X-1381838Y1158484D01*
G01X-1381762Y1159265D02*
X-1382194Y1158896D01*
G01X-1385345Y1158853D02*
X-1385477Y1158741D01*
G01X-1394140Y1140754D02*
X-1394053Y1140843D01*
G01X-1375465Y1147729D02*
X-1375822Y1147317D01*
G01X-1376196D02*
X-1375840Y1147729D01*
G01X-1375898Y1148098D02*
X-1376254Y1147686D01*
G01X-1379405Y1147729D02*
X-1379762Y1147317D01*
G01X-1380136D02*
X-1379780Y1147729D01*
G01X-1379838Y1148098D02*
X-1380194Y1147686D01*
G01X-1383345Y1147729D02*
X-1383702Y1147317D01*
G01X-1383802Y1147634D02*
X-1383720Y1147729D01*
G01X-1375246Y1158484D02*
X-1374889Y1158896D01*
G01X-1374947Y1159265D02*
X-1375304Y1158853D01*
G01X-1375679D02*
X-1375322Y1159265D01*
G01X-1387285Y1147729D02*
X-1387642Y1147317D01*
G01X-1387742Y1147634D02*
X-1387660Y1147729D01*
G01X-1379186Y1158484D02*
X-1378829Y1158896D01*
G01X-1378887Y1159265D02*
X-1379244Y1158853D01*
G01X-1379619D02*
X-1379262Y1159265D01*
G01X-1391225Y1147729D02*
X-1391582Y1147317D01*
G01X-1391682Y1147634D02*
X-1391600Y1147729D01*
G01X-1383126Y1158484D02*
X-1382769Y1158896D01*
G01X-1382827Y1159265D02*
X-1383184Y1158853D01*
G01X-1383559D02*
X-1383202Y1159265D01*
G01X-1395165Y1147729D02*
X-1395522Y1147317D01*
G01X-1395622Y1147634D02*
X-1395540Y1147729D01*
G01X-1387042Y1158948D02*
X-1387124Y1158853D01*
G01X-1387499D02*
X-1387142Y1159265D01*
G01X-1390982Y1158948D02*
X-1391064Y1158853D01*
G01X-1391439D02*
X-1391082Y1159265D01*
G01X-1393140Y1141243D02*
X-1393401Y1140932D01*
G01Y1141287D02*
X-1393140Y1141598D01*
G01X-1393792Y1140799D02*
X-1393923Y1140621D01*
G01X-1402662Y1159362D02*
X-1404144Y1158362D01*
G01X-1385702Y1159265D02*
X-1385802Y1159179D01*
G01X-1389285Y1158853D02*
X-1389417Y1158741D01*
G01X-1389642Y1159265D02*
X-1389742Y1159179D01*
G01X-1393225Y1158853D02*
X-1393357Y1158741D01*
G01X-1393582Y1159265D02*
X-1393682Y1159179D01*
G01X-1399786Y1276519D02*
X-1300757D01*
G01X-1402935D02*
X-1399786D01*
G01X-1312513Y-525398D02*
G03X-1308576Y-529335I3937J0D01*
G01X-1312513Y-525398D02*
Y-100005D01*
G01X-1308576Y-529335D02*
X-678773D01*
G01X-1284481Y-371658D02*
G03I-6496J0D01*
G01X-1272277D02*
G03I-18700J0D01*
G01X-1312513Y-100005D02*
G03X-1316450Y-96068I-3937J0D01*
G01X-1297473Y-109060D02*
G03Y-122446I0J-6693D01*
G01X-1272080Y-115753D02*
G03I-18700J0D01*
G01X-1284088Y-109060D02*
X-1297473D01*
G01X-1284088Y-122446D02*
X-1297473D01*
G01X-1266371Y-56894D02*
G03I-18701J0D01*
G01X-1362394Y-47436D02*
X-1364855D01*
G01X-1348451D02*
X-1350912D01*
G01Y-55393D02*
X-1362394D01*
G01Y-57906D02*
X-1350912D01*
G01Y-67121D02*
X-1348451D01*
G01X-1364855D02*
X-1362394D01*
G01X-1348451D02*
Y-47436D01*
G01X-1350912Y-57906D02*
Y-67121D01*
G01Y-47436D02*
Y-55393D01*
G01X-1362394D02*
Y-47436D01*
G01Y-67121D02*
Y-57906D01*
G01X-1364855Y-47436D02*
Y-67121D01*
G01X-1310633Y473369D02*
Y432110D01*
G01Y477306D02*
G03X-1306696Y473369I3937J0D01*
G01X-1310633Y477306D02*
G03X-1306696Y473369I3937J0D01*
G01X-1310633Y477306D02*
Y902700D01*
G01Y477306D02*
Y902700D01*
G01X-1306696Y473369D02*
X-676893D01*
G01X-1306696D02*
X-676893D01*
G01X-1299727Y631047D02*
X-1345672D01*
G01X-1331890Y579937D02*
X-1335040D01*
G01X-1293268Y626066D02*
X-1331890Y579937D01*
G01X-1289098Y649747D02*
G03Y612346I0J-18701D01*
G01X-1298743Y657917D02*
G03X-1297956Y657129I788J0D01*
G01X-1299531Y657917D02*
G03X-1297956Y656342I1575J0D01*
G01X-1304058Y655062D02*
G03X-1302090Y653094I1968J0D01*
G01X-1295200Y707621D02*
X-1303074D01*
G01X-1295200Y706440D02*
X-1303074D01*
G01X-1295200Y704472D02*
X-1303074D01*
G01X-1295200Y703291D02*
X-1303074D01*
G01X-1295200Y701322D02*
X-1303074D01*
G01X-1295200Y700141D02*
X-1303074D01*
G01X-1295200Y698173D02*
X-1303074D01*
G01X-1295200Y696991D02*
X-1303074D01*
G01X-1295200Y695023D02*
X-1303074D01*
G01X-1295200Y693842D02*
X-1303074D01*
G01X-1295200Y691873D02*
X-1303074D01*
G01X-1295200Y690692D02*
X-1303074D01*
G01X-1295200Y688724D02*
X-1303074D01*
G01X-1295200Y687543D02*
X-1303074D01*
G01X-1295200Y685574D02*
X-1303074D01*
G01X-1295200Y684393D02*
X-1303074D01*
G01X-1295200Y682425D02*
X-1303074D01*
G01X-1295200Y681243D02*
X-1303074D01*
G01X-1295200Y679275D02*
X-1303074D01*
G01X-1295200Y678094D02*
X-1303074D01*
G01X-1295200Y676125D02*
X-1303074D01*
G01X-1295200Y674944D02*
X-1303074D01*
G01X-1295200Y672976D02*
X-1303074D01*
G01X-1295200Y671795D02*
X-1303074D01*
G01X-1295200Y669826D02*
X-1303074D01*
G01X-1295200Y668645D02*
X-1303074D01*
G01X-1295200Y666677D02*
X-1303074D01*
G01X-1295200Y665495D02*
X-1303074D01*
G01X-1298743Y662444D02*
X-1304058D01*
G01X-1280436Y660869D02*
X-1304058D01*
G01X-1299531Y657917D02*
X-1298743D01*
G01X-1297956Y657129D02*
X-1293625D01*
G01X-1296184Y653881D02*
Y653094D01*
G01X-1297956Y657129D02*
Y656342D01*
G01X-1298743Y860082D02*
Y657917D01*
G01X-1299531D02*
Y860082D01*
G01X-1303074Y666677D02*
Y665495D01*
G01Y669826D02*
Y668645D01*
G01Y672976D02*
Y671795D01*
G01Y676125D02*
Y674944D01*
G01Y679275D02*
Y678094D01*
G01Y682425D02*
Y681243D01*
G01Y685574D02*
Y684393D01*
G01Y688724D02*
Y687543D01*
G01Y691873D02*
Y690692D01*
G01Y698173D02*
Y696991D01*
G01Y695023D02*
Y693842D01*
G01Y701322D02*
Y700141D01*
G01Y704472D02*
Y703291D01*
G01Y707621D02*
Y706440D01*
G01X-1304058Y662444D02*
Y655062D01*
G01X-1293625Y656342D02*
X-1297956D01*
G01X-1288310Y653881D02*
X-1296184D01*
G01Y653094D02*
X-1302090D01*
G01X-1295200Y780062D02*
X-1303074D01*
G01X-1295200Y778881D02*
X-1303074D01*
G01X-1295200Y776913D02*
X-1303074D01*
G01X-1298743Y776322D02*
X-1299531D01*
G01X-1295200Y775732D02*
X-1303074D01*
G01X-1295200Y773763D02*
X-1303074D01*
G01X-1295200Y772582D02*
X-1303074D01*
G01X-1295200Y770614D02*
X-1303074D01*
G01X-1295200Y769432D02*
X-1303074D01*
G01X-1295200Y767464D02*
X-1303074D01*
G01X-1295200Y766283D02*
X-1303074D01*
G01X-1298704Y764905D02*
X-1298743D01*
G01X-1295200Y764314D02*
X-1303074D01*
G01X-1298704Y764191D02*
X-1298743D01*
G01X-1295200Y763133D02*
X-1303074D01*
G01X-1295200Y761165D02*
X-1303074D01*
G01X-1298704Y761099D02*
X-1298743D01*
G01X-1298704Y760623D02*
X-1298743D01*
G01X-1295200Y759984D02*
X-1303074D01*
G01X-1298704Y759672D02*
X-1298743D01*
G01X-1298704Y759553D02*
X-1298743D01*
G01X-1298704Y759315D02*
X-1298743D01*
G01X-1298704Y758958D02*
X-1298743D01*
G01X-1298704Y758839D02*
X-1298743D01*
G01X-1298704Y758602D02*
X-1298743D01*
G01X-1298704Y758364D02*
X-1298743D01*
G01X-1298704Y758245D02*
X-1298743D01*
G01X-1295200Y758015D02*
X-1303074D01*
G01X-1298704Y757769D02*
X-1298743D01*
G01X-1295200Y756834D02*
X-1303074D01*
G01X-1298704Y756699D02*
X-1298743D01*
G01X-1298704Y756223D02*
X-1298743D01*
G01X-1298704Y756104D02*
X-1298743D01*
G01X-1298704Y755866D02*
X-1298743D01*
G01X-1298704Y755747D02*
X-1298743D01*
G01X-1298704Y755628D02*
X-1298743D01*
G01X-1298704Y755153D02*
X-1298743D01*
G01X-1298704Y755034D02*
X-1298743D01*
G01X-1295200Y754865D02*
X-1303074D01*
G01X-1298704Y754082D02*
X-1298743D01*
G01X-1295200Y753684D02*
X-1303074D01*
G01X-1298704Y753369D02*
X-1298743D01*
G01X-1295200Y751716D02*
X-1303074D01*
G01X-1295200Y750535D02*
X-1303074D01*
G01X-1295200Y748566D02*
X-1303074D01*
G01X-1295200Y747385D02*
X-1303074D01*
G01X-1295200Y745417D02*
X-1303074D01*
G01X-1295200Y744236D02*
X-1303074D01*
G01X-1295200Y742267D02*
X-1303074D01*
G01X-1298743Y741677D02*
X-1299531D01*
G01X-1295200Y741086D02*
X-1303074D01*
G01X-1295200Y739117D02*
X-1303074D01*
G01X-1295200Y737936D02*
X-1303074D01*
G01X-1295200Y735968D02*
X-1303074D01*
G01X-1298743Y735377D02*
X-1299531D01*
G01X-1295200Y734787D02*
X-1303074D01*
G01X-1295200Y732818D02*
X-1303074D01*
G01X-1295200Y731637D02*
X-1303074D01*
G01X-1295200Y729669D02*
X-1303074D01*
G01X-1295200Y728488D02*
X-1303074D01*
G01X-1295200Y726519D02*
X-1303074D01*
G01X-1298743Y725928D02*
X-1299531D01*
G01X-1295200Y725338D02*
X-1303074D01*
G01X-1295200Y723369D02*
X-1303074D01*
G01X-1295200Y722188D02*
X-1303074D01*
G01X-1295200Y720220D02*
X-1303074D01*
G01X-1298743Y719629D02*
X-1299531D01*
G01X-1295200Y719039D02*
X-1303074D01*
G01X-1295200Y717070D02*
X-1303074D01*
G01X-1295200Y715889D02*
X-1303074D01*
G01X-1295200Y713921D02*
X-1303074D01*
G01X-1295200Y712739D02*
X-1303074D01*
G01X-1295200Y710771D02*
X-1303074D01*
G01X-1295200Y709590D02*
X-1303074D01*
G01X-1298704Y754082D02*
Y753369D01*
G01Y759672D02*
Y755034D01*
G01Y764905D02*
Y760623D01*
G01X-1303074Y710771D02*
Y709590D01*
G01Y713921D02*
Y712739D01*
G01Y717070D02*
Y715889D01*
G01Y720220D02*
Y719039D01*
G01Y723369D02*
Y722188D01*
G01Y726519D02*
Y725338D01*
G01Y729669D02*
Y728488D01*
G01Y732818D02*
Y731637D01*
G01Y735968D02*
Y734787D01*
G01Y739117D02*
Y737936D01*
G01Y742267D02*
Y741086D01*
G01Y745417D02*
Y744236D01*
G01Y748566D02*
Y747385D01*
G01Y751716D02*
Y750535D01*
G01Y754865D02*
Y753684D01*
G01Y761165D02*
Y759984D01*
G01Y758015D02*
Y756834D01*
G01Y764314D02*
Y763133D01*
G01Y767464D02*
Y766283D01*
G01Y770614D02*
Y769432D01*
G01Y773763D02*
Y772582D01*
G01Y776913D02*
Y775732D01*
G01Y780062D02*
Y778881D01*
G01X-1239201Y884003D02*
G03I-38144J0D01*
G01X-1295200Y852503D02*
X-1303074D01*
G01X-1295200Y851322D02*
X-1303074D01*
G01X-1295200Y849354D02*
X-1303074D01*
G01X-1295200Y848173D02*
X-1303074D01*
G01X-1295200Y846204D02*
X-1303074D01*
G01X-1295200Y845023D02*
X-1303074D01*
G01X-1295200Y843054D02*
X-1303074D01*
G01X-1295200Y841873D02*
X-1303074D01*
G01X-1295200Y839905D02*
X-1303074D01*
G01X-1295200Y838724D02*
X-1303074D01*
G01X-1295200Y836755D02*
X-1303074D01*
G01X-1295200Y835574D02*
X-1303074D01*
G01X-1295200Y833606D02*
X-1303074D01*
G01X-1295200Y832425D02*
X-1303074D01*
G01X-1295200Y830456D02*
X-1303074D01*
G01X-1295200Y829275D02*
X-1303074D01*
G01X-1295200Y827306D02*
X-1303074D01*
G01X-1295200Y826125D02*
X-1303074D01*
G01X-1295200Y824157D02*
X-1303074D01*
G01X-1295200Y822976D02*
X-1303074D01*
G01X-1295200Y821007D02*
X-1303074D01*
G01X-1295200Y819826D02*
X-1303074D01*
G01X-1295200Y817858D02*
X-1303074D01*
G01X-1295200Y816677D02*
X-1303074D01*
G01X-1295200Y814708D02*
X-1303074D01*
G01X-1295200Y813527D02*
X-1303074D01*
G01X-1295200Y811558D02*
X-1303074D01*
G01X-1295200Y810377D02*
X-1303074D01*
G01X-1295200Y808409D02*
X-1303074D01*
G01X-1295200Y807228D02*
X-1303074D01*
G01X-1295200Y805259D02*
X-1303074D01*
G01X-1295200Y804078D02*
X-1303074D01*
G01X-1295200Y802110D02*
X-1303074D01*
G01X-1295200Y800928D02*
X-1303074D01*
G01X-1295200Y798960D02*
X-1303074D01*
G01X-1299531Y798369D02*
X-1298743D01*
G01X-1295200Y797779D02*
X-1303074D01*
G01X-1295200Y795810D02*
X-1303074D01*
G01X-1295200Y794629D02*
X-1303074D01*
G01X-1295200Y792661D02*
X-1303074D01*
G01X-1298743Y792070D02*
X-1299531D01*
G01X-1295200Y791480D02*
X-1303074D01*
G01X-1295200Y789511D02*
X-1303074D01*
G01X-1295200Y788330D02*
X-1303074D01*
G01X-1295200Y786362D02*
X-1303074D01*
G01X-1295200Y785180D02*
X-1303074D01*
G01X-1295200Y783212D02*
X-1303074D01*
G01X-1298743Y782621D02*
X-1299531D01*
G01X-1295200Y782031D02*
X-1303074D01*
G01Y783212D02*
Y782031D01*
G01Y786362D02*
Y785180D01*
G01Y789511D02*
Y788330D01*
G01Y792661D02*
Y791480D01*
G01Y795810D02*
Y794629D01*
G01Y798960D02*
Y797779D01*
G01Y802110D02*
Y800928D01*
G01Y805259D02*
Y804078D01*
G01Y808409D02*
Y807228D01*
G01Y811558D02*
Y810377D01*
G01Y814708D02*
Y813527D01*
G01Y817858D02*
Y816677D01*
G01Y821007D02*
Y819826D01*
G01Y827306D02*
Y826125D01*
G01Y824157D02*
Y822976D01*
G01Y830456D02*
Y829275D01*
G01Y833606D02*
Y832425D01*
G01Y836755D02*
Y835574D01*
G01Y839905D02*
Y838724D01*
G01Y843054D02*
Y841873D01*
G01Y846204D02*
Y845023D01*
G01Y849354D02*
Y848173D01*
G01Y852503D02*
Y851322D01*
G01X-1297956Y860869D02*
G03X-1298743Y860082I0J-787D01*
G01X-1297956Y861657D02*
G03X-1299531Y860082I0J-1575D01*
G01X-1302090Y864905D02*
G03X-1304058Y862936I0J-1968D01*
G01X-1310633Y902700D02*
G03X-1314570Y906637I-3937J0D01*
G01X-1310633Y902700D02*
G03X-1314570Y906637I-3937J0D01*
G01X-1295594Y893645D02*
G03Y880259I0J-6693D01*
G01X-1288901Y905653D02*
G03Y868251I0J-18701D01*
G01X-1296184Y864905D02*
X-1302090D01*
G01X-1288310Y864117D02*
X-1296184D01*
G01X-1293625Y861657D02*
X-1297956D01*
G01X-1293625Y860869D02*
X-1297956D01*
G01X-1298743Y860082D02*
X-1299531D01*
G01X-1280436Y857129D02*
X-1304058D01*
G01X-1298743Y855554D02*
X-1304058D01*
G01X-1296184Y864905D02*
Y864117D01*
G01X-1297956Y861657D02*
Y860869D01*
G01X-1304058Y862936D02*
Y855554D01*
G01X-1309058Y983291D02*
Y919039D01*
G01X-1322601Y881556D02*
X-1334412D01*
G01X-1315434Y881944D02*
X-1322601Y881556D01*
G01X-1264491Y945810D02*
G03I-18701J0D01*
G01X-1356695Y952446D02*
X-1355055D01*
G01X-1363257D02*
X-1361616D01*
G01X-1367358D02*
X-1365307D01*
G01X-1362437Y950771D02*
X-1363257D01*
G01X-1355875D02*
X-1357105D01*
G01X-1365307Y939043D02*
X-1367358D01*
G01X-1358746D02*
X-1360796D01*
G01X-1352184D02*
X-1354234D01*
G01X-1355055Y952446D02*
X-1353824Y952027D01*
G01X-1361616Y952446D02*
X-1360386Y952027D01*
G01X-1355055Y950352D02*
X-1355875Y950771D01*
G01X-1361616Y950352D02*
X-1362437Y950771D01*
G01X-1353824Y952027D02*
X-1353004Y951189D01*
G01X-1354645Y949933D02*
X-1355055Y950352D01*
G01X-1360386Y952027D02*
X-1359156Y950771D01*
G01X-1361206Y949933D02*
X-1361616Y950352D01*
G01X-1354234Y949095D02*
X-1354645Y949933D01*
G01X-1353004Y951189D02*
X-1352184Y949095D01*
G01X-1360796D02*
X-1361206Y949933D01*
G01X-1357925Y952027D02*
X-1356695Y952446D01*
G01X-1363257Y950771D02*
X-1364487Y950352D01*
G01Y952027D02*
X-1363257Y952446D01*
G01X-1357105Y950771D02*
X-1357925Y950352D01*
G01D02*
X-1358335Y949933D01*
G01X-1359156Y950771D02*
X-1357925Y952027D01*
G01X-1364487Y950352D02*
X-1365307Y949514D01*
G01Y951189D02*
X-1364487Y952027D01*
G01X-1352184Y949095D02*
Y939043D01*
G01X-1354234D02*
Y949095D01*
G01X-1358746D02*
Y939043D01*
G01X-1360796D02*
Y949095D01*
G01X-1365307Y949514D02*
Y939043D01*
G01Y952446D02*
Y951189D01*
G01X-1367358Y939043D02*
Y952446D01*
G01X-1358335Y949933D02*
X-1358746Y949095D01*
G01X-1199885Y1003330D02*
X-1325869D01*
G01D02*
Y1237149D01*
G01X-1365829Y1148356D02*
X-1365812Y1148542D01*
G01X-1365884Y1148168D02*
X-1365829Y1148356D01*
G01X-1365982Y1147984D02*
X-1365884Y1148168D01*
G01X-1366122Y1147818D02*
X-1365982Y1147984D01*
G01X-1365828Y1158224D02*
X-1365812Y1158040D01*
G01X-1365884Y1158412D02*
X-1365828Y1158224D01*
G01X-1365981Y1158596D02*
X-1365884Y1158412D01*
G01X-1366122Y1158763D02*
X-1365981Y1158596D01*
G01X-1366440Y1159280D02*
X-1366585Y1159291D01*
G01X-1366311Y1159270D02*
X-1366440Y1159280D01*
G01X-1366209Y1159260D02*
X-1366311Y1159270D01*
G01X-1366144Y1159250D02*
X-1366209Y1159260D01*
G01X-1366122Y1159239D02*
X-1366144Y1159250D01*
G01X-1366053Y1159274D02*
X-1366545Y1159291D01*
G01X-1365853Y1159265D02*
X-1366053Y1159274D01*
G01X-1365700Y1159256D02*
X-1365853Y1159265D01*
G01X-1365604Y1159248D02*
X-1365700Y1159256D01*
G01X-1365572Y1159239D02*
X-1365604Y1159248D01*
G01X-1366559Y1147291D02*
X-1366545D01*
G01X-1366571Y1147290D02*
X-1366559Y1147291D01*
G01X-1366585Y1147290D02*
X-1366571D01*
G01X-1366597Y1147289D02*
X-1366585Y1147290D01*
G01X-1366610Y1147288D02*
X-1366597Y1147289D01*
G01X-1366622Y1147286D02*
X-1366610Y1147288D01*
G01X-1366144Y1147332D02*
X-1366122Y1147342D01*
G01X-1366209Y1147322D02*
X-1366144Y1147332D01*
G01X-1366310Y1147311D02*
X-1366209Y1147322D01*
G01X-1366440Y1147301D02*
X-1366310Y1147311D01*
G01X-1366585Y1147291D02*
X-1366440Y1147301D01*
G01X-1365604Y1147334D02*
X-1365572Y1147342D01*
G01X-1365700Y1147325D02*
X-1365604Y1147334D01*
G01X-1365853Y1147316D02*
X-1365700Y1147325D01*
G01X-1366053Y1147308D02*
X-1365853Y1147316D01*
G01X-1366608Y1159294D02*
X-1366622Y1159295D01*
G01X-1366596Y1159293D02*
X-1366608Y1159294D01*
G01X-1366582Y1159292D02*
X-1366596Y1159293D01*
G01X-1366570Y1159291D02*
X-1366582Y1159292D01*
G01X-1366557Y1159291D02*
X-1366570D01*
G01X-1366545D02*
X-1366557D01*
G01X-1366615Y1159294D02*
X-1366622Y1159295D01*
G01X-1366610Y1159293D02*
X-1366615Y1159294D01*
G01X-1366603Y1159292D02*
X-1366610Y1159293D01*
G01X-1366597Y1159291D02*
X-1366603Y1159292D01*
G01X-1366591Y1159291D02*
X-1366597D01*
G01X-1366585D02*
X-1366591D01*
G01X-1366592Y1147291D02*
X-1366585D01*
G01X-1366598Y1147290D02*
X-1366592Y1147291D01*
G01X-1366604Y1147290D02*
X-1366598D01*
G01X-1366610Y1147289D02*
X-1366604Y1147290D01*
G01X-1366616Y1147288D02*
X-1366610Y1147289D01*
G01X-1366622Y1147286D02*
X-1366616Y1147288D01*
G01X-1364648Y1158349D02*
G03X-1364157Y1158611I176J262D01*
G01X-1366572Y1159906D02*
G03X-1366624Y1159280I0J-315D01*
G01X-1364157Y1147971D02*
G03X-1364648Y1148232I-315J0D01*
G01X-1366624Y1147301D02*
G03X-1366572Y1146676I52J-310D01*
G01X-1366585Y1159291D02*
X-1366545D01*
G01X-1365572Y1159239D02*
X-1366122D01*
G01Y1159038D02*
X-1365572D01*
G01Y1158040D02*
X-1365812D01*
G01X-1365572Y1155791D02*
X-1367072D01*
G01X-1365572Y1155541D02*
X-1365122D01*
G01X-1365572D02*
X-1366122D01*
G01X-1365572Y1151041D02*
X-1365122D01*
G01X-1366122D02*
X-1365572D01*
G01X-1367072Y1150791D02*
X-1365572D01*
G01X-1365812Y1148542D02*
X-1365572D01*
G01Y1147543D02*
X-1366122D01*
G01Y1147342D02*
X-1365572D01*
G01X-1366545Y1147291D02*
X-1366585D01*
G01X-1366545D02*
X-1366053Y1147308D01*
G01X-1366122Y1159362D02*
X-1364640Y1158362D01*
G01X-1364172Y1147971D02*
Y1143441D01*
G01Y1163141D02*
Y1158611D01*
G01X-1365122Y1155541D02*
Y1151041D01*
G01X-1365330Y1155541D02*
Y1151041D01*
G01X-1365498Y1155541D02*
Y1151041D01*
G01X-1365572Y1147342D02*
Y1159239D01*
G01X-1365753Y1155541D02*
Y1151041D01*
G01X-1365812Y1155541D02*
Y1158040D01*
G01Y1148542D02*
Y1151041D01*
G01X-1365974Y1155541D02*
Y1151041D01*
G01X-1366122Y1159362D02*
Y1147220D01*
G01X-1366572Y1146691D02*
Y1142791D01*
G01Y1163791D02*
Y1159891D01*
G01X-1366622Y1150791D02*
Y1147286D01*
G01Y1159295D02*
Y1155791D01*
G01X-1366832Y1163141D02*
Y1143441D01*
G01X-1367072Y1155791D02*
Y1150791D01*
G01X-1367132Y1161541D02*
Y1145041D01*
G01X-1364640Y1148219D02*
X-1366122Y1147220D01*
G01X-1238322Y-714465D02*
Y-733402D01*
G01X-1284088Y-122446D02*
G03Y-109060I0J6693D01*
G01X-1278182Y-56894D02*
G03I-6890J0D01*
G01X-1228969Y210822D02*
G03I-6890J0D01*
G01X-1217158D02*
G03I-18701J0D01*
G01X-1224906Y225979D02*
X-1197871Y263388D01*
G01X-1288901Y876322D02*
Y432110D01*
G01X-1289098Y627110D02*
Y432110D01*
G01X-1244930Y490650D02*
X-1245002Y490773D01*
G01X-1244853Y490521D02*
X-1244930Y490650D01*
G01X-1244746Y490399D02*
X-1244853Y490521D01*
G01X-1244614Y490292D02*
X-1244746Y490399D01*
G01X-1244462Y490207D02*
X-1244614Y490292D01*
G01X-1244299Y490150D02*
X-1244462Y490207D01*
G01X-1237427Y478308D02*
X-1237383Y478263D01*
G01X-1237539Y478366D02*
X-1237427Y478308D01*
G01X-1258144Y486063D02*
X-1258136Y486038D01*
G01X-1258160Y486086D02*
X-1258144Y486063D01*
G01X-1258182Y486106D02*
X-1258160Y486086D01*
G01X-1241616Y475069D02*
X-1241475Y474886D01*
G01X-1241763Y475217D02*
X-1241616Y475069D01*
G01X-1248183Y486637D02*
X-1248191Y486647D01*
G01X-1248172Y486625D02*
X-1248183Y486637D01*
G01X-1258226Y486174D02*
X-1258231Y486212D01*
G01X-1258209Y486138D02*
X-1258226Y486174D01*
G01X-1258182Y486106D02*
X-1258209Y486138D01*
G01X-1258080Y485770D02*
X-1258152Y485952D01*
G01X-1257963Y485596D02*
X-1258080Y485770D01*
G01X-1258221Y486307D02*
X-1258231Y486370D01*
G01X-1258190Y486250D02*
X-1258221Y486307D01*
G01X-1242345Y475509D02*
X-1242483Y475519D01*
G01X-1242204Y475476D02*
X-1242345Y475509D01*
G01X-1242060Y475419D02*
X-1242204Y475476D01*
G01X-1241913Y475334D02*
X-1242060Y475419D01*
G01X-1241763Y475217D02*
X-1241913Y475334D01*
G01X-1241616Y475069D02*
X-1241763Y475217D01*
G01X-1241475Y474886D02*
X-1241616Y475069D01*
G01X-1241341Y474669D02*
X-1241475Y474886D01*
G01X-1241218Y474416D02*
X-1241341Y474669D01*
G01X-1246639Y471983D02*
X-1246698Y472188D01*
G01X-1246576Y471786D02*
X-1246639Y471983D01*
G01X-1246509Y471598D02*
X-1246576Y471786D01*
G01X-1258163Y486200D02*
X-1258190Y486250D01*
G01X-1258150Y486144D02*
X-1258163Y486200D01*
G01X-1258210Y486017D02*
X-1258135Y485791D01*
G01X-1258231Y486213D02*
X-1258210Y486017D01*
G01X-1245029Y491002D02*
X-1245069Y491226D01*
G01X-1244977Y490780D02*
X-1245029Y491002D01*
G01X-1244913Y491488D02*
X-1244876Y491225D01*
G01X-1244954Y491761D02*
X-1244913Y491488D01*
G01X-1244998Y492043D02*
X-1244954Y491761D01*
G01X-1258148Y486115D02*
X-1258150Y486137D01*
G01X-1258136Y486038D02*
X-1258148Y486115D01*
G01X-1238115Y486233D02*
X-1238117Y486185D01*
G01X-1238115Y486250D02*
Y486233D01*
G01X-1238158Y486115D02*
X-1238170Y486038D01*
G01X-1238156Y486137D02*
X-1238158Y486115D01*
G01X-1238096Y486138D02*
X-1238124Y486106D01*
G01X-1238080Y486174D02*
X-1238096Y486138D01*
G01X-1238074Y486212D02*
X-1238080Y486174D01*
G01X-1250211Y491488D02*
X-1250248Y491225D01*
G01X-1250170Y491761D02*
X-1250211Y491488D01*
G01X-1250126Y492043D02*
X-1250170Y491761D01*
G01X-1238084Y486307D02*
X-1238115Y486250D01*
G01X-1238074Y486370D02*
X-1238084Y486307D01*
G01X-1250095Y491002D02*
X-1250055Y491226D01*
G01X-1250148Y490780D02*
X-1250095Y491002D01*
G01X-1249729Y471786D02*
X-1249796Y471598D01*
G01X-1249666Y471983D02*
X-1249729Y471786D01*
G01X-1249607Y472188D02*
X-1249666Y471983D01*
G01X-1238095Y486018D02*
X-1238074Y486212D01*
G01X-1238170Y485791D02*
X-1238095Y486018D01*
G01X-1238145Y486086D02*
X-1238124Y486106D01*
G01X-1238161Y486063D02*
X-1238145Y486086D01*
G01X-1238170Y486038D02*
X-1238161Y486063D01*
G01X-1238225Y485771D02*
X-1238342Y485596D01*
G01X-1238154Y485952D02*
X-1238225Y485771D01*
G01X-1238226D02*
X-1238342Y485596D01*
G01X-1238154Y485951D02*
X-1238226Y485771D01*
G01X-1238272Y485766D02*
X-1238372Y485622D01*
G01X-1238204Y485916D02*
X-1238272Y485766D01*
G01X-1238143Y486200D02*
X-1238155Y486144D01*
G01X-1238115Y486250D02*
X-1238143Y486200D01*
G01D02*
X-1238155Y486144D01*
G01X-1238115Y486250D02*
X-1238143Y486200D01*
G01X-1258716Y478490D02*
X-1258598Y478658D01*
G01X-1258795Y478377D02*
X-1258716Y478490D01*
G01X-1258766Y478366D02*
X-1258722Y478411D01*
G01X-1258879Y478308D02*
X-1258766Y478366D01*
G01X-1250194Y490650D02*
X-1250122Y490773D01*
G01X-1250272Y490521D02*
X-1250194Y490650D01*
G01X-1250378Y490399D02*
X-1250272Y490521D01*
G01X-1250510Y490292D02*
X-1250378Y490399D01*
G01X-1250662Y490207D02*
X-1250510Y490292D01*
G01X-1250825Y490150D02*
X-1250662Y490207D01*
G01X-1237778Y491100D02*
G03X-1237888Y489840I696J-696D01*
G01X-1238613Y491936D02*
G03X-1238856Y489162I1531J-1532D01*
G01X-1237874Y484390D02*
G03X-1237985Y484334I29J-195D01*
G01X-1237874Y484390D02*
G03X-1237763Y484445I-28J195D01*
G01X-1238115Y486250D02*
G03X-1238155Y486144I157J-120D01*
G01X-1238654Y483555D02*
G03X-1238764Y482294I696J-696D01*
G01X-1238681Y483582D02*
G03X-1238796Y482271I723J-724D01*
G01X-1238709Y483610D02*
G03X-1238828Y482249I751J-751D01*
G01X-1239489Y484390D02*
G03X-1239731Y481617I1531J-1531D01*
G01X-1239517Y484418D02*
G03X-1239764Y481594I1559J-1559D01*
G01X-1239544Y484445D02*
G03X-1239796Y481571I1586J-1587D01*
G01X-1238074Y487735D02*
G03X-1238252Y488300I-984J0D01*
G01X-1236893Y487735D02*
G03X-1237284Y488977I-2165J1D01*
G01X-1238115Y486250D02*
G03X-1238074Y486370I-155J120D01*
G01X-1238418Y485572D02*
G03X-1238155Y486144I-640J641D01*
G01X-1238390Y485544D02*
G03X-1238342Y485596I-670J666D01*
G01X-1238362Y485516D02*
G03X-1238074Y486212I-697J696D01*
G01X-1237527Y484681D02*
G03X-1236893Y486212I-1532J1531D01*
G01X-1237138Y479972D02*
G03X-1237238Y480046I-161J-113D01*
G01X-1237338Y480120D02*
G03X-1237238Y480046I161J113D01*
G01X-1237583Y478411D02*
G03X-1237483Y478337I161J113D01*
G01X-1237383Y478263D02*
G03X-1237483Y478337I-161J-113D01*
G01X-1243625Y490778D02*
G03X-1242066Y491000I780J111D01*
G01X-1244806Y490778D02*
G03X-1243247Y491000I779J111D01*
G01X-1243820Y490751D02*
G03X-1242149Y491585I975J138D01*
G01X-1243657Y483130D02*
G03X-1243074Y483890I-204J760D01*
G01X-1242537Y480628D02*
G03X-1242286Y481204I-537J577D01*
G01X-1243454Y482369D02*
G03X-1242286Y483890I-406J1521D01*
G01X-1248968Y491248D02*
G03X-1249162Y489029I1012J-1206D01*
G01X-1249474Y491851D02*
G03X-1249765Y488523I1518J-1809D01*
G01X-1245680Y481772D02*
G03X-1246263Y480984I204J-760D01*
G01X-1245884Y482533D02*
G03X-1247050Y480957I408J-1521D01*
G01X-1245508Y477858D02*
G03X-1245833Y477396I941J-1007D01*
G01X-1246150Y476662D02*
G03X-1246263Y476116I1265J-546D01*
G01X-1245340Y471458D02*
G03X-1244855Y471204I485J336D01*
G01X-1246932Y472700D02*
G03X-1246342Y472110I590J0D01*
G01X-1245340Y471458D02*
G03X-1246509Y471598I-647J-450D01*
G01X-1244855Y471795D02*
G03X-1246698Y472188I-1131J-787D01*
G01X-1251877Y491000D02*
G03X-1250318Y490778I779J-111D01*
G01X-1253058Y491000D02*
G03X-1251499Y490778I779J-111D01*
G01X-1252975Y491585D02*
G03X-1251304Y490751I696J-696D01*
G01X-1249474Y491851D02*
G03X-1248349Y494188I-2024J2414D01*
G01X-1248968Y491248D02*
G03X-1248153Y492188I-2530J3017D01*
G01X-1250751Y485771D02*
G03X-1251145Y486165I-394J0D01*
G01Y484196D02*
G03X-1250751Y484590I0J394D01*
G01X-1251538Y485377D02*
G03X-1252412Y485739I-512J0D01*
G01X-1251460Y485377D02*
G03X-1252468Y485795I-591J0D01*
G01X-1254412Y485276D02*
G03X-1253404Y484858I591J0D01*
G01X-1254491Y485276D02*
G03X-1253349Y484803I669J0D01*
G01X-1250751Y478291D02*
G03X-1251145Y478684I-393J0D01*
G01Y476716D02*
G03X-1250751Y477110I0J394D01*
G01X-1252412Y477141D02*
G03X-1251538Y477503I362J362D01*
G01X-1251450Y471204D02*
G03X-1250965Y471458I0J590D01*
G01X-1253404Y478022D02*
G03X-1254412Y477605I-418J-417D01*
G01X-1252468Y477086D02*
G03X-1251460Y477503I418J417D01*
G01X-1253349Y478078D02*
G03X-1254491Y477605I-473J-473D01*
G01X-1249796Y471598D02*
G03X-1250965Y471458I-522J-590D01*
G01X-1249607Y472188D02*
G03X-1251450Y471795I-712J-1180D01*
G01X-1254885Y486165D02*
G03X-1255279Y485771I0J-394D01*
G01Y484590D02*
G03X-1254885Y484196I394J0D01*
G01X-1258150Y486144D02*
G03X-1258190Y486250I-197J-14D01*
G01X-1258231Y486370D02*
G03X-1258190Y486250I196J0D01*
G01X-1258150Y486144D02*
G03X-1257887Y485572I903J69D01*
G01X-1257963Y485596D02*
G03X-1257915Y485544I718J614D01*
G01X-1258231Y486212D02*
G03X-1257943Y485516I985J0D01*
G01X-1259412Y486212D02*
G03X-1258778Y484681I2166J0D01*
G01X-1258320Y484334D02*
G03X-1258431Y484390I-140J-139D01*
G01X-1258543Y484445D02*
G03X-1258431Y484390I139J141D01*
G01X-1257541Y482294D02*
G03X-1257652Y483555I-807J564D01*
G01X-1257509Y482271D02*
G03X-1257624Y483582I-839J587D01*
G01X-1257477Y482249D02*
G03X-1257596Y483610I-871J610D01*
G01X-1256574Y481617D02*
G03X-1256817Y484390I-1774J1242D01*
G01X-1256542Y481594D02*
G03X-1256789Y484418I-1806J1265D01*
G01X-1256509Y481571D02*
G03X-1256761Y484445I-1839J1287D01*
G01X-1259067Y480046D02*
G03X-1259167Y479972I61J-187D01*
G01X-1259067Y480046D02*
G03X-1258967Y480120I-61J187D01*
G01X-1258822Y478337D02*
G03X-1258722Y478411I-61J187D01*
G01X-1258822Y478337D02*
G03X-1258922Y478263I61J-187D01*
G01X-1255279Y477110D02*
G03X-1254885Y476716I394J0D01*
G01Y478684D02*
G03X-1255279Y478291I0J-394D01*
G01X-1245340Y471458D02*
X-1244855Y471795D01*
G01X-1236169Y477215D02*
X-1236491Y476990D01*
G01X-1236030Y478390D02*
X-1236998Y477712D01*
G01X-1237876Y478830D02*
X-1237812Y478875D01*
G01X-1237522Y480520D02*
X-1237586Y480475D01*
G01X-1238764Y482294D02*
X-1239796Y481571D01*
G01X-1237284Y488977D02*
X-1238252Y488300D01*
G01X-1237888Y489840D02*
X-1238856Y489162D01*
G01X-1248153Y486679D02*
X-1248191Y486647D01*
G01X-1249162Y489029D02*
X-1249765Y488523D01*
G01X-1257934Y485622D02*
X-1257993Y485570D01*
G01X-1242537Y480628D02*
X-1245508Y477858D01*
G01X-1237527Y484681D02*
X-1238654Y483555D01*
G01X-1237874Y484390D02*
X-1238681Y483582D01*
G01X-1237985Y484334D02*
X-1238709Y483610D01*
G01X-1238362Y485516D02*
X-1239489Y484390D01*
G01X-1238390Y485544D02*
X-1239517Y484418D01*
G01X-1238418Y485572D02*
X-1239544Y484445D01*
G01X-1236746Y492132D02*
X-1237778Y491100D01*
G01X-1258231Y471795D02*
X-1258822Y471204D01*
G01X-1237024Y493524D02*
X-1238613Y491936D01*
G01X-1241696Y489432D02*
X-1242286Y488842D01*
G01X-1252412Y485739D02*
X-1253349Y484803D01*
G01X-1252468Y485795D02*
X-1253404Y484858D01*
G01X-1256761Y484445D02*
X-1257652Y483555D01*
G01X-1258014Y484028D02*
X-1258069Y483972D01*
G01X-1257887Y485572D02*
X-1258778Y484681D01*
G01X-1258766Y478366D02*
X-1258722Y478411D01*
G01X-1258922Y478263D02*
X-1258879Y478308D01*
G01X-1256542Y481594D02*
X-1258718Y478488D01*
G01X-1256509Y481571D02*
X-1258722Y478411D01*
G01X-1256574Y481617D02*
X-1259814Y476990D01*
G01X-1257477Y482249D02*
X-1258967Y480120D01*
G01X-1257509Y482271D02*
X-1259067Y480046D01*
G01X-1257541Y482294D02*
X-1260330Y478312D01*
G01X-1258822Y478337D02*
X-1258795Y478377D01*
G01X-1258796Y478376D02*
X-1258822Y478337D01*
G01X-1238312Y485570D02*
X-1238170Y485791D01*
G01X-1240909Y474472D02*
X-1242272Y472110D01*
G01X-1238084Y486307D02*
X-1238115Y486250D01*
G01X-1246023Y474094D02*
X-1246206Y473694D01*
G01X-1245833Y477396D02*
X-1246150Y476662D01*
G01X-1238225Y485771D02*
X-1238154Y485953D01*
G01X-1238170Y486038D02*
X-1238205Y485913D01*
G01X-1238154Y485952D02*
X-1238124Y486106D01*
G01X-1235976Y478312D02*
X-1236169Y477215D01*
G01X-1249927Y492004D02*
X-1250055Y491226D01*
G01X-1251236D02*
X-1251108Y492004D01*
G01X-1251435Y491226D02*
X-1251307Y492043D01*
G01X-1249929Y491990D02*
X-1249042Y498111D01*
G01X-1249241Y498149D02*
X-1250126Y492043D01*
G01Y492238D02*
X-1249241Y498343D01*
G01X-1250225Y498096D02*
X-1251111Y491990D01*
G01X-1251307Y492043D02*
X-1250422Y498149D01*
G01Y498343D02*
X-1251307Y492238D01*
G01X-1250254Y491226D02*
X-1250318Y490778D01*
G01X-1251237Y491226D02*
X-1251304Y490751D01*
G01X-1251435Y491226D02*
X-1251499Y490778D01*
G01X-1250302Y502076D02*
X-1251877Y491000D01*
G01X-1251483Y502076D02*
X-1253058Y491000D01*
G01X-1250254Y491226D02*
X-1250126Y492238D01*
G01X-1251307D02*
X-1251435Y491226D01*
G01X-1238118Y486185D02*
X-1238124Y486106D01*
G01X-1238115Y486233D02*
X-1238117Y486185D01*
G01X-1236746Y493246D02*
Y492132D01*
G01X-1236893Y471204D02*
Y570614D01*
G01X-1238074Y471795D02*
Y570614D01*
G01X-1238664Y525338D02*
Y471204D01*
G01X-1240909Y512267D02*
Y474472D01*
G01X-1242286Y481204D02*
Y513054D01*
G01X-1242483D02*
Y475519D01*
G01X-1243074Y483890D02*
Y513054D01*
G01X-1243817Y492238D02*
Y492043D01*
G01X-1244216Y482149D02*
Y513054D01*
G01X-1244688Y478622D02*
Y473291D01*
G01X-1244855Y471795D02*
Y471204D01*
G01X-1244998Y492043D02*
Y492238D01*
G01X-1245003Y513054D02*
Y484539D01*
G01X-1246184D02*
Y484314D01*
G01X-1246263Y476116D02*
Y473291D01*
G01X-1246932Y472700D02*
Y473291D01*
G01X-1246972Y484539D02*
Y484314D01*
G01X-1247050Y484539D02*
Y481362D01*
G01X-1247562D02*
Y473449D01*
G01X-1248153Y513054D02*
Y474472D01*
G01X-1250126Y492043D02*
Y492238D01*
G01X-1243817D02*
X-1243689Y491226D01*
G01X-1244870D02*
X-1244998Y492238D01*
G01X-1250751Y484590D02*
Y485771D01*
G01Y477110D02*
Y478291D01*
G01X-1251307Y492238D02*
Y492043D01*
G01X-1251450Y471204D02*
Y471795D01*
G01X-1251460Y477503D02*
Y485377D01*
G01X-1251538Y477503D02*
Y485377D01*
G01X-1254412Y485276D02*
Y507132D01*
G01Y471204D02*
Y477605D01*
G01X-1254491Y485276D02*
Y507132D01*
G01Y471204D02*
Y477605D01*
G01X-1255279Y478291D02*
Y477110D01*
G01Y485771D02*
Y484590D01*
G01X-1257641Y525338D02*
Y471204D01*
G01X-1258231Y471795D02*
Y570614D01*
G01X-1259412Y471204D02*
Y570614D01*
G01X-1274137Y595614D02*
Y473369D01*
G01X-1258190Y486233D02*
Y486250D01*
G01X-1246023Y474094D02*
X-1246263Y480984D01*
G01X-1246837Y474854D02*
X-1247050Y480957D01*
G01X-1258190Y486233D02*
X-1258188Y486185D01*
G01D02*
X-1258182Y486106D01*
G01X-1243641Y502076D02*
X-1242066Y491000D01*
G01X-1244822Y502076D02*
X-1243247Y491000D01*
G01X-1243689Y491226D02*
X-1243625Y490778D01*
G01X-1243888Y491226D02*
X-1243820Y490751D01*
G01X-1244870Y491226D02*
X-1244806Y490778D01*
G01X-1244702Y498343D02*
X-1243817Y492238D01*
G01Y492043D02*
X-1244702Y498149D01*
G01X-1244899Y498096D02*
X-1244014Y491990D01*
G01X-1244998Y492238D02*
X-1245883Y498343D01*
G01Y498149D02*
X-1244998Y492043D01*
G01X-1245195Y491990D02*
X-1246082Y498111D01*
G01X-1243689Y491226D02*
X-1243817Y492043D01*
G01X-1243888Y491226D02*
X-1244016Y492004D01*
G01X-1245197D02*
X-1245069Y491226D01*
G01X-1260330Y478312D02*
X-1260136Y477215D01*
G01X-1258182Y486106D02*
X-1258151Y485951D01*
G01X-1258150Y486144D02*
X-1258163Y486200D01*
G01X-1258100Y485913D02*
X-1258136Y486038D01*
G01X-1246837Y474854D02*
X-1246481Y473684D01*
G01X-1241218Y474416D02*
X-1241109Y474124D01*
G01X-1258033Y485765D02*
X-1258102Y485917D01*
G01X-1258190Y486250D02*
X-1258221Y486307D01*
G01X-1248153Y474472D02*
X-1246789Y472110D01*
G01X-1258135Y485791D02*
X-1257993Y485570D01*
G01X-1237510Y478376D02*
X-1237483Y478337D01*
G01D02*
X-1237510Y478377D01*
G01X-1257934Y485622D02*
X-1258035Y485768D01*
G01X-1237587Y478488D02*
X-1237510Y478376D01*
G01Y478377D02*
X-1237589Y478490D01*
G01X-1237888Y489840D02*
X-1237284Y488977D01*
G01X-1238856Y489162D02*
X-1238252Y488300D01*
G01X-1238764Y482294D02*
X-1235976Y478312D01*
G01X-1238796Y482271D02*
X-1237238Y480046D01*
G01X-1238828Y482249D02*
X-1237338Y480120D01*
G01X-1239731Y481617D02*
X-1236491Y476990D01*
G01X-1239764Y481594D02*
X-1237588Y478488D01*
G01X-1239796Y481571D02*
X-1237583Y478411D01*
G01X-1249474Y491851D02*
X-1248968Y491248D01*
G01X-1249162Y489029D02*
X-1248153Y487826D01*
G01X-1249765Y488523D02*
X-1248191Y486647D01*
G01X-1248186Y486640D02*
X-1248177Y486631D01*
G01X-1248164Y486615D02*
X-1248172Y486624D01*
G01X-1248161Y486613D02*
X-1248172Y486624D01*
G01X-1248158Y486609D02*
X-1248164Y486615D01*
G01X-1248161Y486613D02*
X-1248153Y486603D01*
G01X-1237583Y478411D02*
X-1237539Y478366D01*
G01X-1237583Y478411D02*
X-1237539Y478366D01*
G01X-1237024Y493524D02*
X-1236746Y493246D01*
G01X-1237660Y492889D02*
X-1236825Y492054D01*
G01X-1238613Y491936D02*
X-1237778Y491100D01*
G01X-1238418Y485572D02*
X-1237527Y484681D01*
G01X-1238292Y484028D02*
X-1238236Y483972D01*
G01X-1239544Y484445D02*
X-1238654Y483555D01*
G01X-1247562Y481362D02*
X-1248153Y481952D01*
G01X-1238074Y471795D02*
X-1237483Y471204D01*
G01X-1257887Y485572D02*
X-1256761Y484445D01*
G01X-1257915Y485544D02*
X-1256789Y484418D01*
G01X-1257943Y485516D02*
X-1256817Y484390D01*
G01X-1258320Y484334D02*
X-1257596Y483610D01*
G01X-1258431Y484390D02*
X-1257624Y483582D01*
G01X-1258778Y484681D02*
X-1257652Y483555D01*
G01X-1253349Y478078D02*
X-1252412Y477141D01*
G01X-1253404Y478022D02*
X-1252468Y477086D01*
G01X-1238372Y485622D02*
X-1238312Y485570D01*
G01X-1243820Y490751D02*
X-1243625Y490778D01*
G01X-1243657Y483130D02*
X-1245884Y482533D01*
G01X-1243454Y482369D02*
X-1245680Y481772D01*
G01X-1244998Y492043D02*
X-1245195Y491990D01*
G01X-1244014D02*
X-1243817Y492043D01*
G01X-1257541Y482294D02*
X-1256509Y481571D01*
G01X-1258783Y480520D02*
X-1258719Y480475D01*
G01X-1258493Y478875D02*
X-1258429Y478830D01*
G01X-1260275Y478390D02*
X-1259308Y477712D01*
G01X-1260136Y477215D02*
X-1259814Y476990D01*
G01X-1251450Y471795D02*
X-1250965Y471458D01*
G01X-1250126Y492043D02*
X-1249929Y491990D01*
G01X-1251111D02*
X-1251307Y492043D01*
G01X-1251304Y490751D02*
X-1251499Y490778D01*
G01X-1242483Y475519D02*
X-1242345Y475509D01*
G01X-1250122Y490773D02*
X-1250317Y490778D01*
G01X-1236893Y493435D02*
X-1238074D01*
G01X-1251307Y492238D02*
X-1243817D01*
G01X-1251108Y492004D02*
X-1244016D01*
G01X-1251236Y491226D02*
X-1251435D01*
G01D02*
X-1243689D01*
G01X-1243888D02*
X-1243689D01*
G01X-1242286Y489432D02*
X-1240909D01*
G01X-1236893Y487735D02*
X-1238074D01*
G01X-1258231Y486212D02*
X-1259412D01*
G01X-1236893D02*
X-1238074D01*
G01X-1254491Y486165D02*
X-1254885D01*
G01X-1251145D02*
X-1254412D01*
G01X-1245003Y484539D02*
X-1247050D01*
G01X-1246184Y484314D02*
X-1246972D01*
G01X-1251460Y484196D02*
X-1251145D01*
G01X-1254885D02*
X-1251538D01*
G01X-1244216Y483133D02*
X-1247050D01*
G01X-1244216Y482149D02*
X-1247050D01*
G01Y481362D02*
X-1247562D01*
G01X-1236893Y479816D02*
X-1238074D01*
G01X-1236893Y479679D02*
X-1238074D01*
G01Y478960D02*
X-1236893D01*
G01X-1251538Y478684D02*
X-1254885D01*
G01X-1251145D02*
X-1251460D01*
G01X-1254412Y476716D02*
X-1251145D01*
G01X-1254885D02*
X-1254491D01*
G01X-1258231Y476173D02*
X-1259412D01*
G01X-1236893D02*
X-1238074D01*
G01X-1242483Y475519D02*
X-1248153D01*
G01X-1246932Y473291D02*
X-1244688D01*
G01X-1258231Y473173D02*
X-1259412D01*
G01X-1236893D02*
X-1238074D01*
G01X-1249607Y472188D02*
X-1246698D01*
G01X-1242272Y472110D02*
X-1246789D01*
G01X-1258231Y471795D02*
X-1238074D01*
G01X-1246509Y471598D02*
X-1249796D01*
G01X-1236893Y471204D02*
X-1259412D01*
G01X-1245002Y490773D02*
X-1244807Y490778D01*
G01X-1246851Y475240D02*
X-1246263Y475260D01*
G01Y474988D02*
X-1246841Y474968D01*
G01X-1246151Y473813D02*
X-1246263Y473809D01*
G01X-1246206Y473694D02*
X-1246481Y473684D01*
G01X-1245263Y501242D02*
X-1245210Y500995D01*
G01X-1245343Y501459D02*
X-1245263Y501242D01*
G01X-1245443Y501645D02*
X-1245343Y501459D01*
G01X-1245556Y501795D02*
X-1245443Y501645D01*
G01X-1245676Y501912D02*
X-1245556Y501795D01*
G01X-1245800Y501998D02*
X-1245676Y501912D01*
G01X-1245924Y502057D02*
X-1245800Y501998D01*
G01X-1246049Y502091D02*
X-1245924Y502057D01*
G01X-1246174Y502102D02*
X-1246049Y502091D01*
G01X-1250355Y498126D02*
X-1250422Y498149D01*
G01X-1250289Y498108D02*
X-1250355Y498126D01*
G01X-1250225Y498096D02*
X-1250289Y498108D01*
G01X-1246021Y498122D02*
X-1246091Y498109D01*
G01X-1245883Y498149D02*
X-1246021Y498122D01*
G01X-1244769Y498126D02*
X-1244702Y498149D01*
G01X-1244835Y498108D02*
X-1244769Y498126D01*
G01X-1244899Y498096D02*
X-1244835Y498108D01*
G01X-1249861Y501242D02*
X-1249914Y500995D01*
G01X-1249781Y501459D02*
X-1249861Y501242D01*
G01X-1249681Y501645D02*
X-1249781Y501459D01*
G01X-1249568Y501795D02*
X-1249681Y501645D01*
G01X-1249448Y501912D02*
X-1249568Y501795D01*
G01X-1249325Y501998D02*
X-1249448Y501912D01*
G01X-1249200Y502057D02*
X-1249325Y501998D01*
G01X-1249075Y502091D02*
X-1249200Y502057D01*
G01X-1248950Y502102D02*
X-1249075Y502091D01*
G01X-1248412Y502161D02*
X-1248512Y502083D01*
G01X-1248299Y502226D02*
X-1248412Y502161D01*
G01X-1248175Y502279D02*
X-1248299Y502226D01*
G01X-1248043Y502317D02*
X-1248175Y502279D01*
G01X-1247906Y502340D02*
X-1248043Y502317D01*
G01X-1247769Y502348D02*
X-1247906Y502340D01*
G01X-1239308Y527077D02*
X-1239420Y527007D01*
G01X-1239190Y527134D02*
X-1239308Y527077D01*
G01X-1239065Y527180D02*
X-1239190Y527134D01*
G01X-1238934Y527212D02*
X-1239065Y527180D01*
G01X-1238800Y527232D02*
X-1238934Y527212D01*
G01X-1238664Y527239D02*
X-1238800Y527232D01*
G01X-1256998Y527703D02*
X-1256885Y527633D01*
G01X-1257116Y527760D02*
X-1256998Y527703D01*
G01X-1257241Y527805D02*
X-1257116Y527760D01*
G01X-1257371Y527838D02*
X-1257241Y527805D01*
G01X-1257505Y527858D02*
X-1257371Y527838D01*
G01X-1257641Y527865D02*
X-1257505Y527858D01*
G01X-1236708Y536224D02*
X-1236696Y536162D01*
G01X-1236741Y536283D02*
X-1236708Y536224D01*
G01X-1236796Y536336D02*
X-1236741Y536283D01*
G01X-1236869Y536384D02*
X-1236796Y536336D01*
G01X-1236960Y536423D02*
X-1236869Y536384D01*
G01X-1237061Y536452D02*
X-1236960Y536423D01*
G01X-1237172Y536469D02*
X-1237061Y536452D01*
G01X-1237286Y536475D02*
X-1237172Y536469D01*
G01X-1246712Y502161D02*
X-1246612Y502083D01*
G01X-1246825Y502226D02*
X-1246712Y502161D01*
G01X-1246949Y502279D02*
X-1246825Y502226D01*
G01X-1247081Y502317D02*
X-1246949Y502279D01*
G01X-1247218Y502340D02*
X-1247081Y502317D01*
G01X-1247355Y502348D02*
X-1247218Y502340D01*
G01X-1259393Y527908D02*
X-1259412Y528073D01*
G01X-1259337Y527753D02*
X-1259393Y527908D01*
G01X-1259246Y527609D02*
X-1259337Y527753D01*
G01X-1259124Y527483D02*
X-1259246Y527609D01*
G01X-1258973Y527378D02*
X-1259124Y527483D01*
G01X-1258803Y527302D02*
X-1258973Y527378D01*
G01X-1258619Y527255D02*
X-1258803Y527302D01*
G01X-1258428Y527239D02*
X-1258619Y527255D01*
G01X-1244239Y528396D02*
X-1244216Y528198D01*
G01X-1244306Y528583D02*
X-1244239Y528396D01*
G01X-1244415Y528756D02*
X-1244306Y528583D01*
G01X-1244562Y528907D02*
X-1244415Y528756D01*
G01X-1244743Y529033D02*
X-1244562Y528907D01*
G01X-1244947Y529125D02*
X-1244743Y529033D01*
G01X-1245167Y529181D02*
X-1244947Y529125D01*
G01X-1245397Y529200D02*
X-1245167Y529181D01*
G01X-1249989Y541584D02*
X-1250008Y541746D01*
G01X-1249934Y541431D02*
X-1249989Y541584D01*
G01X-1249844Y541290D02*
X-1249934Y541431D01*
G01X-1249724Y541166D02*
X-1249844Y541290D01*
G01X-1249576Y541062D02*
X-1249724Y541166D01*
G01X-1249409Y540987D02*
X-1249576Y541062D01*
G01X-1249228Y540941D02*
X-1249409Y540987D01*
G01X-1249040Y540925D02*
X-1249228Y540941D01*
G01X-1249155Y541923D02*
X-1249158Y541943D01*
G01X-1249149Y541904D02*
X-1249155Y541923D01*
G01X-1249138Y541887D02*
X-1249149Y541904D01*
G01X-1249123Y541872D02*
X-1249138Y541887D01*
G01X-1249105Y541859D02*
X-1249123Y541872D01*
G01X-1249085Y541850D02*
X-1249105Y541859D01*
G01X-1249063Y541844D02*
X-1249085Y541850D01*
G01X-1249040Y541842D02*
X-1249063Y541844D01*
G01X-1247034Y543044D02*
X-1247032Y543024D01*
G01X-1247041Y543063D02*
X-1247034Y543044D01*
G01X-1247052Y543080D02*
X-1247041Y543063D01*
G01X-1247066Y543095D02*
X-1247052Y543080D01*
G01X-1247084Y543108D02*
X-1247066Y543095D01*
G01X-1247105Y543117D02*
X-1247084Y543108D01*
G01X-1247127Y543123D02*
X-1247105Y543117D01*
G01X-1247150Y543125D02*
X-1247127Y543123D01*
G01X-1246200Y543591D02*
X-1246181Y543429D01*
G01X-1246256Y543745D02*
X-1246200Y543591D01*
G01X-1246345Y543886D02*
X-1246256Y543745D01*
G01X-1246465Y544010D02*
X-1246345Y543886D01*
G01X-1246614Y544113D02*
X-1246465Y544010D01*
G01X-1246781Y544189D02*
X-1246614Y544113D01*
G01X-1246962Y544235D02*
X-1246781Y544189D01*
G01X-1247150Y544250D02*
X-1246962Y544235D01*
G01X-1258331Y535470D02*
X-1258728Y535401D01*
G01X-1258148Y535536D02*
X-1258331Y535470D01*
G01X-1257985Y535633D02*
X-1258148Y535536D01*
G01X-1257845Y535757D02*
X-1257985Y535633D01*
G01X-1257740Y535901D02*
X-1257845Y535757D01*
G01X-1257672Y536059D02*
X-1257740Y535901D01*
G01X-1257642Y536226D02*
X-1257672Y536059D01*
G01X-1257652Y536394D02*
X-1257642Y536226D01*
G01X-1257703Y536557D02*
X-1257652Y536394D01*
G01X-1257790Y536709D02*
X-1257703Y536557D01*
G01X-1257912Y536842D02*
X-1257790Y536709D01*
G01X-1258063Y536952D02*
X-1257912Y536842D01*
G01X-1258237Y537034D02*
X-1258063Y536952D01*
G01X-1258427Y537084D02*
X-1258237Y537034D01*
G01X-1258625Y537101D02*
X-1258427Y537084D01*
G01X-1236915Y534154D02*
X-1236893Y533980D01*
G01X-1236980Y534323D02*
X-1236915Y534154D01*
G01X-1237083Y534473D02*
X-1236980Y534323D01*
G01X-1237222Y534602D02*
X-1237083Y534473D01*
G01X-1237389Y534704D02*
X-1237222Y534602D01*
G01X-1237577Y534775D02*
X-1237389Y534704D01*
G01X-1237975Y534844D02*
X-1237577Y534775D01*
G01X-1237879Y537084D02*
X-1237680Y537101D01*
G01X-1238069Y537033D02*
X-1237879Y537084D01*
G01X-1238243Y536951D02*
X-1238069Y537033D01*
G01X-1238396Y536839D02*
X-1238243Y536951D01*
G01X-1238517Y536706D02*
X-1238396Y536839D01*
G01X-1238604Y536554D02*
X-1238517Y536706D01*
G01X-1238654Y536390D02*
X-1238604Y536554D01*
G01X-1238663Y536222D02*
X-1238654Y536390D01*
G01X-1238632Y536055D02*
X-1238663Y536222D01*
G01X-1238563Y535897D02*
X-1238632Y536055D01*
G01X-1238457Y535754D02*
X-1238563Y535897D01*
G01X-1238320Y535632D02*
X-1238457Y535754D01*
G01X-1238156Y535536D02*
X-1238320Y535632D01*
G01X-1237974Y535470D02*
X-1238156Y535536D01*
G01X-1239607Y527451D02*
X-1239420Y527633D01*
G01X-1239746Y527270D02*
X-1239607Y527451D01*
G01X-1239841Y527094D02*
X-1239746Y527270D01*
G01X-1239898Y526924D02*
X-1239841Y527094D01*
G01X-1239922Y526757D02*
X-1239898Y526924D01*
G01X-1239916Y526587D02*
X-1239922Y526757D01*
G01X-1239883Y526420D02*
X-1239916Y526587D01*
G01X-1239831Y526272D02*
X-1239883Y526420D01*
G01X-1239771Y526145D02*
X-1239831Y526272D01*
G01X-1239709Y526036D02*
X-1239771Y526145D01*
G01X-1239652Y525950D02*
X-1239709Y526036D01*
G01X-1239582Y525858D02*
X-1239652Y525950D01*
G01X-1239505Y525782D02*
X-1239582Y525858D01*
G01X-1239409Y525706D02*
X-1239505Y525782D01*
G01X-1239295Y525632D02*
X-1239409Y525706D01*
G01X-1239165Y525558D02*
X-1239295Y525632D01*
G01X-1239017Y525485D02*
X-1239165Y525558D01*
G01X-1238850Y525411D02*
X-1239017Y525485D01*
G01X-1238664Y525338D02*
X-1238850Y525411D01*
G01X-1257502Y527232D02*
X-1257641Y527239D01*
G01X-1257368Y527212D02*
X-1257502Y527232D01*
G01X-1257237Y527178D02*
X-1257368Y527212D01*
G01X-1257112Y527133D02*
X-1257237Y527178D01*
G01X-1256995Y527076D02*
X-1257112Y527133D01*
G01X-1256885Y527007D02*
X-1256995Y527076D01*
G01X-1246052Y502342D02*
X-1246174Y502348D01*
G01X-1245930Y502323D02*
X-1246052Y502342D01*
G01X-1245816Y502295D02*
X-1245930Y502323D01*
G01X-1245704Y502254D02*
X-1245816Y502295D01*
G01X-1245602Y502204D02*
X-1245704Y502254D01*
G01X-1245509Y502145D02*
X-1245602Y502204D01*
G01X-1250225Y498101D02*
X-1250224Y498105D01*
G01X-1250227Y498103D02*
X-1250225Y498101D01*
G01X-1258426Y536458D02*
X-1258625Y536475D01*
G01X-1258236Y536407D02*
X-1258426Y536458D01*
G01X-1258062Y536326D02*
X-1258236Y536407D01*
G01X-1257909Y536214D02*
X-1258062Y536326D01*
G01X-1257788Y536080D02*
X-1257909Y536214D01*
G01X-1257701Y535928D02*
X-1257788Y536080D01*
G01X-1257652Y535765D02*
X-1257701Y535928D01*
G01X-1257642Y535596D02*
X-1257652Y535765D01*
G01X-1257673Y535429D02*
X-1257642Y535596D01*
G01X-1257742Y535271D02*
X-1257673Y535429D01*
G01X-1257848Y535128D02*
X-1257742Y535271D01*
G01X-1257985Y535006D02*
X-1257848Y535128D01*
G01X-1258149Y534910D02*
X-1257985Y535006D01*
G01X-1258332Y534844D02*
X-1258149Y534910D01*
G01X-1258729Y534774D02*
X-1258332Y534844D01*
G01X-1238157Y534911D02*
X-1237975Y534844D01*
G01X-1238321Y535007D02*
X-1238157Y534911D01*
G01X-1238460Y535131D02*
X-1238321Y535007D01*
G01X-1238565Y535275D02*
X-1238460Y535131D01*
G01X-1238634Y535433D02*
X-1238565Y535275D01*
G01X-1238663Y535600D02*
X-1238634Y535433D01*
G01X-1238653Y535768D02*
X-1238663Y535600D01*
G01X-1238603Y535932D02*
X-1238653Y535768D01*
G01X-1238515Y536083D02*
X-1238603Y535932D01*
G01X-1238393Y536216D02*
X-1238515Y536083D01*
G01X-1238242Y536326D02*
X-1238393Y536216D01*
G01X-1238068Y536408D02*
X-1238242Y536326D01*
G01X-1237878Y536458D02*
X-1238068Y536408D01*
G01X-1237680Y536475D02*
X-1237878Y536458D01*
G01X-1236912Y528534D02*
X-1236893Y528699D01*
G01X-1236968Y528379D02*
X-1236912Y528534D01*
G01X-1237059Y528235D02*
X-1236968Y528379D01*
G01X-1237181Y528109D02*
X-1237059Y528235D01*
G01X-1237332Y528004D02*
X-1237181Y528109D01*
G01X-1237502Y527928D02*
X-1237332Y528004D01*
G01X-1237686Y527881D02*
X-1237502Y527928D01*
G01X-1237877Y527865D02*
X-1237686Y527881D01*
G01X-1252066Y527771D02*
X-1252090Y527573D01*
G01X-1251999Y527958D02*
X-1252066Y527771D01*
G01X-1251890Y528130D02*
X-1251999Y527958D01*
G01X-1251744Y528281D02*
X-1251890Y528130D01*
G01X-1251562Y528407D02*
X-1251744Y528281D01*
G01X-1251359Y528499D02*
X-1251562Y528407D01*
G01X-1251138Y528555D02*
X-1251359Y528499D01*
G01X-1250909Y528574D02*
X-1251138Y528555D01*
G01X-1247819Y541480D02*
X-1247799Y541642D01*
G01X-1247874Y541326D02*
X-1247819Y541480D01*
G01X-1247963Y541185D02*
X-1247874Y541326D01*
G01X-1248083Y541061D02*
X-1247963Y541185D01*
G01X-1248232Y540958D02*
X-1248083Y541061D01*
G01X-1248399Y540883D02*
X-1248232Y540958D01*
G01X-1248580Y540836D02*
X-1248399Y540883D01*
G01X-1248768Y540821D02*
X-1248580Y540836D01*
G01X-1248392Y542027D02*
X-1248390Y542047D01*
G01X-1248399Y542008D02*
X-1248392Y542027D01*
G01X-1248410Y541991D02*
X-1248399Y542008D01*
G01X-1248425Y541976D02*
X-1248410Y541991D01*
G01X-1248443Y541963D02*
X-1248425Y541976D01*
G01X-1248463Y541954D02*
X-1248443Y541963D01*
G01X-1248485Y541949D02*
X-1248463Y541954D01*
G01X-1248508Y541947D02*
X-1248485Y541949D01*
G01X-1247797Y543148D02*
X-1247799Y543129D01*
G01X-1247790Y543167D02*
X-1247797Y543148D01*
G01X-1247779Y543184D02*
X-1247790Y543167D01*
G01X-1247765Y543199D02*
X-1247779Y543184D01*
G01X-1247747Y543212D02*
X-1247765Y543199D01*
G01X-1247726Y543221D02*
X-1247747Y543212D01*
G01X-1247704Y543227D02*
X-1247726Y543221D01*
G01X-1247681Y543229D02*
X-1247704Y543227D01*
G01X-1248371Y543487D02*
X-1248390Y543325D01*
G01X-1248316Y543640D02*
X-1248371Y543487D01*
G01X-1248226Y543782D02*
X-1248316Y543640D01*
G01X-1248106Y543906D02*
X-1248226Y543782D01*
G01X-1247957Y544009D02*
X-1248106Y543906D01*
G01X-1247791Y544084D02*
X-1247957Y544009D01*
G01X-1247610Y544131D02*
X-1247791Y544084D01*
G01X-1247421Y544146D02*
X-1247610Y544131D01*
G01X-1247797Y547335D02*
X-1247799Y547315D01*
G01X-1247790Y547354D02*
X-1247797Y547335D01*
G01X-1247779Y547371D02*
X-1247790Y547354D01*
G01X-1247765Y547386D02*
X-1247779Y547371D01*
G01X-1247747Y547399D02*
X-1247765Y547386D01*
G01X-1247726Y547408D02*
X-1247747Y547399D01*
G01X-1247704Y547414D02*
X-1247726Y547408D01*
G01X-1247681Y547416D02*
X-1247704Y547414D01*
G01X-1249155Y547335D02*
X-1249158Y547315D01*
G01X-1249149Y547354D02*
X-1249155Y547335D01*
G01X-1249138Y547371D02*
X-1249149Y547354D01*
G01X-1249123Y547386D02*
X-1249138Y547371D01*
G01X-1249105Y547399D02*
X-1249123Y547386D01*
G01X-1249085Y547408D02*
X-1249105Y547399D01*
G01X-1249063Y547414D02*
X-1249085Y547408D01*
G01X-1249040Y547416D02*
X-1249063Y547414D01*
G01X-1249989Y547674D02*
X-1250008Y547512D01*
G01X-1249934Y547827D02*
X-1249989Y547674D01*
G01X-1249844Y547969D02*
X-1249934Y547827D01*
G01X-1249724Y548092D02*
X-1249844Y547969D01*
G01X-1249576Y548196D02*
X-1249724Y548092D01*
G01X-1249409Y548271D02*
X-1249576Y548196D01*
G01X-1249228Y548317D02*
X-1249409Y548271D01*
G01X-1249040Y548333D02*
X-1249228Y548317D01*
G01X-1247034Y551533D02*
X-1247032Y551552D01*
G01X-1247041Y551514D02*
X-1247034Y551533D01*
G01X-1247052Y551497D02*
X-1247041Y551514D01*
G01X-1247066Y551482D02*
X-1247052Y551497D01*
G01X-1247084Y551469D02*
X-1247066Y551482D01*
G01X-1247105Y551460D02*
X-1247084Y551469D01*
G01X-1247127Y551454D02*
X-1247105Y551460D01*
G01X-1247150Y551452D02*
X-1247127Y551454D01*
G01X-1246200Y554000D02*
X-1246181Y554162D01*
G01X-1246256Y553847D02*
X-1246200Y554000D01*
G01X-1246345Y553706D02*
X-1246256Y553847D01*
G01X-1246465Y553582D02*
X-1246345Y553706D01*
G01X-1246614Y553478D02*
X-1246465Y553582D01*
G01X-1246781Y553403D02*
X-1246614Y553478D01*
G01X-1246962Y553357D02*
X-1246781Y553403D01*
G01X-1247150Y553341D02*
X-1246962Y553357D01*
G01X-1247388Y554547D02*
X-1247386Y554567D01*
G01X-1247395Y554529D02*
X-1247388Y554547D01*
G01X-1247406Y554512D02*
X-1247395Y554529D01*
G01X-1247421Y554496D02*
X-1247406Y554512D01*
G01X-1247439Y554484D02*
X-1247421Y554496D01*
G01X-1247459Y554475D02*
X-1247439Y554484D01*
G01X-1247481Y554469D02*
X-1247459Y554475D01*
G01X-1247504Y554467D02*
X-1247481Y554469D01*
G01X-1248801Y555709D02*
X-1248803Y555689D01*
G01X-1248794Y555728D02*
X-1248801Y555709D01*
G01X-1248783Y555745D02*
X-1248794Y555728D01*
G01X-1248769Y555760D02*
X-1248783Y555745D01*
G01X-1248751Y555773D02*
X-1248769Y555760D01*
G01X-1248730Y555782D02*
X-1248751Y555773D01*
G01X-1248708Y555787D02*
X-1248730Y555782D01*
G01X-1248685Y555789D02*
X-1248708Y555787D01*
G01X-1249989Y556048D02*
X-1250008Y555885D01*
G01X-1249934Y556201D02*
X-1249989Y556048D01*
G01X-1249844Y556342D02*
X-1249934Y556201D01*
G01X-1249724Y556466D02*
X-1249844Y556342D01*
G01X-1249576Y556569D02*
X-1249724Y556466D01*
G01X-1249409Y556645D02*
X-1249576Y556569D01*
G01X-1249228Y556691D02*
X-1249409Y556645D01*
G01X-1249040Y556707D02*
X-1249228Y556691D01*
G01X-1249999Y560532D02*
X-1250008Y560453D01*
G01X-1249972Y560607D02*
X-1249999Y560532D01*
G01X-1249928Y560676D02*
X-1249972Y560607D01*
G01X-1249870Y560736D02*
X-1249928Y560676D01*
G01X-1249797Y560786D02*
X-1249870Y560736D01*
G01X-1249716Y560823D02*
X-1249797Y560786D01*
G01X-1249627Y560846D02*
X-1249716Y560823D01*
G01X-1249536Y560853D02*
X-1249627Y560846D01*
G01X-1260755Y536348D02*
X-1260790Y536162D01*
G01X-1260654Y536523D02*
X-1260755Y536348D01*
G01X-1260491Y536685D02*
X-1260654Y536523D01*
G01X-1260272Y536826D02*
X-1260491Y536685D01*
G01X-1259999Y536944D02*
X-1260272Y536826D01*
G01X-1259694Y537030D02*
X-1259999Y536944D01*
G01X-1259363Y537083D02*
X-1259694Y537030D01*
G01X-1259019Y537101D02*
X-1259363Y537083D01*
G01X-1249503Y560957D02*
X-1249494Y560956D01*
G01X-1249509Y560957D02*
X-1249503D01*
G01X-1249516D02*
X-1249509D01*
G01X-1249522Y560958D02*
X-1249516Y560957D01*
G01X-1249529Y560958D02*
X-1249522D01*
G01X-1249536D02*
X-1249529D01*
G01X-1249527Y560853D02*
X-1249536D01*
G01X-1249521D02*
X-1249527D01*
G01X-1249514D02*
X-1249521D01*
G01X-1249508D02*
X-1249514D01*
G01X-1249501Y560852D02*
X-1249508Y560853D01*
G01X-1249494Y560852D02*
X-1249501D01*
G01X-1248392Y547231D02*
X-1248390Y547211D01*
G01X-1248399Y547250D02*
X-1248392Y547231D01*
G01X-1248410Y547267D02*
X-1248399Y547250D01*
G01X-1248425Y547282D02*
X-1248410Y547267D01*
G01X-1248443Y547295D02*
X-1248425Y547282D01*
G01X-1248463Y547304D02*
X-1248443Y547295D01*
G01X-1248485Y547309D02*
X-1248463Y547304D01*
G01X-1248508Y547311D02*
X-1248485Y547309D01*
G01X-1247034Y547231D02*
X-1247032Y547211D01*
G01X-1247041Y547250D02*
X-1247034Y547231D01*
G01X-1247052Y547267D02*
X-1247041Y547250D01*
G01X-1247066Y547282D02*
X-1247052Y547267D01*
G01X-1247084Y547295D02*
X-1247066Y547282D01*
G01X-1247105Y547304D02*
X-1247084Y547295D01*
G01X-1247127Y547309D02*
X-1247105Y547304D01*
G01X-1247150Y547311D02*
X-1247127Y547309D01*
G01X-1246200Y547778D02*
X-1246181Y547616D01*
G01X-1246256Y547932D02*
X-1246200Y547778D01*
G01X-1246345Y548073D02*
X-1246256Y547932D01*
G01X-1246465Y548197D02*
X-1246345Y548073D01*
G01X-1246614Y548300D02*
X-1246465Y548197D01*
G01X-1246781Y548375D02*
X-1246614Y548300D01*
G01X-1246962Y548422D02*
X-1246781Y548375D01*
G01X-1247150Y548437D02*
X-1246962Y548422D01*
G01X-1247034Y550246D02*
X-1247032Y550226D01*
G01X-1247041Y550265D02*
X-1247034Y550246D01*
G01X-1247052Y550282D02*
X-1247041Y550265D01*
G01X-1247066Y550297D02*
X-1247052Y550282D01*
G01X-1247084Y550310D02*
X-1247066Y550297D01*
G01X-1247105Y550319D02*
X-1247084Y550310D01*
G01X-1247127Y550324D02*
X-1247105Y550319D01*
G01X-1247150Y550326D02*
X-1247127Y550324D01*
G01X-1249989Y554104D02*
X-1250008Y554267D01*
G01X-1249934Y553951D02*
X-1249989Y554104D01*
G01X-1249844Y553810D02*
X-1249934Y553951D01*
G01X-1249724Y553686D02*
X-1249844Y553810D01*
G01X-1249576Y553583D02*
X-1249724Y553686D01*
G01X-1249409Y553507D02*
X-1249576Y553583D01*
G01X-1249228Y553461D02*
X-1249409Y553507D01*
G01X-1249040Y553445D02*
X-1249228Y553461D01*
G01X-1248801Y554443D02*
X-1248803Y554463D01*
G01X-1248794Y554424D02*
X-1248801Y554443D01*
G01X-1248783Y554407D02*
X-1248794Y554424D01*
G01X-1248769Y554392D02*
X-1248783Y554407D01*
G01X-1248751Y554380D02*
X-1248769Y554392D01*
G01X-1248730Y554370D02*
X-1248751Y554380D01*
G01X-1248708Y554365D02*
X-1248730Y554370D01*
G01X-1248685Y554363D02*
X-1248708Y554365D01*
G01X-1247388Y555605D02*
X-1247386Y555585D01*
G01X-1247395Y555623D02*
X-1247388Y555605D01*
G01X-1247406Y555641D02*
X-1247395Y555623D01*
G01X-1247421Y555656D02*
X-1247406Y555641D01*
G01X-1247439Y555668D02*
X-1247421Y555656D01*
G01X-1247459Y555677D02*
X-1247439Y555668D01*
G01X-1247481Y555683D02*
X-1247459Y555677D01*
G01X-1247504Y555685D02*
X-1247481Y555683D01*
G01X-1246200Y556152D02*
X-1246181Y555990D01*
G01X-1246256Y556305D02*
X-1246200Y556152D01*
G01X-1246345Y556447D02*
X-1246256Y556305D01*
G01X-1246465Y556570D02*
X-1246345Y556447D01*
G01X-1246614Y556674D02*
X-1246465Y556570D01*
G01X-1246781Y556749D02*
X-1246614Y556674D01*
G01X-1246962Y556795D02*
X-1246781Y556749D01*
G01X-1247150Y556811D02*
X-1246962Y556795D01*
G01X-1259961Y536444D02*
X-1260003Y536851D01*
G01X-1259830Y536074D02*
X-1259961Y536444D01*
G01X-1259609Y535767D02*
X-1259830Y536074D01*
G01X-1257415Y525350D02*
X-1257641Y525338D01*
G01X-1257213Y525376D02*
X-1257415Y525350D01*
G01X-1257034Y525416D02*
X-1257213Y525376D01*
G01X-1256879Y525471D02*
X-1257034Y525416D01*
G01X-1256751Y525538D02*
X-1256879Y525471D01*
G01X-1256651Y525616D02*
X-1256751Y525538D01*
G01X-1256576Y525703D02*
X-1256651Y525616D01*
G01X-1256523Y525800D02*
X-1256576Y525703D01*
G01X-1256489Y525908D02*
X-1256523Y525800D01*
G01X-1256476Y526030D02*
X-1256489Y525908D01*
G01X-1256485Y526167D02*
X-1256476Y526030D01*
G01X-1256518Y526316D02*
X-1256485Y526167D01*
G01X-1256574Y526476D02*
X-1256518Y526316D01*
G01X-1256653Y526646D02*
X-1256574Y526476D01*
G01X-1256757Y526823D02*
X-1256653Y526646D01*
G01X-1256885Y527007D02*
X-1256757Y526823D01*
G01X-1249142Y559847D02*
X-1249158Y559796D01*
G01X-1249099Y559883D02*
X-1249142Y559847D01*
G01X-1249038Y559897D02*
X-1249099Y559883D01*
G01X-1246427Y501732D02*
X-1246381Y501570D01*
G01X-1246506Y501904D02*
X-1246427Y501732D01*
G01X-1246612Y502083D02*
X-1246506Y501904D01*
G01X-1257398Y525357D02*
X-1257641Y525338D01*
G01X-1257184Y525397D02*
X-1257398Y525357D01*
G01X-1257000Y525459D02*
X-1257184Y525397D01*
G01X-1256851Y525538D02*
X-1257000Y525459D01*
G01X-1256732Y525631D02*
X-1256851Y525538D01*
G01X-1256638Y525739D02*
X-1256732Y525631D01*
G01X-1256565Y525864D02*
X-1256638Y525739D01*
G01X-1256513Y526009D02*
X-1256565Y525864D01*
G01X-1256483Y526178D02*
X-1256513Y526009D01*
G01X-1256478Y526372D02*
X-1256483Y526178D01*
G01X-1256500Y526588D02*
X-1256478Y526372D01*
G01X-1256551Y526823D02*
X-1256500Y526588D01*
G01X-1256631Y527077D02*
X-1256551Y526823D01*
G01X-1256742Y527347D02*
X-1256631Y527077D01*
G01X-1256885Y527633D02*
X-1256742Y527347D01*
G01X-1236345Y565395D02*
X-1236302Y564942D01*
G01X-1236475Y565903D02*
X-1236345Y565395D01*
G01X-1245397Y501985D02*
X-1245509Y502145D01*
G01X-1245310Y501834D02*
X-1245397Y501985D01*
G01X-1245240Y501677D02*
X-1245310Y501834D01*
G01X-1245200Y501538D02*
X-1245240Y501677D01*
G01X-1245201Y500958D02*
X-1245200Y500950D01*
G01X-1245203Y500966D02*
X-1245201Y500958D01*
G01X-1245205Y500974D02*
X-1245203Y500966D01*
G01X-1245207Y500982D02*
X-1245205Y500974D01*
G01X-1245209Y500990D02*
X-1245207Y500982D01*
G01X-1245210Y500995D02*
X-1245209Y500990D01*
G01X-1247231Y502091D02*
X-1247355Y502102D01*
G01X-1247106Y502057D02*
X-1247231Y502091D01*
G01X-1246981Y501998D02*
X-1247106Y502057D01*
G01X-1246857Y501912D02*
X-1246981Y501998D01*
G01X-1246737Y501795D02*
X-1246857Y501912D01*
G01X-1246624Y501645D02*
X-1246737Y501795D01*
G01X-1246524Y501459D02*
X-1246624Y501645D01*
G01X-1246444Y501242D02*
X-1246524Y501459D01*
G01X-1246391Y500995D02*
X-1246444Y501242D01*
G01X-1244808Y498913D02*
X-1244702Y498343D01*
G01X-1244914Y499467D02*
X-1244808Y498913D01*
G01X-1245020Y499960D02*
X-1244914Y499467D01*
G01X-1245269Y501036D02*
X-1245182Y500697D01*
G01X-1245351Y501384D02*
X-1245269Y501036D01*
G01X-1245428Y501747D02*
X-1245351Y501384D01*
G01X-1245323Y501238D02*
X-1245224Y500797D01*
G01X-1245417Y501686D02*
X-1245323Y501238D01*
G01X-1245509Y502145D02*
X-1245417Y501686D01*
G01X-1246389Y500987D02*
X-1246391Y500995D01*
G01X-1246387Y500979D02*
X-1246389Y500987D01*
G01X-1246385Y500971D02*
X-1246387Y500979D01*
G01X-1246384Y500963D02*
X-1246385Y500971D01*
G01X-1246382Y500955D02*
X-1246384Y500963D01*
G01X-1246381Y500950D02*
X-1246382Y500955D01*
G01X-1246095Y499467D02*
X-1246201Y499960D01*
G01X-1245989Y498913D02*
X-1246095Y499467D01*
G01X-1245883Y498343D02*
X-1245989Y498913D01*
G01X-1236936Y537083D02*
X-1237286Y537101D01*
G01X-1236606Y537029D02*
X-1236936Y537083D01*
G01X-1236301Y536943D02*
X-1236606Y537029D01*
G01X-1236034Y536826D02*
X-1236301Y536943D01*
G01X-1235811Y536682D02*
X-1236034Y536826D01*
G01X-1235649Y536520D02*
X-1235811Y536682D01*
G01X-1235549Y536345D02*
X-1235649Y536520D01*
G01X-1235515Y536162D02*
X-1235549Y536345D01*
G01X-1245963Y498794D02*
X-1245883Y498149D01*
G01X-1246042Y499421D02*
X-1245963Y498794D01*
G01X-1246121Y500027D02*
X-1246042Y499421D01*
G01X-1246201Y500574D02*
X-1246121Y500027D01*
G01X-1246335Y500240D02*
X-1246273Y499736D01*
G01X-1246399Y500697D02*
X-1246335Y500240D01*
G01X-1244977Y498765D02*
X-1244895Y498112D01*
G01X-1245060Y499473D02*
X-1244977Y498765D01*
G01X-1245142Y500141D02*
X-1245060Y499473D01*
G01X-1245216Y500693D02*
X-1245142Y500141D01*
G01X-1258623Y527881D02*
X-1258428Y527865D01*
G01X-1258806Y527929D02*
X-1258623Y527881D01*
G01X-1258976Y528006D02*
X-1258806Y527929D01*
G01X-1259124Y528109D02*
X-1258976Y528006D01*
G01X-1259248Y528237D02*
X-1259124Y528109D01*
G01X-1259338Y528381D02*
X-1259248Y528237D01*
G01X-1259394Y528537D02*
X-1259338Y528381D01*
G01X-1259412Y528699D02*
X-1259394Y528537D01*
G01X-1258407Y529091D02*
X-1258231Y528831D01*
G01X-1258530Y529342D02*
X-1258407Y529091D01*
G01X-1258601Y529576D02*
X-1258530Y529342D01*
G01X-1258625Y529786D02*
X-1258601Y529576D01*
G01X-1244947Y500076D02*
X-1245020Y500575D01*
G01X-1244870Y499496D02*
X-1244947Y500076D01*
G01X-1237576Y535400D02*
X-1237974Y535470D01*
G01X-1237385Y535328D02*
X-1237576Y535400D01*
G01X-1237218Y535226D02*
X-1237385Y535328D01*
G01X-1237081Y535096D02*
X-1237218Y535226D01*
G01X-1236978Y534945D02*
X-1237081Y535096D01*
G01X-1236914Y534779D02*
X-1236978Y534945D01*
G01X-1236893Y534606D02*
X-1236914Y534779D01*
G01X-1245142Y500141D02*
X-1245216Y500697D01*
G01X-1245060Y499473D02*
X-1245142Y500141D01*
G01X-1244977Y498765D02*
X-1245060Y499473D01*
G01X-1244897Y498103D02*
X-1244977Y498765D01*
G01X-1246145Y498655D02*
X-1246091Y498110D01*
G01X-1246273Y499736D02*
X-1246145Y498655D01*
G01X-1249231Y540837D02*
X-1249040Y540821D01*
G01X-1249412Y540884D02*
X-1249231Y540837D01*
G01X-1249578Y540960D02*
X-1249412Y540884D01*
G01X-1249724Y541061D02*
X-1249578Y540960D01*
G01X-1249846Y541188D02*
X-1249724Y541061D01*
G01X-1249935Y541329D02*
X-1249846Y541188D01*
G01X-1249990Y541483D02*
X-1249935Y541329D01*
G01X-1250008Y541642D02*
X-1249990Y541483D01*
G01X-1249063Y541949D02*
X-1249040Y541947D01*
G01X-1249085Y541954D02*
X-1249063Y541949D01*
G01X-1249105Y541964D02*
X-1249085Y541954D01*
G01X-1249123Y541976D02*
X-1249105Y541964D01*
G01X-1249138Y541991D02*
X-1249123Y541976D01*
G01X-1249149Y542009D02*
X-1249138Y541991D01*
G01X-1249155Y542027D02*
X-1249149Y542009D01*
G01X-1249158Y542047D02*
X-1249155Y542027D01*
G01X-1249231Y553357D02*
X-1249040Y553341D01*
G01X-1249412Y553404D02*
X-1249231Y553357D01*
G01X-1249578Y553480D02*
X-1249412Y553404D01*
G01X-1249724Y553582D02*
X-1249578Y553480D01*
G01X-1249846Y553708D02*
X-1249724Y553582D01*
G01X-1249935Y553850D02*
X-1249846Y553708D01*
G01X-1249990Y554003D02*
X-1249935Y553850D01*
G01X-1250008Y554162D02*
X-1249990Y554003D01*
G01X-1248485Y547414D02*
X-1248508Y547416D01*
G01X-1248463Y547408D02*
X-1248485Y547414D01*
G01X-1248442Y547399D02*
X-1248463Y547408D01*
G01X-1248425Y547386D02*
X-1248442Y547399D01*
G01X-1248410Y547371D02*
X-1248425Y547386D01*
G01X-1248399Y547354D02*
X-1248410Y547371D01*
G01X-1248392Y547335D02*
X-1248399Y547354D01*
G01X-1248390Y547315D02*
X-1248392Y547335D01*
G01X-1248709Y554469D02*
X-1248685Y554467D01*
G01X-1248731Y554475D02*
X-1248709Y554469D01*
G01X-1248751Y554484D02*
X-1248731Y554475D01*
G01X-1248769Y554496D02*
X-1248751Y554484D01*
G01X-1248784Y554512D02*
X-1248769Y554496D01*
G01X-1248794Y554529D02*
X-1248784Y554512D01*
G01X-1248801Y554548D02*
X-1248794Y554529D01*
G01X-1248803Y554567D02*
X-1248801Y554548D01*
G01X-1247126Y543227D02*
X-1247150Y543229D01*
G01X-1247104Y543221D02*
X-1247126Y543227D01*
G01X-1247084Y543212D02*
X-1247104Y543221D01*
G01X-1247066Y543199D02*
X-1247084Y543212D01*
G01X-1247051Y543184D02*
X-1247066Y543199D01*
G01X-1247041Y543167D02*
X-1247051Y543184D01*
G01X-1247034Y543148D02*
X-1247041Y543167D01*
G01X-1247032Y543129D02*
X-1247034Y543148D01*
G01X-1247126Y547414D02*
X-1247150Y547416D01*
G01X-1247104Y547408D02*
X-1247126Y547414D01*
G01X-1247084Y547399D02*
X-1247104Y547408D01*
G01X-1247066Y547386D02*
X-1247084Y547399D01*
G01X-1247051Y547371D02*
X-1247066Y547386D01*
G01X-1247041Y547354D02*
X-1247051Y547371D01*
G01X-1247034Y547335D02*
X-1247041Y547354D01*
G01X-1247032Y547315D02*
X-1247034Y547335D01*
G01X-1247126Y550429D02*
X-1247150Y550431D01*
G01X-1247104Y550423D02*
X-1247126Y550429D01*
G01X-1247084Y550414D02*
X-1247104Y550423D01*
G01X-1247066Y550401D02*
X-1247084Y550414D01*
G01X-1247051Y550386D02*
X-1247066Y550401D01*
G01X-1247041Y550369D02*
X-1247051Y550386D01*
G01X-1247034Y550350D02*
X-1247041Y550369D01*
G01X-1247032Y550330D02*
X-1247034Y550350D01*
G01X-1246958Y544130D02*
X-1247150Y544146D01*
G01X-1246778Y544083D02*
X-1246958Y544130D01*
G01X-1246611Y544007D02*
X-1246778Y544083D01*
G01X-1246465Y543906D02*
X-1246611Y544007D01*
G01X-1246343Y543779D02*
X-1246465Y543906D01*
G01X-1246254Y543638D02*
X-1246343Y543779D01*
G01X-1246200Y543484D02*
X-1246254Y543638D01*
G01X-1246181Y543325D02*
X-1246200Y543484D01*
G01X-1245163Y528554D02*
X-1245397Y528574D01*
G01X-1244943Y528497D02*
X-1245163Y528554D01*
G01X-1244740Y528405D02*
X-1244943Y528497D01*
G01X-1244562Y528281D02*
X-1244740Y528405D01*
G01X-1244413Y528127D02*
X-1244562Y528281D01*
G01X-1244305Y527954D02*
X-1244413Y528127D01*
G01X-1244238Y527767D02*
X-1244305Y527954D01*
G01X-1244216Y527573D02*
X-1244238Y527767D01*
G01X-1247481Y555787D02*
X-1247504Y555789D01*
G01X-1247459Y555782D02*
X-1247481Y555787D01*
G01X-1247438Y555772D02*
X-1247459Y555782D01*
G01X-1247421Y555760D02*
X-1247438Y555772D01*
G01X-1247406Y555745D02*
X-1247421Y555760D01*
G01X-1247395Y555727D02*
X-1247406Y555745D01*
G01X-1247388Y555709D02*
X-1247395Y555727D01*
G01X-1247386Y555689D02*
X-1247388Y555709D01*
G01X-1246958Y548317D02*
X-1247150Y548333D01*
G01X-1246778Y548270D02*
X-1246958Y548317D01*
G01X-1246611Y548194D02*
X-1246778Y548270D01*
G01X-1246465Y548092D02*
X-1246611Y548194D01*
G01X-1246343Y547966D02*
X-1246465Y548092D01*
G01X-1246254Y547825D02*
X-1246343Y547966D01*
G01X-1246200Y547671D02*
X-1246254Y547825D01*
G01X-1246181Y547512D02*
X-1246200Y547671D01*
G01X-1246958Y556690D02*
X-1247150Y556707D01*
G01X-1246778Y556644D02*
X-1246958Y556690D01*
G01X-1246611Y556568D02*
X-1246778Y556644D01*
G01X-1246465Y556466D02*
X-1246611Y556568D01*
G01X-1246343Y556340D02*
X-1246465Y556466D01*
G01X-1246254Y556198D02*
X-1246343Y556340D01*
G01X-1246200Y556045D02*
X-1246254Y556198D01*
G01X-1246181Y555885D02*
X-1246200Y556045D01*
G01X-1237068Y529091D02*
X-1236893Y528831D01*
G01X-1237191Y529342D02*
X-1237068Y529091D01*
G01X-1237263Y529576D02*
X-1237191Y529342D01*
G01X-1237286Y529786D02*
X-1237263Y529576D01*
G01X-1259961Y565396D02*
X-1259830Y565904D01*
G01X-1260003Y564942D02*
X-1259961Y565396D01*
G01X-1259239Y529088D02*
X-1259412Y528831D01*
G01X-1259116Y529337D02*
X-1259239Y529088D01*
G01X-1259043Y529573D02*
X-1259116Y529337D01*
G01X-1259019Y529786D02*
X-1259043Y529573D01*
G01X-1249629Y560950D02*
X-1249536Y560958D01*
G01X-1249717Y560927D02*
X-1249629Y560950D01*
G01X-1249798Y560890D02*
X-1249717Y560927D01*
G01X-1249870Y560840D02*
X-1249798Y560890D01*
G01X-1249929Y560779D02*
X-1249870Y560840D01*
G01X-1249972Y560710D02*
X-1249929Y560779D01*
G01X-1249999Y560635D02*
X-1249972Y560710D01*
G01X-1250008Y560557D02*
X-1249999Y560635D01*
G01X-1249231Y556795D02*
X-1249040Y556811D01*
G01X-1249412Y556748D02*
X-1249231Y556795D01*
G01X-1249578Y556672D02*
X-1249412Y556748D01*
G01X-1249724Y556570D02*
X-1249578Y556672D01*
G01X-1249846Y556444D02*
X-1249724Y556570D01*
G01X-1249935Y556303D02*
X-1249846Y556444D01*
G01X-1249990Y556149D02*
X-1249935Y556303D01*
G01X-1250008Y555990D02*
X-1249990Y556149D01*
G01X-1249231Y548421D02*
X-1249040Y548437D01*
G01X-1249412Y548374D02*
X-1249231Y548421D01*
G01X-1249578Y548298D02*
X-1249412Y548374D01*
G01X-1249724Y548197D02*
X-1249578Y548298D01*
G01X-1249846Y548070D02*
X-1249724Y548197D01*
G01X-1249935Y547929D02*
X-1249846Y548070D01*
G01X-1249990Y547776D02*
X-1249935Y547929D01*
G01X-1250008Y547616D02*
X-1249990Y547776D01*
G01X-1251142Y529180D02*
X-1250909Y529200D01*
G01X-1251362Y529123D02*
X-1251142Y529180D01*
G01X-1251566Y529031D02*
X-1251362Y529123D01*
G01X-1251744Y528907D02*
X-1251566Y529031D01*
G01X-1251892Y528753D02*
X-1251744Y528907D01*
G01X-1252001Y528580D02*
X-1251892Y528753D01*
G01X-1252067Y528393D02*
X-1252001Y528580D01*
G01X-1252090Y528198D02*
X-1252067Y528393D01*
G01X-1248709Y555683D02*
X-1248685Y555685D01*
G01X-1248731Y555677D02*
X-1248709Y555683D01*
G01X-1248751Y555668D02*
X-1248731Y555677D01*
G01X-1248769Y555656D02*
X-1248751Y555668D01*
G01X-1248784Y555640D02*
X-1248769Y555656D01*
G01X-1248794Y555623D02*
X-1248784Y555640D01*
G01X-1248801Y555604D02*
X-1248794Y555623D01*
G01X-1248803Y555585D02*
X-1248801Y555604D01*
G01X-1249063Y547309D02*
X-1249040Y547311D01*
G01X-1249085Y547304D02*
X-1249063Y547309D01*
G01X-1249105Y547294D02*
X-1249085Y547304D01*
G01X-1249123Y547282D02*
X-1249105Y547294D01*
G01X-1249138Y547267D02*
X-1249123Y547282D01*
G01X-1249149Y547249D02*
X-1249138Y547267D01*
G01X-1249155Y547231D02*
X-1249149Y547249D01*
G01X-1249158Y547211D02*
X-1249155Y547231D01*
G01X-1247481Y554365D02*
X-1247504Y554363D01*
G01X-1247459Y554371D02*
X-1247481Y554365D01*
G01X-1247438Y554380D02*
X-1247459Y554371D01*
G01X-1247421Y554392D02*
X-1247438Y554380D01*
G01X-1247406Y554408D02*
X-1247421Y554392D01*
G01X-1247395Y554425D02*
X-1247406Y554408D01*
G01X-1247388Y554444D02*
X-1247395Y554425D01*
G01X-1247386Y554463D02*
X-1247388Y554444D01*
G01X-1247613Y544234D02*
X-1247421Y544250D01*
G01X-1247794Y544187D02*
X-1247613Y544234D01*
G01X-1247960Y544112D02*
X-1247794Y544187D01*
G01X-1248106Y544010D02*
X-1247960Y544112D01*
G01X-1248228Y543884D02*
X-1248106Y544010D01*
G01X-1248317Y543742D02*
X-1248228Y543884D01*
G01X-1248372Y543589D02*
X-1248317Y543742D01*
G01X-1248390Y543429D02*
X-1248372Y543589D01*
G01X-1247705Y547309D02*
X-1247681Y547311D01*
G01X-1247727Y547304D02*
X-1247705Y547309D01*
G01X-1247747Y547294D02*
X-1247727Y547304D01*
G01X-1247765Y547282D02*
X-1247747Y547294D01*
G01X-1247780Y547267D02*
X-1247765Y547282D01*
G01X-1247790Y547249D02*
X-1247780Y547267D01*
G01X-1247797Y547231D02*
X-1247790Y547249D01*
G01X-1247799Y547211D02*
X-1247797Y547231D01*
G01X-1248485Y541844D02*
X-1248508Y541842D01*
G01X-1248463Y541850D02*
X-1248485Y541844D01*
G01X-1248442Y541859D02*
X-1248463Y541850D01*
G01X-1248425Y541872D02*
X-1248442Y541859D01*
G01X-1248410Y541887D02*
X-1248425Y541872D01*
G01X-1248399Y541904D02*
X-1248410Y541887D01*
G01X-1248392Y541923D02*
X-1248399Y541904D01*
G01X-1248390Y541943D02*
X-1248392Y541923D01*
G01X-1247126Y551350D02*
X-1247150Y551348D01*
G01X-1247104Y551356D02*
X-1247126Y551350D01*
G01X-1247084Y551365D02*
X-1247104Y551356D01*
G01X-1247066Y551377D02*
X-1247084Y551365D01*
G01X-1247051Y551393D02*
X-1247066Y551377D01*
G01X-1247041Y551410D02*
X-1247051Y551393D01*
G01X-1247034Y551429D02*
X-1247041Y551410D01*
G01X-1247032Y551448D02*
X-1247034Y551429D01*
G01X-1247705Y543123D02*
X-1247681Y543125D01*
G01X-1247727Y543117D02*
X-1247705Y543123D01*
G01X-1247747Y543108D02*
X-1247727Y543117D01*
G01X-1247765Y543095D02*
X-1247747Y543108D01*
G01X-1247780Y543080D02*
X-1247765Y543095D01*
G01X-1247790Y543063D02*
X-1247780Y543080D01*
G01X-1247797Y543044D02*
X-1247790Y543063D01*
G01X-1247799Y543024D02*
X-1247797Y543044D01*
G01X-1248576Y540941D02*
X-1248768Y540925D01*
G01X-1248396Y540988D02*
X-1248576Y540941D01*
G01X-1248229Y541064D02*
X-1248396Y540988D01*
G01X-1248083Y541166D02*
X-1248229Y541064D01*
G01X-1247961Y541292D02*
X-1248083Y541166D01*
G01X-1247872Y541433D02*
X-1247961Y541292D01*
G01X-1247818Y541587D02*
X-1247872Y541433D01*
G01X-1247799Y541746D02*
X-1247818Y541587D01*
G01X-1246958Y553462D02*
X-1247150Y553445D01*
G01X-1246778Y553509D02*
X-1246958Y553462D01*
G01X-1246611Y553584D02*
X-1246778Y553509D01*
G01X-1246465Y553686D02*
X-1246611Y553584D01*
G01X-1246343Y553812D02*
X-1246465Y553686D01*
G01X-1246254Y553954D02*
X-1246343Y553812D01*
G01X-1246200Y554107D02*
X-1246254Y553954D01*
G01X-1246181Y554267D02*
X-1246200Y554107D01*
G01X-1258920Y534702D02*
X-1258729Y534774D01*
G01X-1259087Y534600D02*
X-1258920Y534702D01*
G01X-1259224Y534470D02*
X-1259087Y534600D01*
G01X-1259327Y534319D02*
X-1259224Y534470D01*
G01X-1259391Y534153D02*
X-1259327Y534319D01*
G01X-1259412Y533980D02*
X-1259391Y534153D01*
G01X-1236475Y536073D02*
X-1236696Y535767D01*
G01X-1236345Y536443D02*
X-1236475Y536073D01*
G01X-1236302Y536851D02*
X-1236345Y536443D01*
G01X-1237900Y529088D02*
X-1238074Y528831D01*
G01X-1237777Y529337D02*
X-1237900Y529088D01*
G01X-1237705Y529573D02*
X-1237777Y529337D01*
G01X-1237680Y529786D02*
X-1237705Y529573D01*
G01X-1237682Y527255D02*
X-1237877Y527239D01*
G01X-1237499Y527303D02*
X-1237682Y527255D01*
G01X-1237329Y527380D02*
X-1237499Y527303D01*
G01X-1237181Y527483D02*
X-1237329Y527380D01*
G01X-1237057Y527612D02*
X-1237181Y527483D01*
G01X-1236967Y527755D02*
X-1237057Y527612D01*
G01X-1236912Y527911D02*
X-1236967Y527755D01*
G01X-1236893Y528073D02*
X-1236912Y527911D01*
G01X-1250147Y498765D02*
X-1250064Y499473D01*
G01X-1250227Y498103D02*
X-1250147Y498765D01*
G01D02*
X-1250229Y498112D01*
G01X-1250064Y499473D02*
X-1250147Y498765D01*
G01X-1249982Y500141D02*
X-1250064Y499473D01*
G01X-1250177Y500076D02*
X-1250104Y500575D01*
G01X-1250254Y499496D02*
X-1250177Y500076D01*
G01X-1250422Y498149D02*
X-1250254Y499496D01*
G01X-1248851Y499736D02*
X-1248979Y498655D01*
G01X-1248789Y500240D02*
X-1248851Y499736D01*
G01X-1248725Y500697D02*
X-1248789Y500240D01*
G01X-1249161Y498794D02*
X-1249241Y498149D01*
G01X-1249082Y499421D02*
X-1249161Y498794D01*
G01X-1249003Y500027D02*
X-1249082Y499421D01*
G01X-1248923Y500574D02*
X-1249003Y500027D01*
G01X-1259135Y536469D02*
X-1259019Y536475D01*
G01X-1259246Y536451D02*
X-1259135Y536469D01*
G01X-1259347Y536422D02*
X-1259246Y536451D01*
G01X-1259436Y536384D02*
X-1259347Y536422D01*
G01X-1259511Y536336D02*
X-1259436Y536384D01*
G01X-1259565Y536282D02*
X-1259511Y536336D01*
G01X-1259598Y536223D02*
X-1259565Y536282D01*
G01X-1259609Y536162D02*
X-1259598Y536223D01*
G01X-1249029Y499467D02*
X-1248923Y499960D01*
G01X-1249135Y498913D02*
X-1249029Y499467D01*
G01X-1249241Y498343D02*
X-1249135Y498913D01*
G01X-1248735Y500987D02*
X-1248733Y500995D01*
G01X-1248737Y500979D02*
X-1248735Y500987D01*
G01X-1248739Y500971D02*
X-1248737Y500979D01*
G01X-1248741Y500963D02*
X-1248739Y500971D01*
G01X-1248742Y500955D02*
X-1248741Y500963D01*
G01X-1248743Y500950D02*
X-1248742Y500955D01*
G01X-1249801Y501238D02*
X-1249900Y500797D01*
G01X-1249707Y501686D02*
X-1249801Y501238D01*
G01X-1249616Y502145D02*
X-1249707Y501686D01*
G01X-1249855Y501036D02*
X-1249942Y500697D01*
G01X-1249774Y501384D02*
X-1249855Y501036D01*
G01X-1249696Y501747D02*
X-1249774Y501384D01*
G01X-1250316Y498913D02*
X-1250422Y498343D01*
G01X-1250210Y499467D02*
X-1250316Y498913D01*
G01X-1250104Y499960D02*
X-1250210Y499467D01*
G01X-1247894Y502091D02*
X-1247769Y502102D01*
G01X-1248018Y502057D02*
X-1247894Y502091D01*
G01X-1248143Y501998D02*
X-1248018Y502057D01*
G01X-1248267Y501912D02*
X-1248143Y501998D01*
G01X-1248387Y501795D02*
X-1248267Y501912D01*
G01X-1248500Y501645D02*
X-1248387Y501795D01*
G01X-1248600Y501459D02*
X-1248500Y501645D01*
G01X-1248680Y501242D02*
X-1248600Y501459D01*
G01X-1248733Y500995D02*
X-1248680Y501242D01*
G01X-1249923Y500958D02*
X-1249924Y500950D01*
G01X-1249921Y500966D02*
X-1249923Y500958D01*
G01X-1249919Y500974D02*
X-1249921Y500966D01*
G01X-1249917Y500982D02*
X-1249919Y500974D01*
G01X-1249916Y500990D02*
X-1249917Y500982D01*
G01X-1249914Y500995D02*
X-1249916Y500990D01*
G01X-1249727Y501985D02*
X-1249616Y502145D01*
G01X-1249814Y501834D02*
X-1249727Y501985D01*
G01X-1249884Y501677D02*
X-1249814Y501834D01*
G01X-1249924Y501538D02*
X-1249884Y501677D01*
G01X-1249099Y559779D02*
X-1249038Y559792D01*
G01X-1249142Y559742D02*
X-1249099Y559779D01*
G01X-1249158Y559692D02*
X-1249142Y559742D01*
G01X-1248697Y501732D02*
X-1248743Y501570D01*
G01X-1248618Y501904D02*
X-1248697Y501732D01*
G01X-1248512Y502083D02*
X-1248618Y501904D01*
G01X-1238822Y525383D02*
X-1238664Y525338D01*
G01X-1238968Y525428D02*
X-1238822Y525383D01*
G01X-1239101Y525474D02*
X-1238968Y525428D01*
G01X-1239220Y525520D02*
X-1239101Y525474D01*
G01X-1239327Y525566D02*
X-1239220Y525520D01*
G01X-1239421Y525612D02*
X-1239327Y525566D01*
G01X-1239502Y525660D02*
X-1239421Y525612D01*
G01X-1239575Y525712D02*
X-1239502Y525660D01*
G01X-1239646Y525778D02*
X-1239575Y525712D01*
G01X-1239712Y525850D02*
X-1239646Y525778D01*
G01X-1239769Y525922D02*
X-1239712Y525850D01*
G01X-1239829Y526012D02*
X-1239769Y525922D01*
G01X-1239881Y526119D02*
X-1239829Y526012D01*
G01X-1239913Y526230D02*
X-1239881Y526119D01*
G01X-1239923Y526341D02*
X-1239913Y526230D01*
G01X-1239909Y526451D02*
X-1239923Y526341D01*
G01X-1239870Y526561D02*
X-1239909Y526451D01*
G01X-1239803Y526674D02*
X-1239870Y526561D01*
G01X-1239704Y526788D02*
X-1239803Y526674D01*
G01X-1239576Y526899D02*
X-1239704Y526788D01*
G01X-1239420Y527007D02*
X-1239576Y526899D01*
G01X-1249073Y502342D02*
X-1248950Y502348D01*
G01X-1249194Y502323D02*
X-1249073Y502342D01*
G01X-1249308Y502295D02*
X-1249194Y502323D01*
G01X-1249420Y502254D02*
X-1249308Y502295D01*
G01X-1249522Y502204D02*
X-1249420Y502254D01*
G01X-1249616Y502145D02*
X-1249522Y502204D01*
G01X-1238804Y527858D02*
X-1238664Y527865D01*
G01X-1238938Y527837D02*
X-1238804Y527858D01*
G01X-1239068Y527804D02*
X-1238938Y527837D01*
G01X-1239193Y527759D02*
X-1239068Y527804D01*
G01X-1239311Y527701D02*
X-1239193Y527759D01*
G01X-1239420Y527633D02*
X-1239311Y527701D01*
G01X-1259391Y534780D02*
X-1259412Y534606D01*
G01X-1259326Y534948D02*
X-1259391Y534780D01*
G01X-1259222Y535099D02*
X-1259326Y534948D01*
G01X-1259083Y535228D02*
X-1259222Y535099D01*
G01X-1258916Y535330D02*
X-1259083Y535228D01*
G01X-1258728Y535401D02*
X-1258916Y535330D01*
G01X-1243231Y559894D02*
G03I-1378J0D01*
G01X-1236696Y554865D02*
G03X-1236893Y555575I-1378J0D01*
G01X-1236499Y560213D02*
G03X-1236781Y561675I-3937J-1D01*
G01X-1235318Y560213D02*
G03X-1235684Y562114I-5118J0D01*
G01X-1238074Y515692D02*
G03X-1237877Y515889I0J197D01*
G01X-1244216Y519418D02*
G03X-1243822Y518736I787J0D01*
G01X-1236893Y515179D02*
G03X-1236696Y515889I-1181J710D01*
G01X-1244216Y517267D02*
G03X-1243822Y518736I0J787D01*
G01X-1247940Y519850D02*
G03X-1248358Y520023I-418J-418D01*
G01X-1247326Y517858D02*
G03X-1246735Y517267I591J0D01*
G01X-1247326Y518991D02*
G03X-1247499Y519409I-590J1D01*
G01X-1249273Y513054D02*
G03X-1248704Y512733I1042J1182D01*
G01X-1249403Y513068D02*
G03X-1248727Y512658I1171J1168D01*
G01X-1249552Y513054D02*
G03X-1248763Y512546I1320J1183D01*
G01X-1248349Y511982D02*
G03X-1248763Y512545I-590J0D01*
G01X-1248231Y511982D02*
G03X-1248727Y512658I-709J0D01*
G01X-1248153Y511982D02*
G03X-1248704Y512733I-787J0D01*
G01X-1248153Y509465D02*
G03X-1248251Y509636I-198J0D01*
G01X-1248349Y509806D02*
G03X-1248251Y509636I196J0D01*
G01X-1248153Y509413D02*
G03X-1248251Y509583I-196J0D01*
G01X-1248349Y509754D02*
G03X-1248251Y509583I198J0D01*
G01X-1248950Y504275D02*
G03X-1251483Y502076I0J-2558D01*
G01X-1244822D02*
G03X-1247355Y504275I-2533J-359D01*
G01X-1247769D02*
G03X-1250302Y502076I0J-2558D01*
G01X-1243641D02*
G03X-1246174Y504275I-2533J-359D01*
G01X-1250318Y557936D02*
G03I-1378J0D01*
G01X-1259412Y555575D02*
G03X-1259609Y554865I1181J-710D01*
G01X-1259525Y561675D02*
G03X-1259806Y560213I3656J-1461D01*
G01X-1260621Y562114D02*
G03X-1260987Y560213I4752J-1901D01*
G01X-1250751Y515299D02*
G03X-1251145Y515692I-393J0D01*
G01Y513724D02*
G03X-1250751Y514117I0J394D01*
G01X-1251538Y514905D02*
G03X-1252412Y515267I-512J0D01*
G01X-1252790Y520023D02*
G03X-1253207Y519850I1J-591D01*
G01X-1253649Y519409D02*
G03X-1253822Y518991I418J-418D01*
G01X-1254412Y517267D02*
G03X-1253822Y517858I0J590D01*
G01X-1254412Y514804D02*
G03X-1253404Y514386I591J0D01*
G01X-1251460Y514905D02*
G03X-1252468Y515322I-590J0D01*
G01X-1254491Y514804D02*
G03X-1253349Y514330I669J0D01*
G01X-1252483Y518736D02*
G03X-1252090Y517267I393J-682D01*
G01X-1252483Y518736D02*
G03X-1252090Y519418I-395J682D01*
G01X-1250751Y507818D02*
G03X-1251145Y508212I-394J0D01*
G01Y506243D02*
G03X-1250751Y506637I0J394D01*
G01X-1252412Y506669D02*
G03X-1251538Y507031I362J362D01*
G01X-1253404Y507550D02*
G03X-1254412Y507132I-417J-418D01*
G01X-1252468Y506613D02*
G03X-1251460Y507031I417J418D01*
G01X-1253349Y507605D02*
G03X-1254491Y507132I-473J-473D01*
G01X-1258428Y515889D02*
G03X-1258231Y515692I197J0D01*
G01X-1255279Y514117D02*
G03X-1254885Y513724I393J0D01*
G01Y515692D02*
G03X-1255279Y515299I0J-394D01*
G01X-1259609Y515889D02*
G03X-1259412Y515179I1378J0D01*
G01X-1255279Y506637D02*
G03X-1254885Y506243I394J0D01*
G01Y508212D02*
G03X-1255279Y507818I0J-394D01*
G01X-1244895Y498112D02*
X-1244705Y498172D01*
G01X-1245101Y527735D02*
X-1247168Y527011D01*
G01X-1248725Y500697D02*
X-1248920Y500593D01*
G01X-1254004Y558028D02*
X-1253960Y558044D01*
G01X-1245200Y551145D02*
X-1251204Y548730D01*
G01X-1245101Y551410D02*
X-1251145Y548980D01*
G01X-1245200Y543271D02*
X-1251204Y540851D01*
G01X-1245101Y543541D02*
X-1251145Y541106D01*
G01X-1239727Y513054D02*
X-1240909Y512267D01*
G01X-1245200Y535397D02*
X-1251204Y530961D01*
G01X-1245101Y535728D02*
X-1251145Y531263D01*
G01X-1245200Y527523D02*
X-1245987Y526822D01*
G01X-1238172Y503802D02*
X-1240141Y501834D01*
G01X-1238172Y514236D02*
X-1239353Y513054D01*
G01X-1244897Y498103D02*
X-1244899Y498101D01*
G01X-1253886Y557998D02*
X-1253945Y557953D01*
G01X-1249924Y503802D02*
X-1251893Y501834D01*
G01X-1239846Y521913D02*
X-1240042Y521716D01*
G01X-1244609Y518566D02*
X-1245790Y517385D01*
G01X-1252412Y515267D02*
X-1253349Y514330D01*
G01X-1252468Y515322D02*
X-1253404Y514386D01*
G01X-1254117Y518173D02*
X-1254905Y517385D01*
G01X-1253207Y519850D02*
X-1253649Y519409D01*
G01X-1258133Y518566D02*
X-1257542Y519157D01*
G01X-1256263Y524865D02*
X-1256460Y524669D01*
G01X-1244895Y498112D02*
X-1244900Y498105D01*
G01X-1253960Y558044D02*
X-1253930Y558074D01*
G01X-1253620Y558209D02*
X-1253709Y558104D01*
G01Y558224D02*
X-1253620Y558330D01*
G01X-1253842Y558059D02*
X-1253886Y557998D01*
G01X-1259609Y554120D02*
X-1260200Y553097D01*
G01X-1257444Y562111D02*
X-1258028Y560987D01*
G01X-1258920Y563186D02*
X-1259525Y561675D01*
G01X-1260621Y562114D02*
X-1259412Y565136D01*
G01X-1253827Y558104D02*
X-1253842Y558059D01*
G01X-1253930Y558074D02*
X-1253915Y558119D01*
G01X-1248704Y512733D02*
X-1248763Y512546D01*
G01X-1237385Y518566D02*
X-1238172Y515628D01*
G01X-1258028Y560987D02*
X-1257444Y563237D01*
G01X-1250104Y500575D02*
X-1249924Y501538D01*
G01X-1248923Y499960D02*
X-1248743Y500950D01*
G01X-1249924D02*
X-1250104Y499960D01*
G01X-1248743Y501570D02*
X-1248923Y500574D01*
G01X-1248512Y502083D02*
X-1248725Y500697D01*
G01X-1249982Y500141D02*
X-1249908Y500697D01*
G01X-1250225Y498096D02*
X-1250224Y498110D01*
G01X-1248979Y498655D02*
X-1249033Y498110D01*
G01X-1248155Y502254D02*
X-1248349Y494188D01*
G01X-1235318Y560213D02*
Y557822D01*
G01X-1235515Y535372D02*
Y570814D01*
G01X-1236302Y564942D02*
Y536851D01*
G01X-1236499Y557822D02*
Y560213D01*
G01X-1236696Y570814D02*
Y515889D01*
G01X-1237267Y525141D02*
Y562891D01*
G01Y566480D02*
Y564117D01*
G01X-1237286Y570534D02*
Y529786D01*
G01X-1237385Y518566D02*
Y521125D01*
G01X-1237680Y529786D02*
Y569688D01*
G01X-1237779Y534810D02*
Y535436D01*
G01X-1237877Y522790D02*
Y515889D01*
G01Y527865D02*
Y527239D01*
G01X-1238172Y503802D02*
Y524865D01*
G01X-1238271Y570436D02*
Y519255D01*
G01X-1238664Y535641D02*
Y536267D01*
G01Y527239D02*
Y527865D01*
G01X-1238763Y519157D02*
Y522790D01*
G01X-1238861Y562111D02*
Y570436D01*
G01X-1239353Y513054D02*
Y528015D01*
G01X-1239420Y527007D02*
Y527633D01*
G01X-1239747Y524964D02*
Y521617D01*
G01X-1239846Y521913D02*
Y524669D01*
G01X-1239923Y526704D02*
Y526331D01*
G01X-1241125Y521617D02*
Y519255D01*
G01X-1241223Y519157D02*
Y521716D01*
G01X-1241460Y528901D02*
Y528015D01*
G01X-1244019Y507739D02*
Y503802D01*
G01Y551345D02*
Y528901D01*
G01Y558790D02*
Y554543D01*
G01X-1244216Y519418D02*
Y557058D01*
G01Y560791D02*
Y559019D01*
G01X-1244609Y521519D02*
Y518566D01*
G01X-1244702Y498149D02*
Y498343D01*
G01X-1245003Y557058D02*
Y527610D01*
G01Y560681D02*
Y559106D01*
G01X-1245020Y499960D02*
Y500575D01*
G01X-1245101Y559218D02*
Y560414D01*
G01Y551410D02*
Y552563D01*
G01Y543541D02*
Y544750D01*
G01Y535728D02*
Y536881D01*
G01Y527735D02*
Y529073D01*
G01X-1245200Y501538D02*
Y500950D01*
G01X-1245397Y529200D02*
Y528574D01*
G01X-1245594Y532051D02*
Y528901D01*
G01Y558790D02*
Y549037D01*
G01X-1245883Y498343D02*
Y498149D01*
G01X-1245987Y549290D02*
Y563547D01*
G01Y526822D02*
Y524964D01*
G01Y532051D02*
Y528901D01*
G01X-1246174Y502102D02*
Y502348D01*
G01X-1246181Y543429D02*
Y540821D01*
G01Y547616D02*
Y544968D01*
G01Y552624D02*
Y549154D01*
G01Y555990D02*
Y554162D01*
G01Y560710D02*
Y559580D01*
G01X-1246201Y500574D02*
Y499960D01*
G01X-1246381Y500950D02*
Y501570D01*
G01X-1246637Y513054D02*
Y517385D01*
G01X-1247031Y518173D02*
Y520338D01*
G01X-1247032Y543129D02*
Y540821D01*
G01Y547315D02*
Y544968D01*
G01Y550330D02*
Y549154D01*
G01Y552624D02*
Y551448D01*
G01X-1247150Y553341D02*
Y553445D01*
G01Y550326D02*
Y550431D01*
G01Y547311D02*
Y547416D01*
G01Y543125D02*
Y543229D01*
G01Y544250D02*
Y544146D01*
G01Y548437D02*
Y548333D01*
G01Y551452D02*
Y551348D01*
G01Y556811D02*
Y556707D01*
G01X-1247168Y527011D02*
Y524964D01*
G01X-1247326Y517858D02*
Y518991D01*
G01X-1247355Y502348D02*
Y502102D01*
G01X-1247386Y555689D02*
Y554463D01*
G01X-1247421Y544146D02*
Y544250D01*
G01X-1247504Y555685D02*
Y555789D01*
G01Y554467D02*
Y554363D01*
G01X-1247681Y543229D02*
Y543125D01*
G01Y547416D02*
Y547311D01*
G01X-1247769Y502348D02*
Y502102D01*
G01X-1247799Y543129D02*
Y541642D01*
G01Y547315D02*
Y545368D01*
G01X-1247956Y570436D02*
Y563547D01*
G01X-1248251Y511982D02*
Y509583D01*
G01X-1248349Y511982D02*
Y509754D01*
G01Y570436D02*
Y563547D01*
G01X-1248390Y543429D02*
Y541943D01*
G01Y547315D02*
Y545368D01*
G01X-1248508Y547311D02*
Y547416D01*
G01Y541947D02*
Y541842D01*
G01X-1248685Y554363D02*
Y554467D01*
G01Y555789D02*
Y555685D01*
G01X-1248743Y500950D02*
Y501570D01*
G01X-1248768Y540821D02*
Y540925D01*
G01X-1248803Y555689D02*
Y554463D01*
G01X-1248923Y500574D02*
Y499960D01*
G01X-1248950Y502102D02*
Y502348D01*
G01X-1249029Y559896D02*
Y559792D01*
G01X-1249040Y556707D02*
Y556811D01*
G01Y548333D02*
Y548437D01*
G01Y541842D02*
Y541947D01*
G01Y540925D02*
Y540821D01*
G01Y547416D02*
Y547311D01*
G01Y553445D02*
Y553341D01*
G01X-1249158Y544250D02*
Y541943D01*
G01Y547315D02*
Y544968D01*
G01Y559796D02*
Y557528D01*
G01X-1249241Y498343D02*
Y498149D01*
G01X-1249494Y560852D02*
Y560956D01*
G01X-1249924Y501538D02*
Y500950D01*
G01Y507739D02*
Y503802D01*
G01X-1250008Y544250D02*
Y541642D01*
G01Y547616D02*
Y544968D01*
G01Y551452D02*
Y550326D01*
G01Y555990D02*
Y554162D01*
G01Y560557D02*
Y557528D01*
G01X-1250104Y499960D02*
Y500575D01*
G01X-1250357Y563547D02*
Y560987D01*
G01X-1250422Y498149D02*
Y498343D01*
G01X-1244901Y498110D02*
X-1244899Y498096D01*
G01X-1244702Y498149D02*
X-1244870Y499496D01*
G01X-1250751Y514117D02*
Y515299D01*
G01Y506637D02*
Y507818D01*
G01X-1250909Y528574D02*
Y529200D01*
G01X-1251204Y530961D02*
Y529710D01*
G01Y540851D02*
Y539606D01*
G01Y548730D02*
Y547485D01*
G01Y558626D02*
Y557375D01*
G01X-1251302Y557149D02*
Y558724D01*
G01Y547306D02*
Y548881D01*
G01Y546891D02*
Y528586D01*
G01X-1251460Y507031D02*
Y514905D01*
G01X-1251538Y507031D02*
Y514905D01*
G01X-1251696Y518566D02*
Y521519D01*
G01X-1252090Y557149D02*
Y558724D01*
G01Y547306D02*
Y548881D01*
G01Y528198D02*
Y519418D01*
G01Y546891D02*
Y528586D01*
G01X-1252129Y531263D02*
Y529491D01*
G01Y541106D02*
Y539334D01*
G01Y548980D02*
Y547208D01*
G01Y558822D02*
Y557051D01*
G01X-1253532Y558330D02*
Y557621D01*
G01X-1253620D02*
Y558209D01*
G01X-1253709Y558104D02*
Y558224D01*
G01X-1253822Y518991D02*
Y517858D01*
G01X-1253827Y558164D02*
Y558104D01*
G01X-1253915Y558119D02*
Y558164D01*
G01X-1254117Y518173D02*
Y520338D01*
G01X-1254285Y558255D02*
Y558028D01*
G01Y557938D02*
Y557621D01*
G01X-1254373D02*
Y558330D01*
G01X-1254412Y514804D02*
Y517267D01*
G01X-1254491Y514804D02*
Y517267D01*
G01X-1254511Y517385D02*
Y513054D01*
G01X-1255082Y521716D02*
Y519157D01*
G01X-1255180Y519255D02*
Y521617D01*
G01X-1255279Y507818D02*
Y506637D01*
G01Y515299D02*
Y514117D01*
G01X-1256460Y524669D02*
Y521913D01*
G01X-1256476Y526044D02*
Y526309D01*
G01X-1256558Y521617D02*
Y524964D01*
G01X-1256885Y527633D02*
Y527007D01*
G01X-1256952Y513054D02*
Y528015D01*
G01X-1257444Y562111D02*
Y570436D01*
G01X-1257542Y522790D02*
Y519157D01*
G01X-1257641Y535641D02*
Y536267D01*
G01Y527865D02*
Y527239D01*
G01X-1258035Y570436D02*
Y519255D01*
G01X-1258133Y524865D02*
Y503802D01*
G01X-1258428Y527239D02*
Y527865D01*
G01Y522790D02*
Y515889D01*
G01X-1258527Y535436D02*
Y534810D01*
G01X-1258625Y569688D02*
Y529786D01*
G01X-1258920Y522790D02*
Y524354D01*
G01Y521125D02*
Y518566D01*
G01Y563330D02*
Y526716D01*
G01X-1259019Y529786D02*
Y570534D01*
G01X-1259609Y570814D02*
Y515889D01*
G01X-1259806Y557822D02*
Y560213D01*
G01X-1260003Y536851D02*
Y564942D01*
G01X-1260790Y570814D02*
Y535372D01*
G01X-1260987Y560213D02*
Y557822D01*
G01X-1246612Y502083D02*
X-1246399Y500697D01*
G01X-1246381Y501570D02*
X-1246201Y500574D01*
G01X-1245200Y500950D02*
X-1245020Y499960D01*
G01X-1246201D02*
X-1246381Y500950D01*
G01X-1245020Y500575D02*
X-1245200Y501538D01*
G01X-1245594Y558790D02*
X-1245987Y560399D01*
G01X-1258920Y518566D02*
X-1258133Y515628D01*
G01X-1253842Y558209D02*
X-1253827Y558164D01*
G01X-1253915D02*
X-1253930Y558209D01*
G01X-1235684Y562114D02*
X-1236893Y565136D01*
G01X-1237267Y562891D02*
X-1236781Y561675D01*
G01X-1238271Y560975D02*
X-1238861Y562111D01*
G01X-1259019Y542134D02*
X-1258920Y541923D01*
G01X-1236696Y554120D02*
X-1236105Y553097D01*
G01X-1253886Y558270D02*
X-1253842Y558209D01*
G01X-1253945Y557953D02*
X-1254019Y557938D01*
G01X-1250229Y498112D02*
X-1250224Y498105D01*
G01X-1253930Y558209D02*
X-1253960Y558240D01*
G01X-1247956Y563547D02*
X-1245200Y560791D01*
G01X-1248349Y563662D02*
X-1245101Y560414D01*
G01X-1240042Y524865D02*
X-1239846Y524669D01*
G01X-1238763Y519157D02*
X-1238172Y518566D01*
G01X-1247940Y519850D02*
X-1247499Y519409D01*
G01X-1247031Y518173D02*
X-1246243Y517385D01*
G01X-1253945Y558315D02*
X-1253886Y558270D01*
G01X-1251204Y557375D02*
X-1245200Y552917D01*
G01X-1251145Y557051D02*
X-1245101Y552563D01*
G01X-1245594Y549037D02*
X-1245987Y549290D01*
G01X-1254019Y558330D02*
X-1253945Y558315D01*
G01X-1249494Y560956D02*
X-1246181Y560710D01*
G01Y560606D02*
X-1249494Y560852D01*
G01X-1246181Y559685D02*
X-1249038Y559897D01*
G01Y559792D02*
X-1246181Y559580D01*
G01X-1260003Y564942D02*
X-1260790D01*
G01X-1235515D02*
X-1236302D01*
G01X-1259412Y564920D02*
X-1258231D01*
G01Y564159D02*
X-1259412D01*
G01X-1236893Y564117D02*
X-1238074D01*
G01X-1247956Y563547D02*
X-1245987D01*
G01X-1248349D02*
X-1250357D01*
G01X-1259412Y563397D02*
X-1258231D01*
G01Y563330D02*
X-1259412D01*
G01X-1236893Y562630D02*
X-1238074D01*
G01X-1258920Y561831D02*
X-1259412D01*
G01X-1236893Y561755D02*
X-1238074D01*
G01Y561684D02*
X-1236893D01*
G01X-1258920Y561298D02*
X-1259412D01*
G01X-1238074Y561000D02*
X-1236893D01*
G01X-1258028Y560987D02*
X-1250357D01*
G01X-1236893Y560941D02*
X-1238074D01*
G01Y560869D02*
X-1236893D01*
G01X-1244216Y560791D02*
X-1245200D01*
G01X-1244216Y560681D02*
X-1245003D01*
G01X-1244216Y560663D02*
X-1245003D01*
G01Y560386D02*
X-1244216D01*
G01X-1237267Y560286D02*
X-1236893D01*
G01Y559604D02*
X-1237267D01*
G01X-1245003Y559402D02*
X-1244216D01*
G01X-1245003Y559125D02*
X-1244216D01*
G01Y559106D02*
X-1245003D01*
G01X-1244216Y559019D02*
X-1245200D01*
G01X-1251145Y558822D02*
X-1252129D01*
G01X-1245594Y558790D02*
X-1244019D01*
G01X-1251302Y558724D02*
X-1252090D01*
G01X-1251302Y558706D02*
X-1252090D01*
G01Y558428D02*
X-1251302D01*
G01X-1253620Y558330D02*
X-1253532D01*
G01X-1254373D02*
X-1254019D01*
G01X-1254004Y558255D02*
X-1254285D01*
G01Y558028D02*
X-1254004D01*
G01X-1254019Y557938D02*
X-1254285D01*
G01X-1259806Y557822D02*
X-1260987D01*
G01X-1258920D02*
X-1259412D01*
G01X-1235318D02*
X-1236499D01*
G01X-1236893D02*
X-1237267D01*
G01X-1249158Y557632D02*
X-1250008D01*
G01X-1259609Y557625D02*
X-1260790D01*
G01X-1235515D02*
X-1236696D01*
G01X-1253532Y557621D02*
X-1253620D01*
G01X-1254285D02*
X-1254373D01*
G01X-1249158Y557528D02*
X-1250008D01*
G01X-1252090Y557444D02*
X-1251302D01*
G01X-1260790Y557231D02*
X-1259609D01*
G01X-1258920D02*
X-1259412D01*
G01X-1236893D02*
X-1237267D01*
G01X-1235515D02*
X-1236696D01*
G01X-1252090Y557167D02*
X-1251302D01*
G01Y557149D02*
X-1252090D01*
G01X-1244216Y557058D02*
X-1245003D01*
G01X-1251145Y557051D02*
X-1252129D01*
G01X-1236696Y556838D02*
X-1235515D01*
G01X-1259609D02*
X-1260790D01*
G01X-1249040Y556811D02*
X-1247150D01*
G01X-1249040Y556707D02*
X-1247150D01*
G01X-1258920Y555853D02*
X-1259412D01*
G01X-1236893D02*
X-1237267D01*
G01X-1248685Y555789D02*
X-1247504D01*
G01X-1248685Y555685D02*
X-1247504D01*
G01X-1258920Y555657D02*
X-1259412D01*
G01X-1236893D02*
X-1237267D01*
G01X-1259412Y555432D02*
X-1258920D01*
G01X-1236893D02*
X-1237267D01*
G01X-1244019Y555280D02*
X-1238271D01*
G01X-1259609Y555066D02*
X-1260790D01*
G01X-1235515D02*
X-1236696D01*
G01X-1258920Y554869D02*
X-1259412D01*
G01X-1236893D02*
X-1237267D01*
G01X-1244019Y554543D02*
X-1238271D01*
G01X-1247504Y554467D02*
X-1248685D01*
G01X-1247504Y554363D02*
X-1248685D01*
G01X-1247150Y553445D02*
X-1249040D01*
G01X-1247150Y553341D02*
X-1249040D01*
G01X-1260200Y553097D02*
X-1260790D01*
G01X-1235515D02*
X-1236105D01*
G01X-1259412Y553094D02*
X-1259609D01*
G01X-1236696D02*
X-1236893D01*
G01X-1244216Y552917D02*
X-1245200D01*
G01X-1244216Y552807D02*
X-1245003D01*
G01X-1244216Y552789D02*
X-1245003D01*
G01X-1247032Y552624D02*
X-1246181D01*
G01X-1247032Y552520D02*
X-1246181D01*
G01X-1245003Y552512D02*
X-1244216D01*
G01X-1245003Y551528D02*
X-1244216D01*
G01X-1250008Y551452D02*
X-1247150D01*
G01X-1250008Y551348D02*
X-1247150D01*
G01X-1244019Y551345D02*
X-1238271D01*
G01X-1245003Y551250D02*
X-1244216D01*
G01Y551232D02*
X-1245003D01*
G01X-1244216Y551145D02*
X-1245200D01*
G01X-1247150Y550431D02*
X-1250008D01*
G01X-1247150Y550326D02*
X-1250008D01*
G01X-1244019Y549923D02*
X-1245987D01*
G01X-1238271Y549780D02*
X-1244019D01*
G01X-1246181Y549259D02*
X-1247032D01*
G01X-1246181Y549154D02*
X-1247032D01*
G01X-1244019Y549037D02*
X-1245594D01*
G01X-1251145Y548980D02*
X-1252129D01*
G01X-1251302Y548881D02*
X-1252090D01*
G01X-1251302Y548863D02*
X-1252090D01*
G01Y548586D02*
X-1251302D01*
G01X-1258920Y548488D02*
X-1259412D01*
G01X-1236893D02*
X-1237267D01*
G01X-1249040Y548437D02*
X-1247150D01*
G01X-1249040Y548333D02*
X-1247150D01*
G01X-1258920Y548291D02*
X-1259019D01*
G01X-1244216Y548257D02*
X-1245003D01*
G01Y547812D02*
X-1244216D01*
G01X-1252090Y547602D02*
X-1251302D01*
G01X-1248508Y547416D02*
X-1249040D01*
G01X-1247150D02*
X-1247681D01*
G01X-1252090Y547324D02*
X-1251302D01*
G01X-1248508Y547311D02*
X-1249040D01*
G01X-1247150D02*
X-1247681D01*
G01X-1251302Y547306D02*
X-1252090D01*
G01X-1251145Y547208D02*
X-1252129D01*
G01X-1237267Y547018D02*
X-1236893D01*
G01X-1259412D02*
X-1258920D01*
G01X-1244019Y547013D02*
X-1238271D01*
G01X-1251302Y546891D02*
X-1252090D01*
G01X-1258920Y546336D02*
X-1259412D01*
G01X-1236893D02*
X-1237267D01*
G01X-1244019Y545749D02*
X-1238271D01*
G01X-1247799Y545472D02*
X-1248390D01*
G01X-1247799Y545368D02*
X-1248390D01*
G01X-1249158Y545072D02*
X-1250008D01*
G01X-1246181D02*
X-1247032D01*
G01X-1244216Y545043D02*
X-1245200D01*
G01X-1249158Y544968D02*
X-1250008D01*
G01X-1246181D02*
X-1247032D01*
G01X-1244216Y544933D02*
X-1245003D01*
G01X-1244216Y544915D02*
X-1245003D01*
G01Y544638D02*
X-1244216D01*
G01X-1247421Y544250D02*
X-1247150D01*
G01X-1250008D02*
X-1249158D01*
G01X-1247421Y544146D02*
X-1247150D01*
G01X-1250008D02*
X-1249158D01*
G01X-1245003Y543654D02*
X-1244216D01*
G01X-1245003Y543376D02*
X-1244216D01*
G01Y543358D02*
X-1245003D01*
G01X-1244216Y543271D02*
X-1245200D01*
G01X-1247150Y543229D02*
X-1247681D01*
G01X-1247150Y543125D02*
X-1247681D01*
G01X-1251302Y542888D02*
X-1252090D01*
G01Y542190D02*
X-1251302D01*
G01X-1249040Y541947D02*
X-1248508D01*
G01X-1249040Y541842D02*
X-1248508D01*
G01X-1251145Y541106D02*
X-1252129D01*
G01X-1251302Y541007D02*
X-1252090D01*
G01X-1251302Y540989D02*
X-1252090D01*
G01X-1248768Y540925D02*
X-1249040D01*
G01X-1246181D02*
X-1247032D01*
G01X-1248768Y540821D02*
X-1249040D01*
G01X-1246181D02*
X-1247032D01*
G01X-1252090Y540712D02*
X-1251302D01*
G01X-1252090Y539728D02*
X-1251302D01*
G01X-1252090Y539450D02*
X-1251302D01*
G01X-1258920Y539432D02*
X-1259412D01*
G01X-1251302D02*
X-1252090D01*
G01X-1236893D02*
X-1237267D01*
G01X-1251145Y539334D02*
X-1252129D01*
G01X-1258920Y538645D02*
X-1259412D01*
G01X-1236893D02*
X-1237267D01*
G01X-1244216Y537169D02*
X-1245200D01*
G01X-1258625Y537101D02*
X-1259019D01*
G01X-1237286D02*
X-1237680D01*
G01X-1244216Y537059D02*
X-1245003D01*
G01X-1244216Y537041D02*
X-1245003D01*
G01X-1236302Y536851D02*
X-1235515D01*
G01X-1260790D02*
X-1260003D01*
G01X-1245003Y536764D02*
X-1244216D01*
G01X-1245101Y559218D02*
X-1251145Y558822D01*
G01X-1245200Y559019D02*
X-1251204Y558626D01*
G01X-1251696Y518566D02*
X-1250515Y517385D01*
G01X-1256460Y521913D02*
X-1256263Y521716D01*
G01X-1242050Y501834D02*
X-1244019Y503802D01*
G01X-1258133Y514236D02*
X-1256952Y513054D01*
G01X-1253349Y507605D02*
X-1252412Y506669D01*
G01X-1253404Y507550D02*
X-1252468Y506613D01*
G01X-1256164Y501834D02*
X-1258133Y503802D01*
G01X-1249334Y513054D02*
X-1248153Y512267D01*
G01X-1245200Y545043D02*
X-1251204Y547485D01*
G01X-1245101Y544750D02*
X-1251145Y547208D01*
G01X-1245200Y537169D02*
X-1251204Y539606D01*
G01X-1245101Y536881D02*
X-1251145Y539334D01*
G01X-1253960Y558240D02*
X-1254004Y558255D01*
G01X-1245200Y529295D02*
X-1251204Y529710D01*
G01X-1245101Y529073D02*
X-1251145Y529491D01*
G01X-1248153Y501466D02*
X-1248174D01*
G01X-1258625Y536475D02*
X-1259019D01*
G01X-1237286D02*
X-1237680D01*
G01X-1259609Y535849D02*
X-1260790D01*
G01X-1235515D02*
X-1236696D01*
G01X-1245003Y535780D02*
X-1244216D01*
G01X-1245003Y535502D02*
X-1244216D01*
G01Y535484D02*
X-1245003D01*
G01X-1244216Y535397D02*
X-1245200D01*
G01X-1260790Y535371D02*
X-1259609D01*
G01X-1235515D02*
X-1236696D01*
G01X-1251302Y535219D02*
X-1252090D01*
G01X-1244216Y533962D02*
X-1245003D01*
G01X-1252090Y533133D02*
X-1251302D01*
G01X-1238271Y532051D02*
X-1245987D01*
G01X-1245003Y531876D02*
X-1244216D01*
G01X-1244019Y531296D02*
X-1238271D01*
G01X-1251145Y531263D02*
X-1252129D01*
G01X-1251302Y531165D02*
X-1252090D01*
G01X-1251302Y531147D02*
X-1252090D01*
G01Y530869D02*
X-1251302D01*
G01X-1252090Y529885D02*
X-1251302D01*
G01X-1258625Y529786D02*
X-1259019D01*
G01X-1237286D02*
X-1237680D01*
G01X-1252090Y529608D02*
X-1251302D01*
G01Y529590D02*
X-1252090D01*
G01X-1251145Y529491D02*
X-1252129D01*
G01X-1244216Y529295D02*
X-1245200D01*
G01X-1245397Y529200D02*
X-1250909D01*
G01X-1244216Y529185D02*
X-1245003D01*
G01X-1244216Y529167D02*
X-1245003D01*
G01X-1245987Y528901D02*
X-1238271D01*
G01X-1245003Y528890D02*
X-1244216D01*
G01X-1259412Y528748D02*
X-1258920D01*
G01X-1251302Y528586D02*
X-1252090D01*
G01X-1245397Y528574D02*
X-1250909D01*
G01X-1258920Y528215D02*
X-1259412D01*
G01Y528197D02*
X-1258231D01*
G01X-1236893D02*
X-1238074D01*
G01X-1256952Y528015D02*
X-1239353D01*
G01X-1245003Y527906D02*
X-1244216D01*
G01X-1257641Y527865D02*
X-1258428D01*
G01X-1237877D02*
X-1238664D01*
G01X-1252090Y527633D02*
X-1256885D01*
G01X-1239420D02*
X-1244216D01*
G01X-1245003Y527628D02*
X-1244216D01*
G01Y527610D02*
X-1245003D01*
G01X-1258231Y527602D02*
X-1259412D01*
G01Y527530D02*
X-1258231D01*
G01X-1244216Y527523D02*
X-1245200D01*
G01X-1258231Y527471D02*
X-1259412D01*
G01X-1237267Y527292D02*
X-1236893D01*
G01X-1257641Y527239D02*
X-1258428D01*
G01X-1237877D02*
X-1238664D01*
G01X-1244216Y527007D02*
X-1239420D01*
G01X-1256885D02*
X-1252090D01*
G01X-1258231Y526787D02*
X-1259412D01*
G01X-1258231Y526716D02*
X-1259412D01*
G01X-1237267Y526610D02*
X-1236893D01*
G01X-1259412Y525841D02*
X-1258231D01*
G01X-1244216Y525338D02*
X-1236893D01*
G01X-1252090D02*
X-1259412D01*
G01X-1236893Y525141D02*
X-1238074D01*
G01X-1236893Y525074D02*
X-1238074D01*
G01X-1247168Y524964D02*
X-1256558D01*
G01X-1239747D02*
X-1245987D01*
G01X-1238271D02*
X-1239353D01*
G01X-1258133Y524865D02*
X-1238172D01*
G01X-1258231Y524354D02*
X-1259412D01*
G01X-1238074Y524312D02*
X-1236893D01*
G01Y523551D02*
X-1238074D01*
G01Y522794D02*
X-1236893D01*
G01X-1239846Y522790D02*
X-1239747D01*
G01X-1239353D02*
X-1237877D01*
G01X-1256558D02*
X-1256460D01*
G01X-1258920D02*
X-1256952D01*
G01X-1236893Y522033D02*
X-1238074D01*
G01X-1258231Y521991D02*
X-1259412D01*
G01X-1241223Y521716D02*
X-1240042D01*
G01X-1256263D02*
X-1255082D01*
G01X-1255180Y521617D02*
X-1256558D01*
G01X-1239747D02*
X-1241125D01*
G01X-1244609Y521519D02*
X-1251696D01*
G01X-1258231Y521322D02*
X-1259412D01*
G01X-1236893D02*
X-1238074D01*
G01Y521271D02*
X-1236893D01*
G01Y521204D02*
X-1238074D01*
G01X-1258133Y521125D02*
X-1258920D01*
G01X-1237385D02*
X-1238172D01*
G01X-1251696Y520535D02*
X-1244609D01*
G01X-1258231Y520504D02*
X-1259412D01*
G01X-1247031Y520338D02*
X-1254117D01*
G01X-1256952Y520239D02*
X-1258035D01*
G01X-1238271D02*
X-1239353D01*
G01X-1248358Y520023D02*
X-1252790D01*
G01X-1258231Y519853D02*
X-1259412D01*
G01X-1236893D02*
X-1238074D01*
G01X-1253428Y519629D02*
X-1247720D01*
G01X-1258231D02*
X-1259412D01*
G01Y519558D02*
X-1258231D01*
G01X-1241125Y519255D02*
X-1238271D01*
G01X-1258035D02*
X-1255180D01*
G01X-1258231Y519171D02*
X-1259412D01*
G01X-1236893D02*
X-1238074D01*
G01X-1255082Y519157D02*
X-1257542D01*
G01X-1238763D02*
X-1241223D01*
G01X-1259412Y518874D02*
X-1258231D01*
G01Y518815D02*
X-1259412D01*
G01X-1258231Y518743D02*
X-1259412D01*
G01X-1258231Y517661D02*
X-1258428D01*
G01X-1259412D02*
X-1259609D01*
G01X-1236696D02*
X-1236893D01*
G01X-1237877D02*
X-1238074D01*
G01X-1254905Y517385D02*
X-1258133D01*
G01X-1238172D02*
X-1254511D01*
G01X-1252090Y517267D02*
X-1236893D01*
G01X-1259412D02*
X-1254491D01*
G01Y515692D02*
X-1254885D01*
G01X-1251145D02*
X-1254412D01*
G01X-1258231Y515023D02*
X-1259412D01*
G01X-1236893D02*
X-1238074D01*
G01X-1258231Y514236D02*
X-1259412D01*
G01X-1238172D02*
X-1258133D01*
G01X-1236893D02*
X-1238074D01*
G01X-1251460Y513724D02*
X-1251145D01*
G01X-1254885D02*
X-1251538D01*
G01X-1239353Y513054D02*
X-1256952D01*
G01X-1242286Y512938D02*
X-1243074D01*
G01X-1240909Y512267D02*
X-1248153D01*
G01Y511982D02*
X-1248349D01*
G01X-1242286Y511927D02*
X-1243074D01*
G01X-1242286Y511882D02*
X-1243074D01*
G01X-1242286Y511586D02*
X-1243074D01*
G01X-1242286Y511534D02*
X-1243074D01*
G01X-1242286Y511086D02*
X-1243074D01*
G01X-1248153Y510102D02*
X-1248349D01*
G01X-1251538Y508212D02*
X-1254885D01*
G01X-1251145D02*
X-1251460D01*
G01X-1258133Y507739D02*
X-1238172D01*
G01X-1254412Y506243D02*
X-1251145D01*
G01X-1254885D02*
X-1254491D01*
G01X-1248950Y504275D02*
X-1246174D01*
G01X-1250712Y503015D02*
X-1257346D01*
G01X-1238960D02*
X-1243231D01*
G01X-1248950Y502348D02*
X-1246174D01*
G01X-1248950Y502102D02*
X-1246174D01*
G01X-1242050Y501834D02*
X-1240141D01*
G01X-1256164D02*
X-1251893D01*
G01X-1238074Y501125D02*
X-1236893D01*
G01X-1259412D02*
X-1258231D01*
G01X-1249914Y500995D02*
X-1245210D01*
G01X-1249908Y500697D02*
X-1245216D01*
G01X-1258231Y500066D02*
X-1259412D01*
G01X-1236893D02*
X-1238074D01*
G01X-1250104Y499960D02*
X-1245020D01*
G01X-1258231Y499822D02*
X-1259412D01*
G01X-1236893D02*
X-1238074D01*
G01X-1250422Y498343D02*
X-1244702D01*
G01X-1250224Y498110D02*
X-1244901D01*
G01X-1246399Y500697D02*
X-1246204Y500593D01*
G01X-1250229Y498112D02*
X-1250419Y498172D01*
G01X-1249241Y498149D02*
X-1249103Y498122D01*
G01D02*
X-1249033Y498109D01*
G01X-1248153Y494183D02*
X-1248349Y494188D01*
G01X-1236893Y495771D02*
X-1238074D01*
G01X-1235550Y569781D02*
X-1235515Y569595D01*
G01X-1235651Y569956D02*
X-1235550Y569781D01*
G01X-1235814Y570118D02*
X-1235651Y569956D01*
G01X-1236034Y570259D02*
X-1235814Y570118D01*
G01X-1236306Y570377D02*
X-1236034Y570259D01*
G01X-1236611Y570463D02*
X-1236306Y570377D01*
G01X-1236942Y570516D02*
X-1236611Y570463D01*
G01X-1237286Y570534D02*
X-1236942Y570516D01*
G01X-1239355Y570936D02*
X-1239556Y571105D01*
G01X-1239129Y570794D02*
X-1239355Y570936D01*
G01X-1238887Y570683D02*
X-1239129Y570794D01*
G01X-1238623Y570600D02*
X-1238887Y570683D01*
G01X-1238348Y570550D02*
X-1238623Y570600D01*
G01X-1238074Y570534D02*
X-1238348Y570550D01*
G01X-1252612Y570867D02*
X-1252483Y570945D01*
G01X-1252720Y570767D02*
X-1252612Y570867D01*
G01X-1252802Y570652D02*
X-1252720Y570767D01*
G01X-1252854Y570526D02*
X-1252802Y570652D01*
G01X-1252876Y570393D02*
X-1252854Y570526D01*
G01X-1252866Y570258D02*
X-1252876Y570393D01*
G01X-1252826Y570130D02*
X-1252866Y570258D01*
G01X-1252754Y570009D02*
X-1252826Y570130D01*
G01X-1252656Y569903D02*
X-1252754Y570009D01*
G01X-1252537Y569818D02*
X-1252656Y569903D01*
G01X-1252397Y569753D02*
X-1252537Y569818D01*
G01X-1252245Y569713D02*
X-1252397Y569753D01*
G01X-1252090Y569699D02*
X-1252245Y569713D01*
G01X-1256615Y570631D02*
X-1256749Y570479D01*
G01X-1256518Y570770D02*
X-1256615Y570631D01*
G01X-1256451Y570896D02*
X-1256518Y570770D01*
G01X-1256412Y571012D02*
X-1256451Y570896D01*
G01X-1256398Y571116D02*
X-1256412Y571012D01*
G01X-1256409Y571208D02*
X-1256398Y571116D01*
G01X-1256447Y571287D02*
X-1256409Y571208D01*
G01X-1256514Y571348D02*
X-1256447Y571287D01*
G01X-1256613Y571389D02*
X-1256514Y571348D01*
G01X-1256749Y571405D02*
X-1256613Y571389D01*
G01X-1256522Y571558D02*
X-1256749Y571105D01*
G01X-1256410Y571969D02*
X-1256522Y571558D01*
G01X-1256415Y572300D02*
X-1256410Y571969D01*
G01X-1256528Y572509D02*
X-1256415Y572300D01*
G01X-1256749Y572586D02*
X-1256528Y572509D01*
G01X-1244010Y570448D02*
X-1244042Y570479D01*
G01X-1243975Y570418D02*
X-1244010Y570448D01*
G01X-1243939Y570389D02*
X-1243975Y570418D01*
G01X-1243902Y570365D02*
X-1243939Y570389D01*
G01X-1243862Y570340D02*
X-1243902Y570365D01*
G01X-1243822Y570320D02*
X-1243862Y570340D01*
G01X-1244057Y569713D02*
X-1244216Y569699D01*
G01X-1243905Y569753D02*
X-1244057Y569713D01*
G01X-1243766Y569819D02*
X-1243905Y569753D01*
G01X-1243647Y569905D02*
X-1243766Y569819D01*
G01X-1243549Y570011D02*
X-1243647Y569905D01*
G01X-1243479Y570132D02*
X-1243549Y570011D01*
G01X-1243438Y570260D02*
X-1243479Y570132D01*
G01X-1243429Y570395D02*
X-1243438Y570260D01*
G01X-1243452Y570529D02*
X-1243429Y570395D01*
G01X-1243504Y570654D02*
X-1243452Y570529D01*
G01X-1243587Y570769D02*
X-1243504Y570654D01*
G01X-1243695Y570868D02*
X-1243587Y570769D01*
G01X-1243822Y570945D02*
X-1243695Y570868D01*
G01X-1238356Y569926D02*
X-1238074Y569908D01*
G01X-1238631Y569977D02*
X-1238356Y569926D01*
G01X-1238889Y570058D02*
X-1238631Y569977D01*
G01X-1239136Y570172D02*
X-1238889Y570058D01*
G01X-1239362Y570315D02*
X-1239136Y570172D01*
G01X-1239556Y570479D02*
X-1239362Y570315D01*
G01X-1243864Y570967D02*
X-1243822Y570945D01*
G01X-1243904Y570992D02*
X-1243864Y570967D01*
G01X-1243942Y571018D02*
X-1243904Y570992D01*
G01X-1243977Y571045D02*
X-1243942Y571018D01*
G01X-1244011Y571075D02*
X-1243977Y571045D01*
G01X-1244042Y571105D02*
X-1244011Y571075D01*
G01X-1243693Y570241D02*
X-1243822Y570320D01*
G01X-1243585Y570141D02*
X-1243693Y570241D01*
G01X-1243503Y570026D02*
X-1243585Y570141D01*
G01X-1243451Y569901D02*
X-1243503Y570026D01*
G01X-1243429Y569767D02*
X-1243451Y569901D01*
G01X-1243439Y569632D02*
X-1243429Y569767D01*
G01X-1243480Y569504D02*
X-1243439Y569632D01*
G01X-1243551Y569383D02*
X-1243480Y569504D01*
G01X-1243649Y569277D02*
X-1243551Y569383D01*
G01X-1243768Y569192D02*
X-1243649Y569277D01*
G01X-1243908Y569127D02*
X-1243768Y569192D01*
G01X-1244060Y569087D02*
X-1243908Y569127D01*
G01X-1244216Y569074D02*
X-1244060Y569087D01*
G01X-1256950Y570310D02*
X-1256749Y570479D01*
G01X-1257177Y570168D02*
X-1256950Y570310D01*
G01X-1257418Y570057D02*
X-1257177Y570168D01*
G01X-1257682Y569975D02*
X-1257418Y570057D01*
G01X-1257957Y569924D02*
X-1257682Y569975D01*
G01X-1258231Y569908D02*
X-1257957Y569924D01*
G01X-1259598Y569657D02*
X-1259609Y569595D01*
G01X-1259564Y569716D02*
X-1259598Y569657D01*
G01X-1259510Y569769D02*
X-1259564Y569716D01*
G01X-1259436Y569817D02*
X-1259510Y569769D01*
G01X-1259346Y569856D02*
X-1259436Y569817D01*
G01X-1259244Y569885D02*
X-1259346Y569856D01*
G01X-1259133Y569902D02*
X-1259244Y569885D01*
G01X-1259019Y569908D02*
X-1259133Y569902D01*
G01X-1239690Y571396D02*
X-1239556Y571405D01*
G01X-1239788Y571371D02*
X-1239690Y571396D01*
G01X-1239854Y571329D02*
X-1239788Y571371D01*
G01X-1239894Y571272D02*
X-1239854Y571329D01*
G01X-1239908Y571197D02*
X-1239894Y571272D01*
G01X-1239896Y571102D02*
X-1239908Y571197D01*
G01X-1239858Y570986D02*
X-1239896Y571102D01*
G01X-1239791Y570845D02*
X-1239858Y570986D01*
G01X-1239692Y570677D02*
X-1239791Y570845D01*
G01X-1239556Y570479D02*
X-1239692Y570677D01*
G01X-1244184Y570728D02*
X-1244216Y570780D01*
G01X-1244156Y570682D02*
X-1244184Y570728D01*
G01X-1244128Y570635D02*
X-1244156Y570682D01*
G01X-1244097Y570580D02*
X-1244128Y570635D01*
G01X-1244069Y570530D02*
X-1244097Y570580D01*
G01X-1244042Y570479D02*
X-1244069Y570530D01*
G01X-1236696Y566444D02*
X-1236475Y565903D01*
G01X-1239783Y572534D02*
X-1239556Y572586D01*
G01X-1239895Y572366D02*
X-1239783Y572534D01*
G01X-1239890Y572065D02*
X-1239895Y572366D01*
G01X-1239777Y571650D02*
X-1239890Y572065D01*
G01X-1239556Y571105D02*
X-1239777Y571650D01*
G01X-1244071Y571192D02*
X-1244042Y571105D01*
G01X-1244101Y571277D02*
X-1244071Y571192D01*
G01X-1244130Y571360D02*
X-1244101Y571277D01*
G01X-1244160Y571440D02*
X-1244130Y571360D01*
G01X-1244189Y571518D02*
X-1244160Y571440D01*
G01X-1244216Y571586D02*
X-1244189Y571518D01*
G01X-1259193Y570282D02*
X-1259412Y570481D01*
G01X-1259061Y570008D02*
X-1259193Y570282D01*
G01X-1259019Y569688D02*
X-1259061Y570008D01*
G01X-1237170Y569902D02*
X-1237286Y569908D01*
G01X-1237060Y569884D02*
X-1237170Y569902D01*
G01X-1236958Y569855D02*
X-1237060Y569884D01*
G01X-1236869Y569817D02*
X-1236958Y569855D01*
G01X-1236795Y569768D02*
X-1236869Y569817D01*
G01X-1236740Y569715D02*
X-1236795Y569768D01*
G01X-1236707Y569656D02*
X-1236740Y569715D01*
G01X-1236696Y569595D02*
X-1236707Y569656D01*
G01X-1237854Y570282D02*
X-1238074Y570481D01*
G01X-1237722Y570008D02*
X-1237854Y570282D01*
G01X-1237680Y569688D02*
X-1237722Y570008D01*
G01X-1259830Y565904D02*
X-1259609Y566444D01*
G01X-1259369Y570516D02*
X-1259019Y570534D01*
G01X-1259700Y570462D02*
X-1259369Y570516D01*
G01X-1260004Y570375D02*
X-1259700Y570462D01*
G01X-1260272Y570259D02*
X-1260004Y570375D01*
G01X-1260494Y570115D02*
X-1260272Y570259D01*
G01X-1260657Y569953D02*
X-1260494Y570115D01*
G01X-1260757Y569778D02*
X-1260657Y569953D01*
G01X-1260790Y569595D02*
X-1260757Y569778D01*
G01X-1252119Y571509D02*
X-1252090Y571586D01*
G01X-1252149Y571430D02*
X-1252119Y571509D01*
G01X-1252178Y571350D02*
X-1252149Y571430D01*
G01X-1252208Y571267D02*
X-1252178Y571350D01*
G01X-1252237Y571182D02*
X-1252208Y571267D01*
G01X-1252264Y571105D02*
X-1252237Y571182D01*
G01X-1252232Y570538D02*
X-1252264Y570479D01*
G01X-1252204Y570587D02*
X-1252232Y570538D01*
G01X-1252176Y570636D02*
X-1252204Y570587D01*
G01X-1252145Y570689D02*
X-1252176Y570636D01*
G01X-1252117Y570735D02*
X-1252145Y570689D01*
G01X-1252090Y570780D02*
X-1252117Y570735D01*
G01X-1252442Y570341D02*
X-1252483Y570320D01*
G01X-1252401Y570366D02*
X-1252442Y570341D01*
G01X-1252363Y570392D02*
X-1252401Y570366D01*
G01X-1252328Y570419D02*
X-1252363Y570392D01*
G01X-1252294Y570449D02*
X-1252328Y570419D01*
G01X-1252264Y570479D02*
X-1252294Y570449D01*
G01X-1258585Y570002D02*
X-1258625Y569688D01*
G01X-1258454Y570278D02*
X-1258585Y570002D01*
G01X-1258231Y570481D02*
X-1258454Y570278D01*
G01X-1237246Y570002D02*
X-1237286Y569688D01*
G01X-1237116Y570278D02*
X-1237246Y570002D01*
G01X-1236893Y570481D02*
X-1237116Y570278D01*
G01X-1257949Y570551D02*
X-1258231Y570534D01*
G01X-1257674Y570602D02*
X-1257949Y570551D01*
G01X-1257416Y570684D02*
X-1257674Y570602D01*
G01X-1257169Y570798D02*
X-1257416Y570684D01*
G01X-1256944Y570941D02*
X-1257169Y570798D01*
G01X-1256749Y571105D02*
X-1256944Y570941D01*
G01X-1252248Y569087D02*
X-1252090Y569074D01*
G01X-1252400Y569128D02*
X-1252248Y569087D01*
G01X-1252539Y569193D02*
X-1252400Y569128D01*
G01X-1252658Y569279D02*
X-1252539Y569193D01*
G01X-1252756Y569385D02*
X-1252658Y569279D01*
G01X-1252827Y569506D02*
X-1252756Y569385D01*
G01X-1252867Y569635D02*
X-1252827Y569506D01*
G01X-1252876Y569769D02*
X-1252867Y569635D01*
G01X-1252854Y569903D02*
X-1252876Y569769D01*
G01X-1252801Y570028D02*
X-1252854Y569903D01*
G01X-1252718Y570143D02*
X-1252801Y570028D01*
G01X-1252610Y570242D02*
X-1252718Y570143D01*
G01X-1252483Y570320D02*
X-1252610Y570242D01*
G01X-1252296Y571074D02*
X-1252264Y571105D01*
G01X-1252330Y571043D02*
X-1252296Y571074D01*
G01X-1252367Y571015D02*
X-1252330Y571043D01*
G01X-1252403Y570990D02*
X-1252367Y571015D01*
G01X-1252444Y570966D02*
X-1252403Y570990D01*
G01X-1252483Y570945D02*
X-1252444Y570966D01*
G01X-1282601Y631047D02*
G03I-6497J0D01*
G01X-1236696Y570814D02*
G03X-1237286Y571405I-591J0D01*
G01X-1235515Y570814D02*
G03X-1237286Y572586I-1772J0D01*
G01X-1259019Y571405D02*
G03X-1259609Y570814I0J-590D01*
G01X-1259019Y572586D02*
G03X-1260790Y570814I0J-1771D01*
G01X-1253258Y626320D02*
X-1253012Y626404D01*
G01X-1254324Y626069D02*
X-1254570Y625985D01*
G01Y626320D02*
X-1254324Y626404D01*
G01X-1256949Y626320D02*
X-1256702Y626404D01*
G01X-1258015Y626069D02*
X-1258261Y625985D01*
G01Y626320D02*
X-1258015Y626404D01*
G01X-1253094Y626069D02*
X-1253258Y625985D01*
G01X-1256785Y626069D02*
X-1256949Y625985D01*
G01X-1260475Y623808D02*
X-1260065Y624059D01*
G01X-1261460Y627577D02*
X-1261870Y627326D01*
G01X-1260557Y624226D02*
X-1260311Y624394D01*
G01X-1261378Y627158D02*
X-1261624Y626991D01*
G01X-1253258Y625985D02*
X-1253340Y625902D01*
G01X-1253504Y626069D02*
X-1253258Y626320D01*
G01X-1254570Y625985D02*
X-1254734Y625818D01*
G01Y626153D02*
X-1254570Y626320D01*
G01X-1256949Y625985D02*
X-1257031Y625902D01*
G01X-1257195Y626069D02*
X-1256949Y626320D01*
G01X-1260065Y624059D02*
X-1259819Y624310D01*
G01X-1258261Y625985D02*
X-1258425Y625818D01*
G01Y626153D02*
X-1258261Y626320D01*
G01X-1261870Y627326D02*
X-1262116Y627074D01*
G01X-1260311Y624394D02*
X-1259983Y624896D01*
G01X-1261624Y626991D02*
X-1261952Y626488D01*
G01X-1253340Y625902D02*
X-1253422Y625734D01*
G01X-1257031Y625902D02*
X-1257113Y625734D01*
G01X-1259819Y624310D02*
X-1259655Y624645D01*
G01X-1262116Y627074D02*
X-1262280Y626739D01*
G01X-1259655Y624645D02*
X-1259573Y624896D01*
G01X-1262280Y626739D02*
X-1262362Y626488D01*
G01X-1259573Y624896D02*
X-1259491Y625315D01*
G01X-1262362Y626488D02*
X-1262444Y626069D01*
G01X-1259983Y624896D02*
X-1259901Y625399D01*
G01X-1261952Y626488D02*
X-1262034Y625985D01*
G01X-1237267Y569551D02*
Y568842D01*
G01X-1237680Y571405D02*
Y572586D01*
G01X-1238193D02*
Y571405D01*
G01X-1238664Y572586D02*
Y571405D01*
G01X-1238704D02*
Y572586D01*
G01X-1239124D02*
Y571405D01*
G01X-1239556D02*
Y572586D01*
G01Y571105D02*
Y570479D01*
G01X-1239747Y566499D02*
Y570436D01*
G01X-1239806Y571405D02*
Y572586D01*
G01X-1239908Y572246D02*
Y571192D01*
G01X-1242109Y570436D02*
Y566499D01*
G01X-1243428Y569741D02*
Y570367D01*
G01X-1243822Y570945D02*
Y570320D01*
G01X-1244042Y570479D02*
Y571105D01*
G01X-1244216Y569074D02*
Y569699D01*
G01Y572586D02*
Y570780D01*
G01X-1245003Y571405D02*
Y572586D01*
G01X-1245397D02*
Y571405D01*
G01X-1245790Y649747D02*
Y612346D01*
G01X-1250909Y571405D02*
Y572586D01*
G01X-1251302D02*
Y571405D01*
G01X-1252090Y572586D02*
Y570780D01*
G01Y569699D02*
Y569074D01*
G01X-1252109Y625734D02*
Y623724D01*
G01X-1252264Y571105D02*
Y570479D01*
G01X-1252483Y570945D02*
Y570320D01*
G01X-1252519Y623724D02*
Y625734D01*
G01X-1252877Y569741D02*
Y570367D01*
G01X-1253422Y625734D02*
Y623724D01*
G01X-1253832D02*
Y625734D01*
G01X-1254196Y566499D02*
Y570436D01*
G01X-1254734Y625818D02*
Y623724D01*
G01Y626404D02*
Y626153D01*
G01X-1255144Y623724D02*
Y626404D01*
G01X-1255475Y570436D02*
Y569551D01*
G01X-1255800Y625734D02*
Y623724D01*
G01X-1256210D02*
Y625734D01*
G01X-1256398Y571121D02*
Y572131D01*
G01X-1256499Y572586D02*
Y571405D01*
G01X-1256558Y570436D02*
Y566499D01*
G01X-1256749Y570479D02*
Y571105D01*
G01Y572586D02*
Y571405D01*
G01X-1257113Y625734D02*
Y623724D01*
G01X-1257181Y571405D02*
Y572586D01*
G01X-1257523Y623724D02*
Y625734D01*
G01X-1257601Y571405D02*
Y572586D01*
G01X-1257641D02*
Y571405D01*
G01X-1258112D02*
Y572586D01*
G01X-1258425Y625818D02*
Y623724D01*
G01Y626404D02*
Y626153D01*
G01X-1258625Y572586D02*
Y571405D01*
G01X-1258835Y623724D02*
Y626404D01*
G01X-1258920Y569551D02*
Y567267D01*
G01X-1259491Y625315D02*
Y626069D01*
G01X-1259901Y625399D02*
Y625985D01*
G01X-1260751Y612346D02*
Y595614D01*
G01X-1262034Y625985D02*
Y625399D01*
G01X-1262444Y626069D02*
Y625315D01*
G01X-1263100Y625399D02*
Y625064D01*
G01Y626404D02*
Y626069D01*
G01X-1264412D02*
Y626404D01*
G01Y625064D02*
Y625399D01*
G01X-1265069Y627661D02*
Y623724D01*
G01X-1265561D02*
Y625567D01*
G01Y626069D02*
Y627661D01*
G01X-1267857Y625567D02*
Y623724D01*
G01Y627661D02*
Y626069D01*
G01X-1268349Y623724D02*
Y627661D01*
G01X-1259901Y625985D02*
X-1259983Y626488D01*
G01X-1262034Y625399D02*
X-1261952Y624896D01*
G01X-1259491Y626069D02*
X-1259573Y626488D01*
G01X-1262444Y625315D02*
X-1262362Y624896D01*
G01X-1259573Y626488D02*
X-1259655Y626739D01*
G01X-1262362Y624896D02*
X-1262280Y624645D01*
G01X-1252273Y626153D02*
X-1252109Y625734D01*
G01X-1255964Y626153D02*
X-1255800Y625734D01*
G01X-1252519D02*
X-1252601Y625902D01*
G01X-1253832Y625734D02*
X-1253914Y625902D01*
G01X-1256210Y625734D02*
X-1256292Y625902D01*
G01X-1257523Y625734D02*
X-1257605Y625902D01*
G01X-1259655Y626739D02*
X-1259819Y627074D01*
G01X-1262280Y624645D02*
X-1262116Y624310D01*
G01X-1259983Y626488D02*
X-1260311Y626991D01*
G01X-1261952Y624896D02*
X-1261624Y624394D01*
G01X-1265561Y627661D02*
X-1265069D01*
G01X-1268349D02*
X-1267857D01*
G01X-1253012Y626404D02*
X-1252683D01*
G01X-1254324D02*
X-1253996D01*
G01X-1255144D02*
X-1254734D01*
G01X-1256702D02*
X-1256374D01*
G01X-1258015D02*
X-1257687D01*
G01X-1258835D02*
X-1258425D01*
G01X-1264412D02*
X-1263100D01*
G01X-1267857Y626069D02*
X-1265561D01*
G01X-1263100D02*
X-1264412D01*
G01X-1257851D02*
X-1258015D01*
G01X-1256538D02*
X-1256785D01*
G01X-1254160D02*
X-1254324D01*
G01X-1252848D02*
X-1253094D01*
G01X-1265561Y625567D02*
X-1267857D01*
G01X-1264412Y625399D02*
X-1263100D01*
G01Y625064D02*
X-1264412D01*
G01X-1267857Y623724D02*
X-1268349D01*
G01X-1265069D02*
X-1265561D01*
G01X-1258425D02*
X-1258835D01*
G01X-1254734D02*
X-1255144D01*
G01X-1257113D02*
X-1257523D01*
G01X-1255800D02*
X-1256210D01*
G01X-1253422D02*
X-1253832D01*
G01X-1252109D02*
X-1252519D01*
G01X-1260968Y627661D02*
X-1261460Y627577D01*
G01X-1260968Y623724D02*
X-1260475Y623808D01*
G01X-1260968Y627242D02*
X-1261378Y627158D01*
G01X-1260968Y624143D02*
X-1260557Y624226D01*
G01X-1238271Y566526D02*
X-1238861Y567471D01*
G01X-1252437Y626320D02*
X-1252273Y626153D01*
G01X-1252601Y625902D02*
X-1252683Y625985D01*
G01X-1253750Y626320D02*
X-1253504Y626069D01*
G01X-1253914Y625902D02*
X-1253996Y625985D01*
G01X-1256128Y626320D02*
X-1255964Y626153D01*
G01X-1256292Y625902D02*
X-1256374Y625985D01*
G01X-1257441Y626320D02*
X-1257195Y626069D01*
G01X-1257605Y625902D02*
X-1257687Y625985D01*
G01X-1259819Y627074D02*
X-1260065Y627326D01*
G01X-1262116Y624310D02*
X-1261870Y624059D01*
G01X-1260311Y626991D02*
X-1260557Y627158D01*
G01X-1261624Y624394D02*
X-1261378Y624226D01*
G01X-1260065Y627326D02*
X-1260475Y627577D01*
G01X-1261870Y624059D02*
X-1261460Y623808D01*
G01X-1252683Y625985D02*
X-1252848Y626069D01*
G01X-1253996Y625985D02*
X-1254160Y626069D01*
G01X-1256374Y625985D02*
X-1256538Y626069D01*
G01X-1257687Y625985D02*
X-1257851Y626069D01*
G01X-1252683Y626404D02*
X-1252437Y626320D01*
G01X-1253996Y626404D02*
X-1253750Y626320D01*
G01X-1256374Y626404D02*
X-1256128Y626320D01*
G01X-1257687Y626404D02*
X-1257441Y626320D01*
G01X-1260557Y627158D02*
X-1260968Y627242D01*
G01X-1261378Y624226D02*
X-1260968Y624143D01*
G01X-1260475Y627577D02*
X-1260968Y627661D01*
G01X-1261460Y623808D02*
X-1260968Y623724D01*
G01X-1245790Y612346D02*
X-1289098D01*
G01X-1260751Y595614D02*
X-1274137D01*
G01X-1259019Y572586D02*
X-1237286D01*
G01X-1259019Y571405D02*
X-1237286D01*
G01X-1244042Y571105D02*
X-1239556D01*
G01X-1256749D02*
X-1252264D01*
G01X-1258231Y570614D02*
X-1259412D01*
G01X-1236893D02*
X-1238074D01*
G01Y570534D02*
X-1237286D01*
G01X-1259019D02*
X-1258231D01*
G01X-1252264Y570479D02*
X-1256749D01*
G01X-1239556D02*
X-1244042D01*
G01X-1258035Y570436D02*
X-1248349D01*
G01X-1238271D02*
X-1247956D01*
G01X-1238074Y569908D02*
X-1237286D01*
G01X-1259019D02*
X-1258231D01*
G01X-1238074Y569728D02*
X-1236893D01*
G01X-1244216Y569699D02*
X-1252090D01*
G01X-1237680Y569688D02*
X-1237286D01*
G01X-1259019D02*
X-1258625D01*
G01X-1238074Y569656D02*
X-1236893D01*
G01X-1238074Y569629D02*
X-1236893D01*
G01Y569597D02*
X-1238074D01*
G01X-1238861Y569551D02*
X-1237267D01*
G01X-1248349D02*
X-1247956D01*
G01X-1258920D02*
X-1255475D01*
G01X-1259412Y569299D02*
X-1258920D01*
G01X-1236696Y569282D02*
X-1235515D01*
G01X-1260790D02*
X-1259609D01*
G01X-1244216Y569074D02*
X-1252090D01*
G01X-1236893Y568913D02*
X-1238074D01*
G01X-1236893Y568842D02*
X-1238074D01*
G01X-1258920Y568766D02*
X-1259412D01*
G01X-1247956Y568586D02*
X-1238861D01*
G01X-1257444Y568079D02*
X-1248349D01*
G01X-1238074Y567967D02*
X-1236893D01*
G01X-1259609Y567468D02*
X-1260790D01*
G01X-1235515D02*
X-1236696D01*
G01X-1258231Y567267D02*
X-1259412D01*
G01X-1258231Y567200D02*
X-1259412D01*
G01X-1259609Y566680D02*
X-1260790D01*
G01X-1235515D02*
X-1236696D01*
G01X-1242109Y566499D02*
X-1239747D01*
G01X-1256558D02*
X-1254196D01*
G01X-1236893Y566480D02*
X-1238074D01*
G01X-1259412Y566438D02*
X-1258231D01*
G01Y565677D02*
X-1259412D01*
G01X-1291922Y657020D02*
X-1292247Y657085D01*
G01X-1291648Y656835D02*
X-1291922Y657020D01*
G01X-1291468Y656562D02*
X-1291648Y656835D01*
G01X-1291405Y656240D02*
X-1291468Y656562D01*
G01X-1291470Y655918D02*
X-1291405Y656240D01*
G01X-1291652Y655648D02*
X-1291470Y655918D01*
G01X-1291923Y655466D02*
X-1291652Y655648D01*
G01X-1292247Y655401D02*
X-1291923Y655466D01*
G01X-1286538Y659865D02*
G03X-1285751Y660653I0J787D01*
G01X-1293625Y657129D02*
G03X-1292838Y657911I0J787D01*
G01X-1292247Y657070D02*
G03Y655417I0J-826D01*
G01X-1290869Y659078D02*
G03X-1292050Y657905I0J-1181D01*
G01X-1286538Y659078D02*
G03X-1284964Y660653I0J1574D01*
G01X-1293625Y656342D02*
G03X-1292050Y657905I0J1575D01*
G01X-1290869Y659865D02*
G03X-1292838Y657911I0J-1969D01*
G01X-1282405Y653094D02*
G03X-1280436Y655062I0J1969D01*
G01X-1290229Y656243D02*
G03I-2018J0D01*
G01X-1290082D02*
G03I-2165J0D01*
G01X-1282075Y666090D02*
X-1282122Y666074D01*
G01X-1282011Y657865D02*
X-1283586Y656956D01*
G01X-1282200Y666122D02*
X-1282137Y666169D01*
G01X-1295279Y661302D02*
X-1294491Y662090D01*
G01X-1282122Y666074D02*
X-1282153Y666042D01*
G01X-1283353Y665883D02*
X-1283446Y665771D01*
G01Y665899D02*
X-1283353Y666010D01*
G01X-1282246Y666058D02*
X-1282200Y666122D01*
G01X-1282153Y666042D02*
X-1282168Y665994D01*
G01X-1282262Y666010D02*
X-1282246Y666058D01*
G01X-1281420Y707621D02*
X-1289294D01*
G01X-1281420Y706440D02*
X-1289294D01*
G01X-1281420Y704472D02*
X-1289294D01*
G01X-1281420Y703291D02*
X-1289294D01*
G01X-1281420Y701322D02*
X-1289294D01*
G01X-1281420Y700141D02*
X-1289294D01*
G01X-1281420Y698173D02*
X-1289294D01*
G01X-1282137Y666169D02*
X-1282059Y666185D01*
G01X-1260751Y868251D02*
Y649747D01*
G01X-1280436Y655062D02*
Y662444D01*
G01X-1281223Y658606D02*
Y655456D01*
G01X-1281420Y666677D02*
Y665495D01*
G01Y669826D02*
Y668645D01*
G01Y672976D02*
Y671795D01*
G01Y676125D02*
Y674944D01*
G01Y679275D02*
Y678094D01*
G01Y682425D02*
Y681243D01*
G01Y685574D02*
Y684393D01*
G01Y688724D02*
Y687543D01*
G01Y691873D02*
Y690692D01*
G01Y695023D02*
Y693842D01*
G01Y698173D02*
Y696991D01*
G01Y701322D02*
Y700141D01*
G01Y704472D02*
Y703291D01*
G01Y707621D02*
Y706440D01*
G01X-1281685Y666520D02*
Y665771D01*
G01X-1281779Y665851D02*
Y666090D01*
G01Y666185D02*
Y666520D01*
G01X-1282011Y657865D02*
Y656047D01*
G01X-1282168Y665994D02*
Y665947D01*
G01X-1282262D02*
Y666010D01*
G01X-1282387Y666520D02*
Y665771D01*
G01X-1282480D02*
Y666520D01*
G01X-1282605D02*
Y665771D01*
G01X-1282698Y665867D02*
Y666520D01*
G01X-1283135Y666408D02*
Y665771D01*
G01X-1283228D02*
Y666520D01*
G01X-1283353Y666010D02*
Y665883D01*
G01X-1283446Y666520D02*
Y665899D01*
G01X-1283540Y665771D02*
Y666520D01*
G01X-1284373Y658606D02*
Y655456D01*
G01X-1284964Y660653D02*
Y857346D01*
G01X-1285751Y660653D02*
Y857346D01*
G01X-1286538Y659078D02*
Y659865D01*
G01X-1288310Y653881D02*
Y653094D01*
G01X-1289216Y856696D02*
Y661302D01*
G01X-1289294Y666677D02*
Y665495D01*
G01Y669826D02*
Y668645D01*
G01Y672976D02*
Y671795D01*
G01Y676125D02*
Y674944D01*
G01Y679275D02*
Y678094D01*
G01Y682425D02*
Y681243D01*
G01Y685574D02*
Y684393D01*
G01Y688724D02*
Y687543D01*
G01Y691873D02*
Y690692D01*
G01Y695023D02*
Y693842D01*
G01Y698173D02*
Y696991D01*
G01Y701322D02*
Y700141D01*
G01Y704472D02*
Y703291D01*
G01Y707621D02*
Y706440D01*
G01X-1290003Y855909D02*
Y662090D01*
G01X-1281420Y696991D02*
X-1289294D01*
G01X-1281420Y695023D02*
X-1289294D01*
G01X-1281420Y693842D02*
X-1289294D01*
G01X-1281420Y691873D02*
X-1289294D01*
G01X-1281420Y690692D02*
X-1289294D01*
G01X-1281420Y688724D02*
X-1289294D01*
G01X-1281420Y687543D02*
X-1289294D01*
G01X-1281420Y685574D02*
X-1289294D01*
G01X-1281420Y684393D02*
X-1289294D01*
G01X-1281420Y682425D02*
X-1289294D01*
G01X-1281420Y681243D02*
X-1289294D01*
G01X-1281420Y679275D02*
X-1289294D01*
G01X-1281420Y678094D02*
X-1289294D01*
G01X-1281420Y676125D02*
X-1289294D01*
G01X-1281420Y674944D02*
X-1289294D01*
G01X-1281420Y672976D02*
X-1289294D01*
G01X-1281420Y671795D02*
X-1289294D01*
G01X-1281420Y669826D02*
X-1289294D01*
G01X-1281420Y668645D02*
X-1289294D01*
G01X-1281420Y666677D02*
X-1289294D01*
G01X-1283540Y666520D02*
X-1283446D01*
G01X-1282698D02*
X-1282605D01*
G01X-1283228D02*
X-1283088D01*
G01X-1282480D02*
X-1282387D01*
G01X-1281779D02*
X-1281685D01*
G01X-1282059Y666185D02*
X-1281779D01*
G01Y666090D02*
X-1282075D01*
G01Y665851D02*
X-1281779D01*
G01X-1283446Y665771D02*
X-1283540D01*
G01X-1282605D02*
X-1282745D01*
G01X-1283135D02*
X-1283228D01*
G01X-1282387D02*
X-1282480D01*
G01X-1281685D02*
X-1282059D01*
G01X-1281420Y665495D02*
X-1289294D01*
G01X-1280436Y662444D02*
X-1285751D01*
G01X-1290003Y662090D02*
X-1294491D01*
G01X-1289216Y661302D02*
X-1295279D01*
G01X-1285751Y660653D02*
X-1284964D01*
G01X-1290869Y659865D02*
X-1286538D01*
G01Y659078D02*
X-1290869D01*
G01X-1281223Y658606D02*
X-1284373D01*
G01X-1290869Y659865D02*
Y659078D01*
G01X-1292247Y654225D02*
Y655401D01*
G01Y657085D02*
Y658262D01*
G01X-1293625Y656342D02*
Y657129D01*
G01X-1294491Y855909D02*
Y662090D01*
G01X-1295200Y666677D02*
Y665495D01*
G01Y669826D02*
Y668645D01*
G01Y672976D02*
Y671795D01*
G01Y676125D02*
Y674944D01*
G01Y679275D02*
Y678094D01*
G01Y682425D02*
Y681243D01*
G01Y685574D02*
Y684393D01*
G01Y688724D02*
Y687543D01*
G01Y691873D02*
Y690692D01*
G01Y695023D02*
Y693842D01*
G01Y698173D02*
Y696991D01*
G01Y701322D02*
Y700141D01*
G01Y704472D02*
Y703291D01*
G01Y707621D02*
Y706440D01*
G01X-1295279Y661302D02*
Y856696D01*
G01X-1282168Y665947D02*
X-1282153Y665899D01*
G01X-1282246D02*
X-1282262Y665947D01*
G01X-1283088Y666520D02*
X-1282698Y665867D01*
G01X-1282745Y665771D02*
X-1283135Y666408D01*
G01X-1282200Y665835D02*
X-1282246Y665899D01*
G01X-1282153D02*
X-1282122Y665867D01*
G01D02*
X-1282075Y665851D01*
G01X-1282059Y665771D02*
X-1282137Y665787D01*
G01X-1292050Y657905D02*
X-1292838Y657911D01*
G01X-1281223Y655456D02*
X-1284373D01*
G01X-1282405Y653094D02*
X-1288310D01*
G01X-1289098Y649747D02*
X-1245790D01*
G01X-1290003Y662090D02*
X-1289216Y661302D01*
G01X-1282137Y665787D02*
X-1282200Y665835D01*
G01X-1283586Y656956D02*
X-1282011Y656047D01*
G01X-1281420Y780062D02*
X-1289294D01*
G01X-1281420Y778881D02*
X-1289294D01*
G01X-1281420Y776913D02*
X-1289294D01*
G01X-1285751Y776322D02*
X-1284964D01*
G01X-1281420Y775732D02*
X-1289294D01*
G01X-1281420Y773763D02*
X-1289294D01*
G01X-1281420Y772582D02*
X-1289294D01*
G01X-1281420Y770614D02*
X-1289294D01*
G01X-1281420Y769432D02*
X-1289294D01*
G01X-1281420Y767464D02*
X-1289294D01*
G01X-1281420Y766283D02*
X-1289294D01*
G01X-1281420Y764314D02*
X-1289294D01*
G01X-1281420Y763133D02*
X-1289294D01*
G01X-1281420Y761165D02*
X-1289294D01*
G01X-1281420Y759984D02*
X-1289294D01*
G01X-1281420Y758015D02*
X-1289294D01*
G01X-1281420Y756834D02*
X-1289294D01*
G01X-1281420Y754865D02*
X-1289294D01*
G01X-1281420Y753684D02*
X-1289294D01*
G01X-1281420Y751716D02*
X-1289294D01*
G01X-1281420Y750535D02*
X-1289294D01*
G01X-1281420Y748566D02*
X-1289294D01*
G01X-1281420Y747385D02*
X-1289294D01*
G01X-1281420Y745417D02*
X-1289294D01*
G01X-1281420Y744236D02*
X-1289294D01*
G01X-1281420Y742267D02*
X-1289294D01*
G01X-1284964Y741677D02*
X-1285751D01*
G01X-1281420Y741086D02*
X-1289294D01*
G01X-1281420Y739117D02*
X-1289294D01*
G01X-1281420Y737936D02*
X-1289294D01*
G01X-1281420Y735968D02*
X-1289294D01*
G01X-1284964Y735377D02*
X-1285751D01*
G01X-1281420Y734787D02*
X-1289294D01*
G01X-1281420Y732818D02*
X-1289294D01*
G01X-1281420Y731637D02*
X-1289294D01*
G01X-1281420Y729669D02*
X-1289294D01*
G01X-1281420Y728488D02*
X-1289294D01*
G01X-1281420Y726519D02*
X-1289294D01*
G01X-1284964Y725928D02*
X-1285751D01*
G01X-1281420Y725338D02*
X-1289294D01*
G01X-1281420Y723369D02*
X-1289294D01*
G01X-1281420Y722188D02*
X-1289294D01*
G01X-1281420Y720220D02*
X-1289294D01*
G01X-1284964Y719629D02*
X-1285751D01*
G01X-1281420Y719039D02*
X-1289294D01*
G01X-1281420Y717070D02*
X-1289294D01*
G01X-1281420Y715889D02*
X-1289294D01*
G01X-1281420Y713921D02*
X-1289294D01*
G01X-1281420Y712739D02*
X-1289294D01*
G01X-1281420Y710771D02*
X-1289294D01*
G01X-1281420Y709590D02*
X-1289294D01*
G01X-1281420Y710771D02*
Y709590D01*
G01Y713921D02*
Y712739D01*
G01Y717070D02*
Y715889D01*
G01Y720220D02*
Y719039D01*
G01Y723369D02*
Y722188D01*
G01Y726519D02*
Y725338D01*
G01Y729669D02*
Y728488D01*
G01Y732818D02*
Y731637D01*
G01Y735968D02*
Y734787D01*
G01Y739117D02*
Y737936D01*
G01Y742267D02*
Y741086D01*
G01Y745417D02*
Y744236D01*
G01Y748566D02*
Y747385D01*
G01Y751716D02*
Y750535D01*
G01Y754865D02*
Y753684D01*
G01Y758015D02*
Y756834D01*
G01Y761165D02*
Y759984D01*
G01Y764314D02*
Y763133D01*
G01Y767464D02*
Y766283D01*
G01Y770614D02*
Y769432D01*
G01Y773763D02*
Y772582D01*
G01Y776913D02*
Y775732D01*
G01Y780062D02*
Y778881D01*
G01X-1289294Y710771D02*
Y709590D01*
G01Y713921D02*
Y712739D01*
G01Y717070D02*
Y715889D01*
G01Y720220D02*
Y719039D01*
G01Y723369D02*
Y722188D01*
G01Y726519D02*
Y725338D01*
G01Y729669D02*
Y728488D01*
G01Y732818D02*
Y731637D01*
G01Y735968D02*
Y734787D01*
G01Y739117D02*
Y737936D01*
G01Y742267D02*
Y741086D01*
G01Y745417D02*
Y744236D01*
G01Y748566D02*
Y747385D01*
G01Y751716D02*
Y750535D01*
G01Y754865D02*
Y753684D01*
G01Y758015D02*
Y756834D01*
G01Y761165D02*
Y759984D01*
G01Y764314D02*
Y763133D01*
G01Y767464D02*
Y766283D01*
G01Y770614D02*
Y769432D01*
G01Y773763D02*
Y772582D01*
G01Y776913D02*
Y775732D01*
G01Y780062D02*
Y778881D01*
G01X-1295200Y710771D02*
Y709590D01*
G01Y713921D02*
Y712739D01*
G01Y717070D02*
Y715889D01*
G01Y720220D02*
Y719039D01*
G01Y723369D02*
Y722188D01*
G01Y726519D02*
Y725338D01*
G01Y729669D02*
Y728488D01*
G01Y732818D02*
Y731637D01*
G01Y735968D02*
Y734787D01*
G01Y739117D02*
Y737936D01*
G01Y742267D02*
Y741086D01*
G01Y745417D02*
Y744236D01*
G01Y748566D02*
Y747385D01*
G01Y751716D02*
Y750535D01*
G01Y754865D02*
Y753684D01*
G01Y758015D02*
Y756834D01*
G01Y761165D02*
Y759984D01*
G01Y764314D02*
Y763133D01*
G01Y767464D02*
Y766283D01*
G01Y770614D02*
Y769432D01*
G01Y773763D02*
Y772582D01*
G01Y776913D02*
Y775732D01*
G01Y780062D02*
Y778881D01*
G01X-1281420Y852503D02*
X-1289294D01*
G01X-1281420Y851322D02*
X-1289294D01*
G01X-1281420Y849354D02*
X-1289294D01*
G01X-1281420Y848173D02*
X-1289294D01*
G01X-1281420Y846204D02*
X-1289294D01*
G01X-1281420Y845023D02*
X-1289294D01*
G01X-1281420Y843054D02*
X-1289294D01*
G01X-1281420Y841873D02*
X-1289294D01*
G01X-1281420Y839905D02*
X-1289294D01*
G01X-1281420Y838724D02*
X-1289294D01*
G01X-1281420Y836755D02*
X-1289294D01*
G01X-1281420Y835574D02*
X-1289294D01*
G01X-1281420Y833606D02*
X-1289294D01*
G01X-1281420Y832425D02*
X-1289294D01*
G01X-1281420Y830456D02*
X-1289294D01*
G01X-1281420Y829275D02*
X-1289294D01*
G01X-1281420Y827306D02*
X-1289294D01*
G01X-1281420Y826125D02*
X-1289294D01*
G01X-1281420Y824157D02*
X-1289294D01*
G01X-1281420Y822976D02*
X-1289294D01*
G01X-1281420Y821007D02*
X-1289294D01*
G01X-1281420Y819826D02*
X-1289294D01*
G01X-1281420Y817858D02*
X-1289294D01*
G01X-1281420Y816677D02*
X-1289294D01*
G01X-1281420Y814708D02*
X-1289294D01*
G01X-1281420Y813527D02*
X-1289294D01*
G01X-1281420Y811558D02*
X-1289294D01*
G01X-1281420Y810377D02*
X-1289294D01*
G01X-1281420Y808409D02*
X-1289294D01*
G01X-1281420Y807228D02*
X-1289294D01*
G01X-1281420Y805259D02*
X-1289294D01*
G01X-1281420Y804078D02*
X-1289294D01*
G01X-1281420Y802110D02*
X-1289294D01*
G01X-1281420Y800928D02*
X-1289294D01*
G01X-1281420Y798960D02*
X-1289294D01*
G01X-1284964Y798369D02*
X-1285751D01*
G01X-1281420Y797779D02*
X-1289294D01*
G01X-1281420Y795810D02*
X-1289294D01*
G01X-1281420Y794629D02*
X-1289294D01*
G01X-1281420Y792661D02*
X-1289294D01*
G01X-1285751Y792070D02*
X-1284964D01*
G01X-1281420Y791480D02*
X-1289294D01*
G01X-1281420Y789511D02*
X-1289294D01*
G01X-1281420Y788330D02*
X-1289294D01*
G01X-1281420Y786362D02*
X-1289294D01*
G01X-1281420Y785180D02*
X-1289294D01*
G01X-1281420Y783212D02*
X-1289294D01*
G01X-1284964Y782621D02*
X-1285751D01*
G01X-1281420Y782031D02*
X-1289294D01*
G01X-1281420Y783212D02*
Y782031D01*
G01Y786362D02*
Y785180D01*
G01Y789511D02*
Y788330D01*
G01Y792661D02*
Y791480D01*
G01Y795810D02*
Y794629D01*
G01Y798960D02*
Y797779D01*
G01Y802110D02*
Y800928D01*
G01Y805259D02*
Y804078D01*
G01Y808409D02*
Y807228D01*
G01Y811558D02*
Y810377D01*
G01Y814708D02*
Y813527D01*
G01Y817858D02*
Y816677D01*
G01Y821007D02*
Y819826D01*
G01Y824157D02*
Y822976D01*
G01Y827306D02*
Y826125D01*
G01Y830456D02*
Y829275D01*
G01Y833606D02*
Y832425D01*
G01Y836755D02*
Y835574D01*
G01Y839905D02*
Y838724D01*
G01Y843054D02*
Y841873D01*
G01Y846204D02*
Y845023D01*
G01Y849354D02*
Y848173D01*
G01Y852503D02*
Y851322D01*
G01X-1289294Y783212D02*
Y782031D01*
G01Y786362D02*
Y785180D01*
G01Y789511D02*
Y788330D01*
G01Y792661D02*
Y791480D01*
G01Y795810D02*
Y794629D01*
G01Y798960D02*
Y797779D01*
G01Y802110D02*
Y800928D01*
G01Y805259D02*
Y804078D01*
G01Y808409D02*
Y807228D01*
G01Y811558D02*
Y810377D01*
G01Y814708D02*
Y813527D01*
G01Y817858D02*
Y816677D01*
G01Y821007D02*
Y819826D01*
G01Y824157D02*
Y822976D01*
G01Y827306D02*
Y826125D01*
G01Y830456D02*
Y829275D01*
G01Y833606D02*
Y832425D01*
G01Y836755D02*
Y835574D01*
G01Y839905D02*
Y838724D01*
G01Y843054D02*
Y841873D01*
G01Y846204D02*
Y845023D01*
G01Y849354D02*
Y848173D01*
G01Y852503D02*
Y851322D01*
G01X-1295200Y783212D02*
Y782031D01*
G01Y786362D02*
Y785180D01*
G01Y789511D02*
Y788330D01*
G01Y792661D02*
Y791480D01*
G01Y795810D02*
Y794629D01*
G01Y798960D02*
Y797779D01*
G01Y802110D02*
Y800928D01*
G01Y805259D02*
Y804078D01*
G01Y808409D02*
Y807228D01*
G01Y811558D02*
Y810377D01*
G01Y814708D02*
Y813527D01*
G01Y817858D02*
Y816677D01*
G01Y821007D02*
Y819826D01*
G01Y824157D02*
Y822976D01*
G01Y827306D02*
Y826125D01*
G01Y830456D02*
Y829275D01*
G01Y833606D02*
Y832425D01*
G01Y836755D02*
Y835574D01*
G01Y839905D02*
Y838724D01*
G01Y843054D02*
Y841873D01*
G01Y846204D02*
Y845023D01*
G01Y849354D02*
Y848173D01*
G01Y852503D02*
Y851322D01*
G01X-1291657Y886952D02*
X-1178525D01*
G01X-1285751Y857346D02*
G03X-1286538Y858133I-787J0D01*
G01X-1292838Y860088D02*
G03X-1293625Y860869I-787J-6D01*
G01X-1292050Y860093D02*
G03X-1290869Y858921I1181J9D01*
G01X-1291030Y861755D02*
G03I-1217J0D01*
G01X-1290869D02*
G03I-1378J0D01*
G01X-1284964Y857346D02*
G03X-1286538Y858921I-1575J0D01*
G01X-1292050Y860093D02*
G03X-1293625Y861657I-1575J-11D01*
G01X-1292838Y860088D02*
G03X-1290869Y858133I1969J14D01*
G01X-1290279Y861755D02*
G03I-1968J0D01*
G01X-1280436Y862936D02*
G03X-1282405Y864905I-1969J0D01*
G01X-1282208Y880259D02*
G03Y893645I0J6693D01*
G01X-1288901Y905653D02*
X-1233192D01*
G01X-1252897Y884432D02*
X-1253389Y884349D01*
G01X-1252897Y880495D02*
X-1252405Y880579D01*
G01X-1252897Y884014D02*
X-1253307Y883930D01*
G01X-1252897Y880914D02*
X-1252487Y880998D01*
G01Y883930D02*
X-1252897Y884014D01*
G01X-1252405Y884349D02*
X-1252897Y884432D01*
G01X-1253389Y880579D02*
X-1252897Y880495D01*
G01X-1282208Y893645D02*
X-1295594D01*
G01X-1257490Y884432D02*
X-1256998D01*
G01X-1260279D02*
X-1259786D01*
G01X-1244941Y883176D02*
X-1244613D01*
G01X-1246253D02*
X-1245925D01*
G01X-1247073D02*
X-1246663D01*
G01X-1248632D02*
X-1248304D01*
G01X-1249944D02*
X-1249616D01*
G01X-1250764D02*
X-1250354D01*
G01X-1256342D02*
X-1255029D01*
G01X-1259786Y882841D02*
X-1257490D01*
G01X-1255029D02*
X-1256342D01*
G01X-1249780D02*
X-1249944D01*
G01X-1248468D02*
X-1248714D01*
G01X-1246089D02*
X-1246253D01*
G01X-1244777D02*
X-1245023D01*
G01X-1257490Y882338D02*
X-1259786D01*
G01X-1256342Y882171D02*
X-1255029D01*
G01Y881836D02*
X-1256342D01*
G01X-1259786Y880495D02*
X-1260279D01*
G01X-1256998D02*
X-1257490D01*
G01X-1249042D02*
X-1249452D01*
G01X-1247729D02*
X-1248139D01*
G01X-1250354D02*
X-1250764D01*
G01X-1245351D02*
X-1245761D01*
G01X-1246663D02*
X-1247073D01*
G01X-1244038D02*
X-1244449D01*
G01X-1282208Y880259D02*
X-1295594D01*
G01X-1233192Y868251D02*
X-1288901D01*
G01X-1282405Y864905D02*
X-1288310D01*
G01X-1286538Y858921D02*
X-1290869D01*
G01X-1286538Y858133D02*
X-1290869D01*
G01X-1292838Y860088D02*
X-1292050Y860093D01*
G01X-1251994Y884097D02*
X-1252405Y884349D01*
G01X-1244613Y882757D02*
X-1244777Y882841D01*
G01X-1245925Y882757D02*
X-1246089Y882841D01*
G01X-1248304Y882757D02*
X-1248468Y882841D01*
G01X-1249616Y882757D02*
X-1249780Y882841D01*
G01X-1244613Y883176D02*
X-1244367Y883092D01*
G01X-1245925Y883176D02*
X-1245679Y883092D01*
G01X-1248304Y883176D02*
X-1248057Y883092D01*
G01X-1249616Y883176D02*
X-1249370Y883092D01*
G01X-1253307Y880998D02*
X-1252897Y880914D01*
G01X-1284964Y857346D02*
X-1285751D01*
G01X-1295279Y856696D02*
X-1289216D01*
G01X-1290003Y855909D02*
X-1294491D01*
G01X-1280436Y855554D02*
X-1285751D01*
G01X-1244367Y883092D02*
X-1244202Y882925D01*
G01X-1244531Y882673D02*
X-1244613Y882757D01*
G01X-1245679Y883092D02*
X-1245433Y882841D01*
G01X-1245843Y882673D02*
X-1245925Y882757D01*
G01X-1248057Y883092D02*
X-1247893Y882925D01*
G01X-1248222Y882673D02*
X-1248304Y882757D01*
G01X-1249370Y883092D02*
X-1249124Y882841D01*
G01X-1249534Y882673D02*
X-1249616Y882757D01*
G01X-1251748Y883846D02*
X-1251994Y884097D01*
G01X-1254045Y881082D02*
X-1253799Y880830D01*
G01X-1252241Y883762D02*
X-1252487Y883930D01*
G01X-1253553Y881166D02*
X-1253307Y880998D01*
G01X-1253799Y880830D02*
X-1253389Y880579D01*
G01X-1245187Y883092D02*
X-1244941Y883176D01*
G01X-1246253Y882841D02*
X-1246499Y882757D01*
G01Y883092D02*
X-1246253Y883176D01*
G01X-1248878Y883092D02*
X-1248632Y883176D01*
G01X-1249944Y882841D02*
X-1250190Y882757D01*
G01Y883092D02*
X-1249944Y883176D01*
G01X-1251830Y882757D02*
X-1251912Y883260D01*
G01X-1253963Y882171D02*
X-1253881Y881668D01*
G01X-1251420Y882841D02*
X-1251502Y883260D01*
G01X-1254373Y882087D02*
X-1254291Y881668D01*
G01X-1251502Y883260D02*
X-1251584Y883511D01*
G01X-1254291Y881668D02*
X-1254209Y881417D01*
G01X-1244202Y882925D02*
X-1244038Y882506D01*
G01X-1247893Y882925D02*
X-1247729Y882506D01*
G01X-1244449D02*
X-1244531Y882673D01*
G01X-1245761Y882506D02*
X-1245843Y882673D01*
G01X-1248139Y882506D02*
X-1248222Y882673D01*
G01X-1249452Y882506D02*
X-1249534Y882673D01*
G01X-1251584Y883511D02*
X-1251748Y883846D01*
G01X-1254209Y881417D02*
X-1254045Y881082D01*
G01X-1251912Y883260D02*
X-1252241Y883762D01*
G01X-1253881Y881668D02*
X-1253553Y881166D01*
G01X-1294491Y855909D02*
X-1295279Y856696D01*
G01X-1245023Y882841D02*
X-1245187Y882757D01*
G01X-1248714Y882841D02*
X-1248878Y882757D01*
G01X-1252405Y880579D02*
X-1251994Y880830D01*
G01X-1253389Y884349D02*
X-1253799Y884097D01*
G01X-1252487Y880998D02*
X-1252241Y881166D01*
G01X-1253307Y883930D02*
X-1253553Y883762D01*
G01X-1289216Y856696D02*
X-1290003Y855909D01*
G01X-1245187Y882757D02*
X-1245269Y882673D01*
G01X-1245433Y882841D02*
X-1245187Y883092D01*
G01X-1246499Y882757D02*
X-1246663Y882590D01*
G01Y882925D02*
X-1246499Y883092D01*
G01X-1248878Y882757D02*
X-1248960Y882673D01*
G01X-1249124Y882841D02*
X-1248878Y883092D01*
G01X-1251994Y880830D02*
X-1251748Y881082D01*
G01X-1250190Y882757D02*
X-1250354Y882590D01*
G01Y882925D02*
X-1250190Y883092D01*
G01X-1253799Y884097D02*
X-1254045Y883846D01*
G01X-1252241Y881166D02*
X-1251912Y881668D01*
G01X-1245269Y882673D02*
X-1245351Y882506D01*
G01X-1233192Y905653D02*
Y868251D01*
G01X-1244038Y882506D02*
Y880495D01*
G01X-1244449D02*
Y882506D01*
G01X-1245351D02*
Y880495D01*
G01X-1245761D02*
Y882506D01*
G01X-1246663Y882590D02*
Y880495D01*
G01Y883176D02*
Y882925D01*
G01X-1247073Y880495D02*
Y883176D01*
G01X-1247729Y882506D02*
Y880495D01*
G01X-1248139D02*
Y882506D01*
G01X-1249042D02*
Y880495D01*
G01X-1249452D02*
Y882506D01*
G01X-1250354Y882590D02*
Y880495D01*
G01Y883176D02*
Y882925D01*
G01X-1253553Y883762D02*
X-1253881Y883260D01*
G01X-1248960Y882673D02*
X-1249042Y882506D01*
G01X-1251748Y881082D02*
X-1251584Y881417D01*
G01X-1254045Y883846D02*
X-1254209Y883511D01*
G01X-1251584Y881417D02*
X-1251502Y881668D01*
G01X-1254209Y883511D02*
X-1254291Y883260D01*
G01X-1251502Y881668D02*
X-1251420Y882087D01*
G01X-1254291Y883260D02*
X-1254373Y882841D01*
G01X-1251912Y881668D02*
X-1251830Y882171D01*
G01X-1253881Y883260D02*
X-1253963Y882757D01*
G01X-1250764Y880495D02*
Y883176D01*
G01X-1251420Y882087D02*
Y882841D01*
G01X-1251830Y882171D02*
Y882757D01*
G01X-1253963D02*
Y882171D01*
G01X-1254373Y882841D02*
Y882087D01*
G01X-1255029Y882171D02*
Y881836D01*
G01Y883176D02*
Y882841D01*
G01X-1256342Y881836D02*
Y882171D01*
G01Y882841D02*
Y883176D01*
G01X-1256998Y884432D02*
Y880495D01*
G01X-1257490Y882841D02*
Y884432D01*
G01Y880495D02*
Y882338D01*
G01X-1259786D02*
Y880495D01*
G01Y884432D02*
Y882841D01*
G01X-1260279Y880495D02*
Y884432D01*
G01X-1260751Y918448D02*
Y905653D01*
G01X-1280436Y855554D02*
Y862936D01*
G01X-1286538Y858133D02*
Y858921D01*
G01X-1288310Y864905D02*
Y864117D01*
G01X-1290869Y858921D02*
Y858133D01*
G01X-1293625Y860869D02*
Y861657D01*
G01X-1279255Y945810D02*
X-1246773D01*
G01X-1283192Y949747D02*
Y988490D01*
G01X-1276302Y945810D02*
G03I-6890J0D01*
G01X-1261276Y1060614D02*
X-1259307D01*
G01X-1283258D02*
X-1281289D01*
G01X-1294412D02*
X-1292444D01*
G01X-1230108Y1055588D02*
X-1228796D01*
G01X-1235357D02*
X-1234045D01*
G01X-1238638D02*
X-1236998D01*
G01X-1244872D02*
X-1243559D01*
G01X-1250121D02*
X-1248809D01*
G01X-1253402D02*
X-1251762D01*
G01X-1292444Y1054247D02*
X-1283258D01*
G01X-1249465D02*
X-1250121D01*
G01X-1244216D02*
X-1245200D01*
G01X-1234701D02*
X-1235357D01*
G01X-1229452D02*
X-1230436D01*
G01X-1283258Y1052237D02*
X-1292444D01*
G01X-1259307Y1051567D02*
X-1256027D01*
G01X-1261276D02*
X-1266853D01*
G01X-1261276Y1049556D02*
X-1269150D01*
G01X-1256027D02*
X-1259307D01*
G01X-1292444Y1044865D02*
X-1294412D01*
G01X-1281289D02*
X-1283258D01*
G01X-1259307D02*
X-1261276D01*
G01X-1251762D02*
X-1253402D01*
G01X-1246512D02*
X-1248153D01*
G01X-1241263D02*
X-1242903D01*
G01X-1236998D02*
X-1238638D01*
G01X-1231748D02*
X-1233389D01*
G01X-1226499D02*
X-1228139D01*
G01X-1228796Y1053912D02*
X-1229452Y1054247D01*
G01X-1234045Y1053912D02*
X-1234701Y1054247D01*
G01X-1243559Y1053912D02*
X-1244216Y1054247D01*
G01X-1248809Y1053912D02*
X-1249465Y1054247D01*
G01X-1228796Y1055588D02*
X-1227811Y1055252D01*
G01X-1234045Y1055588D02*
X-1233061Y1055252D01*
G01X-1243559Y1055588D02*
X-1242575Y1055252D01*
G01X-1248809Y1055588D02*
X-1247825Y1055252D01*
G01X-1272431Y1049556D02*
X-1278664Y1052907D01*
G01X-1276368D02*
X-1271775Y1050562D01*
G01X-1227811Y1055252D02*
X-1227155Y1054582D01*
G01X-1228468Y1053577D02*
X-1228796Y1053912D01*
G01X-1233061Y1055252D02*
X-1232077Y1054247D01*
G01X-1233717Y1053577D02*
X-1234045Y1053912D01*
G01X-1242575Y1055252D02*
X-1241919Y1054582D01*
G01X-1243231Y1053577D02*
X-1243559Y1053912D01*
G01X-1247825Y1055252D02*
X-1246840Y1054247D01*
G01X-1248481Y1053577D02*
X-1248809Y1053912D01*
G01X-1227155Y1054582D02*
X-1226499Y1052907D01*
G01X-1241919Y1054582D02*
X-1241263Y1052907D01*
G01X-1228139D02*
X-1228468Y1053577D01*
G01X-1233389Y1052907D02*
X-1233717Y1053577D01*
G01X-1242903Y1052907D02*
X-1243231Y1053577D01*
G01X-1248153Y1052907D02*
X-1248481Y1053577D01*
G01X-1272431Y1056258D02*
X-1271775Y1055252D01*
G01X-1226499Y1052907D02*
Y1044865D01*
G01X-1228139D02*
Y1052907D01*
G01X-1231748D02*
Y1044865D01*
G01X-1233389D02*
Y1052907D01*
G01X-1236998Y1053242D02*
Y1044865D01*
G01Y1055588D02*
Y1054582D01*
G01X-1238638Y1044865D02*
Y1055588D01*
G01X-1241263Y1052907D02*
Y1044865D01*
G01X-1242903D02*
Y1052907D01*
G01X-1246512D02*
Y1044865D01*
G01X-1248153D02*
Y1052907D01*
G01X-1251762Y1053242D02*
Y1044865D01*
G01Y1055588D02*
Y1054582D01*
G01X-1253402Y1044865D02*
Y1055588D01*
G01X-1256027Y1051567D02*
Y1049556D01*
G01X-1259307D02*
Y1044865D01*
G01Y1060614D02*
Y1051567D01*
G01X-1261276Y1044865D02*
Y1049556D01*
G01Y1057933D02*
Y1051567D01*
G01X-1269150Y1049556D02*
Y1051567D01*
G01X-1281289Y1060614D02*
Y1044865D01*
G01X-1283258Y1054247D02*
Y1060614D01*
G01Y1044865D02*
Y1052237D01*
G01X-1231420Y1053577D02*
X-1231748Y1052907D01*
G01X-1246184Y1053577D02*
X-1246512Y1052907D01*
G01X-1292444Y1052237D02*
Y1044865D01*
G01Y1060614D02*
Y1054247D01*
G01X-1294412Y1044865D02*
Y1060614D01*
G01X-1231092Y1055252D02*
X-1230108Y1055588D01*
G01X-1235357Y1054247D02*
X-1236342Y1053912D01*
G01Y1055252D02*
X-1235357Y1055588D01*
G01X-1245856Y1055252D02*
X-1244872Y1055588D01*
G01X-1250121Y1054247D02*
X-1251105Y1053912D01*
G01Y1055252D02*
X-1250121Y1055588D01*
G01X-1230436Y1054247D02*
X-1231092Y1053912D01*
G01X-1245200Y1054247D02*
X-1245856Y1053912D01*
G01X-1231092D02*
X-1231420Y1053577D01*
G01X-1232077Y1054247D02*
X-1231092Y1055252D01*
G01X-1236342Y1053912D02*
X-1236998Y1053242D01*
G01Y1054582D02*
X-1236342Y1055252D01*
G01X-1245856Y1053912D02*
X-1246184Y1053577D01*
G01X-1246840Y1054247D02*
X-1245856Y1055252D01*
G01X-1251105Y1053912D02*
X-1251762Y1053242D01*
G01Y1054582D02*
X-1251105Y1055252D01*
G01X-1266853Y1051567D02*
X-1261276Y1057933D01*
G01X-1269150Y1051567D02*
X-1261276Y1060614D01*
G01X-1271775Y1050562D02*
X-1272431Y1049556D01*
G01X-1271775Y1055252D02*
X-1276368Y1052907D01*
G01X-1278664D02*
X-1272431Y1056258D01*
G01X-1227090Y1213527D02*
G03I-6889J0D01*
G01X-1215279D02*
G03I-18700J0D01*
G01X-1233979Y1217464D02*
Y1275319D01*
G01X-1230127Y1231827D02*
X-1204928Y1351519D01*
G01X-1228491Y1217692D02*
X-1186360Y1249666D01*
G01X-1238322Y1463291D02*
Y1444354D01*
G01X-1187631Y-489965D02*
G03I-6890J0D01*
G01X-1175820D02*
G03I-18701J0D01*
G01X-1115151Y-392131D02*
X-1157058D01*
G01X-1115151Y-364611D02*
X-1160854D01*
G01X-1191765Y-340359D02*
G03X-1187828I1968J0D01*
G01X-1191765Y194145D02*
Y-340359D01*
G01X-1187828D02*
X-1035859D01*
G01X-1191765Y194145D02*
G03X-1192180Y195906I-3937J2D01*
G01X-1210362Y232268D02*
X-1192180Y195905D01*
G01X-1194722Y263388D02*
X-908606D01*
G01X-1197871D02*
X-1194722D01*
G01X-1210362Y232268D02*
G03X-1213883Y234444I-3521J-1761D01*
G01X-1192641Y508802D02*
Y432110D01*
G01X-1188704Y512739D02*
X-1057031D01*
G01X-1185751D02*
G03I-6890J0D01*
G01X-1173940D02*
G03I-18701J0D01*
G01X-1182329Y594755D02*
X-1182300Y594391D01*
G01X-1182412Y595105D02*
X-1182329Y594755D01*
G01X-1182545Y595426D02*
X-1182412Y595105D01*
G01X-1182718Y595704D02*
X-1182545Y595426D01*
G01X-1182919Y595932D02*
X-1182718Y595704D01*
G01X-1183137Y596106D02*
X-1182919Y595932D01*
G01X-1175242Y594755D02*
X-1175213Y594391D01*
G01X-1175326Y595105D02*
X-1175242Y594755D01*
G01X-1175458Y595426D02*
X-1175326Y595105D01*
G01X-1175631Y595704D02*
X-1175458Y595426D01*
G01X-1175833Y595932D02*
X-1175631Y595704D01*
G01X-1176051Y596106D02*
X-1175833Y595932D01*
G01X-1168156Y594755D02*
X-1168127Y594391D01*
G01X-1168239Y595105D02*
X-1168156Y594755D01*
G01X-1168372Y595426D02*
X-1168239Y595105D01*
G01X-1168545Y595704D02*
X-1168372Y595426D01*
G01X-1168746Y595932D02*
X-1168545Y595704D01*
G01X-1168964Y596106D02*
X-1168746Y595932D01*
G01X-1161069Y594755D02*
X-1161040Y594391D01*
G01X-1161153Y595105D02*
X-1161069Y594755D01*
G01X-1161285Y595426D02*
X-1161153Y595105D01*
G01X-1161458Y595704D02*
X-1161285Y595426D01*
G01X-1161659Y595932D02*
X-1161458Y595704D01*
G01X-1161878Y596106D02*
X-1161659Y595932D01*
G01X-1153982Y594755D02*
X-1153953Y594391D01*
G01X-1154066Y595105D02*
X-1153982Y594755D01*
G01X-1154198Y595426D02*
X-1154066Y595105D01*
G01X-1154371Y595704D02*
X-1154198Y595426D01*
G01X-1154573Y595932D02*
X-1154371Y595704D01*
G01X-1154791Y596106D02*
X-1154573Y595932D01*
G01X-1182772Y595884D02*
X-1183137Y596106D01*
G01X-1182509Y595603D02*
X-1182772Y595884D01*
G01X-1182353Y595290D02*
X-1182509Y595603D01*
G01X-1182300Y594962D02*
X-1182353Y595290D01*
G01X-1175685Y595884D02*
X-1176051Y596106D01*
G01X-1175423Y595603D02*
X-1175685Y595884D01*
G01X-1175266Y595290D02*
X-1175423Y595603D01*
G01X-1175213Y594962D02*
X-1175266Y595290D01*
G01X-1168598Y595884D02*
X-1168964Y596106D01*
G01X-1168336Y595603D02*
X-1168598Y595884D01*
G01X-1168179Y595290D02*
X-1168336Y595603D01*
G01X-1168127Y594962D02*
X-1168179Y595290D01*
G01X-1161512Y595884D02*
X-1161878Y596106D01*
G01X-1161249Y595603D02*
X-1161512Y595884D01*
G01X-1161093Y595290D02*
X-1161249Y595603D01*
G01X-1161040Y594962D02*
X-1161093Y595290D01*
G01X-1154425Y595884D02*
X-1154791Y596106D01*
G01X-1154163Y595603D02*
X-1154425Y595884D01*
G01X-1154006Y595290D02*
X-1154163Y595603D01*
G01X-1153953Y594962D02*
X-1154006Y595290D01*
G01X-1177724Y595932D02*
X-1177506Y596106D01*
G01X-1177925Y595704D02*
X-1177724Y595932D01*
G01X-1178098Y595426D02*
X-1177925Y595704D01*
G01X-1178231Y595105D02*
X-1178098Y595426D01*
G01X-1178314Y594755D02*
X-1178231Y595105D01*
G01X-1178343Y594391D02*
X-1178314Y594755D01*
G01X-1170637Y595932D02*
X-1170419Y596106D01*
G01X-1170839Y595704D02*
X-1170637Y595932D01*
G01X-1171011Y595426D02*
X-1170839Y595704D01*
G01X-1171144Y595105D02*
X-1171011Y595426D01*
G01X-1171228Y594755D02*
X-1171144Y595105D01*
G01X-1171257Y594391D02*
X-1171228Y594755D01*
G01X-1163551Y595932D02*
X-1163332Y596106D01*
G01X-1163752Y595704D02*
X-1163551Y595932D01*
G01X-1163925Y595426D02*
X-1163752Y595704D01*
G01X-1164057Y595105D02*
X-1163925Y595426D01*
G01X-1164141Y594755D02*
X-1164057Y595105D01*
G01X-1164170Y594391D02*
X-1164141Y594755D01*
G01X-1156464Y595932D02*
X-1156246Y596106D01*
G01X-1156665Y595704D02*
X-1156464Y595932D01*
G01X-1156838Y595426D02*
X-1156665Y595704D01*
G01X-1156971Y595105D02*
X-1156838Y595426D01*
G01X-1157054Y594755D02*
X-1156971Y595105D01*
G01X-1157083Y594391D02*
X-1157054Y594755D01*
G01X-1177968Y595798D02*
X-1177506Y596106D01*
G01X-1178249Y595398D02*
X-1177968Y595798D01*
G01X-1178343Y594962D02*
X-1178249Y595398D01*
G01X-1170881Y595798D02*
X-1170419Y596106D01*
G01X-1171162Y595398D02*
X-1170881Y595798D01*
G01X-1171257Y594962D02*
X-1171162Y595398D01*
G01X-1163794Y595798D02*
X-1163332Y596106D01*
G01X-1164076Y595398D02*
X-1163794Y595798D01*
G01X-1164170Y594962D02*
X-1164076Y595398D01*
G01X-1156708Y595798D02*
X-1156246Y596106D01*
G01X-1156989Y595398D02*
X-1156708Y595798D01*
G01X-1157083Y594962D02*
X-1156989Y595398D01*
G01X-1154531Y637543D02*
G03I-708J0D01*
G01X-1161617Y637936D02*
G03I-709J0D01*
G01Y632425D02*
G03I-709J0D01*
G01X-1154531Y633212D02*
G03I-708J0D01*
G01Y627700D02*
G03I-708J0D01*
G01X-1161617Y628094D02*
G03I-709J0D01*
G01X-1154531Y623369D02*
G03I-708J0D01*
G01X-1161617Y623763D02*
G03I-709J0D01*
G01X-1157093Y634019D02*
G03X-1153944I1575J0D01*
G01X-1154531Y619039D02*
G03I-708J0D01*
G01X-1161617Y618251D02*
G03I-709J0D01*
G01Y613921D02*
G03I-709J0D01*
G01X-1154531Y613527D02*
G03I-708J0D01*
G01Y609196D02*
G03I-708J0D01*
G01X-1161617Y609590D02*
G03I-709J0D01*
G01X-1153550Y614334D02*
G03I-1968J0D01*
G01X-1154531Y604865D02*
G03I-708J0D01*
G01X-1161617Y604078D02*
G03I-709J0D01*
G01Y599747D02*
G03I-709J0D01*
G01X-1154531Y599354D02*
G03I-708J0D01*
G01Y595023D02*
G03I-708J0D01*
G01X-1154786Y596114D02*
G03X-1156250I-732J-1394D01*
G01X-1168704Y637543D02*
G03I-708J0D01*
G01Y633212D02*
G03I-708J0D01*
G01Y627700D02*
G03I-708J0D01*
G01Y623369D02*
G03I-708J0D01*
G01X-1164180Y634019D02*
G03X-1161030I1575J0D01*
G01X-1171266D02*
G03X-1168117I1574J0D01*
G01X-1175790Y637936D02*
G03I-709J0D01*
G01Y632425D02*
G03I-709J0D01*
G01Y628094D02*
G03I-709J0D01*
G01Y623763D02*
G03I-709J0D01*
G01X-1175400Y629511D02*
G03X-1174416Y630495I0J984D01*
G01X-1179140D02*
G03X-1178156Y629511I984J0D01*
G01X-1178353Y634019D02*
G03X-1175203I1575J0D01*
G01X-1183865Y632444D02*
G03X-1182290Y634019I0J1575D01*
G01X-1168704Y619039D02*
G03I-708J0D01*
G01Y613527D02*
G03I-708J0D01*
G01Y609196D02*
G03I-708J0D01*
G01X-1160636Y614334D02*
G03I-1969J0D01*
G01X-1167723D02*
G03I-1969J0D01*
G01X-1168704Y604865D02*
G03I-708J0D01*
G01Y599354D02*
G03I-708J0D01*
G01Y595023D02*
G03I-708J0D01*
G01X-1168960Y596114D02*
G03X-1170424I-732J-1394D01*
G01X-1161873D02*
G03X-1163337I-732J-1394D01*
G01X-1175790Y618251D02*
G03I-709J0D01*
G01Y613921D02*
G03I-709J0D01*
G01Y609590D02*
G03I-709J0D01*
G01X-1183865Y612365D02*
G03Y616302I0J1969D01*
G01X-1174810Y614334D02*
G03I-1968J0D01*
G01X-1175790Y604078D02*
G03I-709J0D01*
G01Y599747D02*
G03I-709J0D01*
G01X-1183133Y596114D02*
G03X-1183865Y596295I-733J-1394D01*
G01X-1176046Y596114D02*
G03X-1177510I-732J-1394D01*
G01X-1175243Y588625D02*
X-1176424Y587444D01*
G01X-1175243Y636555D02*
X-1176030Y635191D01*
G01X-1153944Y634019D02*
Y650530D01*
G01X-1153953Y594962D02*
Y589019D01*
G01X-1157083Y594962D02*
Y589019D01*
G01X-1157093Y650530D02*
Y634019D01*
G01X-1161030D02*
Y650530D01*
G01X-1161040Y594962D02*
Y589019D01*
G01X-1164170Y594962D02*
Y589019D01*
G01X-1164180Y650530D02*
Y634019D01*
G01X-1168117D02*
Y650530D01*
G01X-1168127Y594962D02*
Y589019D01*
G01X-1171257Y594962D02*
Y589019D01*
G01X-1171266Y650530D02*
Y634019D01*
G01X-1174416Y653921D02*
Y630495D01*
G01X-1175203Y634019D02*
Y638850D01*
G01X-1175213Y594962D02*
Y589019D01*
G01X-1175243Y588625D02*
Y591381D01*
G01Y638790D02*
Y636555D01*
G01X-1178314D02*
Y638790D01*
G01Y591381D02*
Y588625D01*
G01X-1178343Y594962D02*
Y589019D01*
G01X-1178353Y638850D02*
Y634019D01*
G01X-1179140Y653921D02*
Y630495D01*
G01X-1180335Y675174D02*
Y586460D01*
G01X-1182290Y634019D02*
Y650530D01*
G01X-1182300Y594962D02*
Y589019D01*
G01X-1183865Y616302D02*
Y632444D01*
G01Y596285D02*
Y612365D01*
G01Y589019D02*
Y591381D01*
G01X-1178314Y636555D02*
X-1177526Y635191D01*
G01X-1178314Y588625D02*
X-1177133Y587444D01*
G01X-1176030Y635191D02*
X-1177526D01*
G01X-1174416Y632034D02*
X-1179140D01*
G01X-1175400Y629511D02*
X-1178156D01*
G01X-1124197Y599905D02*
X-1180335D01*
G01X-1177506Y596106D02*
X-1183137D01*
G01X-1170419D02*
X-1176051D01*
G01X-1163332D02*
X-1168964D01*
G01X-1156246D02*
X-1161878D01*
G01X-1149159D02*
X-1154791D01*
G01X-1124197Y593862D02*
X-1180335D01*
G01X-1124197Y593389D02*
X-1180335D01*
G01X-1039136Y591381D02*
X-1183865D01*
G01X-1124197Y589806D02*
X-1180335D01*
G01X-1039136Y589019D02*
X-1183865D01*
G01X-1175243Y588625D02*
X-1178314D01*
G01X-1176424Y587444D02*
X-1177133D01*
G01X-1124197Y586460D02*
X-1180335D01*
G01X-1155016Y675833D02*
X-1154996Y675895D01*
G01X-1155054Y675774D02*
X-1155016Y675833D01*
G01X-1155108Y675722D02*
X-1155054Y675774D01*
G01X-1155175Y675678D02*
X-1155108Y675722D01*
G01X-1155252Y675644D02*
X-1155175Y675678D01*
G01X-1155336Y675623D02*
X-1155252Y675644D01*
G01X-1169189Y675833D02*
X-1169169Y675895D01*
G01X-1169228Y675774D02*
X-1169189Y675833D01*
G01X-1169281Y675722D02*
X-1169228Y675774D01*
G01X-1169348Y675678D02*
X-1169281Y675722D01*
G01X-1169425Y675644D02*
X-1169348Y675678D01*
G01X-1169509Y675623D02*
X-1169425Y675644D01*
G01X-1175458Y664118D02*
X-1175474Y664117D01*
G01X-1175443Y664120D02*
X-1175458Y664118D01*
G01X-1175427Y664124D02*
X-1175443Y664120D01*
G01X-1154032Y674116D02*
X-1154018Y674190D01*
G01X-1154074Y674051D02*
X-1154032Y674116D01*
G01X-1154138Y674009D02*
X-1154074Y674051D01*
G01X-1154214Y673993D02*
X-1154138Y674009D01*
G01X-1168205Y674116D02*
X-1168191Y674190D01*
G01X-1168248Y674051D02*
X-1168205Y674116D01*
G01X-1168311Y674009D02*
X-1168248Y674051D01*
G01X-1168388Y673993D02*
X-1168311Y674009D01*
G01X-1169006Y674807D02*
X-1168988Y674865D01*
G01X-1169040Y674753D02*
X-1169006Y674807D01*
G01X-1169089Y674702D02*
X-1169040Y674753D01*
G01X-1169149Y674659D02*
X-1169089Y674702D01*
G01X-1169219Y674624D02*
X-1169149Y674659D01*
G01X-1169296Y674600D02*
X-1169219Y674624D01*
G01X-1169375Y674587D02*
X-1169296Y674600D01*
G01X-1155344Y675621D02*
X-1155336Y675623D01*
G01X-1155352Y675620D02*
X-1155344Y675621D01*
G01X-1155360Y675619D02*
X-1155352Y675620D01*
G01X-1155369Y675618D02*
X-1155360Y675619D01*
G01X-1155377Y675617D02*
X-1155369Y675618D01*
G01X-1155384Y675616D02*
X-1155377Y675617D01*
G01X-1169517Y675621D02*
X-1169509Y675623D01*
G01X-1169526Y675620D02*
X-1169517Y675621D01*
G01X-1169534Y675619D02*
X-1169526Y675620D01*
G01X-1169542Y675618D02*
X-1169534Y675619D01*
G01X-1169550Y675617D02*
X-1169542Y675618D01*
G01X-1169557Y675616D02*
X-1169550Y675617D01*
G01X-1165830Y664205D02*
X-1165858Y664251D01*
G01X-1165796Y664167D02*
X-1165830Y664205D01*
G01X-1165756Y664139D02*
X-1165796Y664167D01*
G01X-1165711Y664123D02*
X-1165756Y664139D01*
G01X-1165666Y664117D02*
X-1165711Y664123D01*
G01X-1171765Y674132D02*
X-1171773Y674190D01*
G01X-1171742Y674083D02*
X-1171765Y674132D01*
G01X-1171709Y674044D02*
X-1171742Y674083D01*
G01X-1171668Y674015D02*
X-1171709Y674044D01*
G01X-1171623Y673998D02*
X-1171668Y674015D01*
G01X-1171577Y673993D02*
X-1171623Y673998D01*
G01X-1157592Y674132D02*
X-1157600Y674190D01*
G01X-1157569Y674083D02*
X-1157592Y674132D01*
G01X-1157536Y674044D02*
X-1157569Y674083D01*
G01X-1157495Y674015D02*
X-1157536Y674044D01*
G01X-1157450Y673998D02*
X-1157495Y674015D01*
G01X-1157403Y673993D02*
X-1157450Y673998D01*
G01X-1159346Y674807D02*
X-1159364Y674865D01*
G01X-1159312Y674753D02*
X-1159346Y674807D01*
G01X-1159263Y674702D02*
X-1159312Y674753D01*
G01X-1159203Y674659D02*
X-1159263Y674702D01*
G01X-1159133Y674624D02*
X-1159203Y674659D01*
G01X-1159056Y674600D02*
X-1159133Y674624D01*
G01X-1158976Y674587D02*
X-1159056Y674600D01*
G01X-1172977Y675617D02*
X-1172968Y675616D01*
G01X-1172985Y675618D02*
X-1172977Y675617D01*
G01X-1172993Y675619D02*
X-1172985Y675618D01*
G01X-1173001Y675620D02*
X-1172993Y675619D01*
G01X-1173009Y675621D02*
X-1173001Y675620D01*
G01X-1173016Y675623D02*
X-1173009Y675621D01*
G01X-1158803Y675617D02*
X-1158795Y675616D01*
G01X-1158812Y675618D02*
X-1158803Y675617D01*
G01X-1158820Y675619D02*
X-1158812Y675618D01*
G01X-1158828Y675620D02*
X-1158820Y675619D01*
G01X-1158836Y675621D02*
X-1158828Y675620D01*
G01X-1158843Y675623D02*
X-1158836Y675621D01*
G01X-1173284Y669533D02*
X-1173341Y669826D01*
G01X-1173112Y669274D02*
X-1173284Y669533D01*
G01X-1172849Y669099D02*
X-1173112Y669274D01*
G01X-1172542Y669039D02*
X-1172849Y669099D01*
G01X-1159111Y669533D02*
X-1159168Y669826D01*
G01X-1158939Y669274D02*
X-1159111Y669533D01*
G01X-1158676Y669099D02*
X-1158939Y669274D01*
G01X-1158369Y669039D02*
X-1158676Y669099D01*
G01X-1174602Y701883D02*
X-1174225Y701795D01*
G01X-1174679Y701902D02*
X-1174602Y701883D01*
G01X-1172901Y669633D02*
X-1172954Y669826D01*
G01X-1172750Y669487D02*
X-1172901Y669633D01*
G01X-1172542Y669432D02*
X-1172750Y669487D01*
G01X-1158727Y669633D02*
X-1158780Y669826D01*
G01X-1158577Y669487D02*
X-1158727Y669633D01*
G01X-1158369Y669432D02*
X-1158577Y669487D01*
G01X-1178679Y664118D02*
X-1178663Y664117D01*
G01X-1178695Y664120D02*
X-1178679Y664118D01*
G01X-1178710Y664124D02*
X-1178695Y664120D01*
G01X-1178751Y664130D02*
X-1178710Y664124D01*
G01X-1178792Y664145D02*
X-1178751Y664130D01*
G01X-1178829Y664170D02*
X-1178792Y664145D01*
G01X-1178860Y664203D02*
X-1178829Y664170D01*
G01X-1153435Y701961D02*
X-1153463Y701902D01*
G01X-1153396Y702011D02*
X-1153435Y701961D01*
G01X-1153348Y702053D02*
X-1153396Y702011D01*
G01X-1153293Y702084D02*
X-1153348Y702053D01*
G01X-1153233Y702103D02*
X-1153293Y702084D01*
G01X-1153171Y702110D02*
X-1153233Y702103D01*
G01X-1155005Y701961D02*
X-1155033Y701902D01*
G01X-1154966Y702011D02*
X-1155005Y701961D01*
G01X-1154918Y702053D02*
X-1154966Y702011D01*
G01X-1154863Y702084D02*
X-1154918Y702053D01*
G01X-1154803Y702103D02*
X-1154863Y702084D01*
G01X-1154741Y702110D02*
X-1154803Y702103D01*
G01X-1167608Y701961D02*
X-1167636Y701902D01*
G01X-1167570Y702011D02*
X-1167608Y701961D01*
G01X-1167521Y702053D02*
X-1167570Y702011D01*
G01X-1167466Y702084D02*
X-1167521Y702053D01*
G01X-1167407Y702103D02*
X-1167466Y702084D01*
G01X-1167344Y702110D02*
X-1167407Y702103D01*
G01X-1169178Y701961D02*
X-1169206Y701902D01*
G01X-1169140Y702011D02*
X-1169178Y701961D01*
G01X-1169091Y702053D02*
X-1169140Y702011D01*
G01X-1169036Y702084D02*
X-1169091Y702053D01*
G01X-1168977Y702103D02*
X-1169036Y702084D01*
G01X-1168914Y702110D02*
X-1168977Y702103D01*
G01X-1169603Y700366D02*
X-1169572Y700381D01*
G01X-1169651Y700360D02*
X-1169603Y700366D01*
G01X-1169712Y700361D02*
X-1169651Y700360D01*
G01X-1155429Y700366D02*
X-1155399Y700381D01*
G01X-1155477Y700360D02*
X-1155429Y700366D01*
G01X-1155539Y700361D02*
X-1155477Y700360D01*
G01X-1160429Y701883D02*
X-1160052Y701795D01*
G01X-1160506Y701902D02*
X-1160429Y701883D01*
G01X-1172835Y700360D02*
X-1172774Y700361D01*
G01X-1172883Y700366D02*
X-1172835Y700360D01*
G01X-1172914Y700381D02*
X-1172883Y700366D01*
G01X-1158662Y700360D02*
X-1158600Y700361D01*
G01X-1158710Y700366D02*
X-1158662Y700360D01*
G01X-1158740Y700381D02*
X-1158710Y700366D01*
G01X-1169646Y701322D02*
X-1169810Y700764D01*
G01X-1169566Y701747D02*
X-1169646Y701322D01*
G01X-1169574Y702016D02*
X-1169566Y701747D01*
G01X-1169668Y702110D02*
X-1169574Y702016D01*
G01X-1155473Y701322D02*
X-1155636Y700764D01*
G01X-1155393Y701747D02*
X-1155473Y701322D01*
G01X-1155401Y702016D02*
X-1155393Y701747D01*
G01X-1155495Y702110D02*
X-1155401Y702016D01*
G01X-1169441Y702078D02*
X-1169668Y702110D01*
G01X-1169294Y702008D02*
X-1169441Y702078D01*
G01X-1169206Y701902D02*
X-1169294Y702008D01*
G01X-1155268Y702078D02*
X-1155495Y702110D01*
G01X-1155121Y702008D02*
X-1155268Y702078D01*
G01X-1155033Y701902D02*
X-1155121Y702008D01*
G01X-1172521Y699951D02*
X-1172424Y699747D01*
G01X-1172639Y700155D02*
X-1172521Y699951D01*
G01X-1172862Y700496D02*
X-1172639Y700155D01*
G01X-1158348Y699951D02*
X-1158251Y699747D01*
G01X-1158465Y700155D02*
X-1158348Y699951D01*
G01X-1158689Y700496D02*
X-1158465Y700155D01*
G01X-1172941Y700631D02*
X-1172862Y700496D01*
G01X-1173009Y700764D02*
X-1172941Y700631D01*
G01X-1158767D02*
X-1158689Y700496D01*
G01X-1158836Y700764D02*
X-1158767Y700631D01*
G01X-1172578Y669639D02*
X-1172499Y669629D01*
G01X-1172654Y669657D02*
X-1172578Y669639D01*
G01X-1172723Y669682D02*
X-1172654Y669657D01*
G01X-1172783Y669712D02*
X-1172723Y669682D01*
G01X-1172832Y669748D02*
X-1172783Y669712D01*
G01X-1172867Y669786D02*
X-1172832Y669748D01*
G01X-1172886Y669826D02*
X-1172867Y669786D01*
G01X-1172504Y670374D02*
X-1172424Y670364D01*
G01X-1172579Y670392D02*
X-1172504Y670374D01*
G01X-1172649Y670417D02*
X-1172579Y670392D01*
G01X-1172709Y670447D02*
X-1172649Y670417D01*
G01X-1172757Y670482D02*
X-1172709Y670447D01*
G01X-1172792Y670521D02*
X-1172757Y670482D01*
G01X-1172812Y670561D02*
X-1172792Y670521D01*
G01X-1158405Y669639D02*
X-1158325Y669629D01*
G01X-1158481Y669657D02*
X-1158405Y669639D01*
G01X-1158550Y669682D02*
X-1158481Y669657D01*
G01X-1158610Y669712D02*
X-1158550Y669682D01*
G01X-1158659Y669748D02*
X-1158610Y669712D01*
G01X-1158693Y669786D02*
X-1158659Y669748D01*
G01X-1158713Y669826D02*
X-1158693Y669786D01*
G01X-1158330Y670374D02*
X-1158251Y670364D01*
G01X-1158406Y670392D02*
X-1158330Y670374D01*
G01X-1158475Y670417D02*
X-1158406Y670392D01*
G01X-1158535Y670447D02*
X-1158475Y670417D01*
G01X-1158584Y670482D02*
X-1158535Y670447D01*
G01X-1158619Y670521D02*
X-1158584Y670482D01*
G01X-1158638Y670561D02*
X-1158619Y670521D01*
G01X-1175117Y702103D02*
X-1175181Y702110D01*
G01X-1175057Y702084D02*
X-1175117Y702103D01*
G01X-1175002Y702052D02*
X-1175057Y702084D01*
G01X-1174955Y702010D02*
X-1175002Y702052D01*
G01X-1174916Y701960D02*
X-1174955Y702010D01*
G01X-1174889Y701902D02*
X-1174916Y701960D01*
G01X-1174907Y702103D02*
X-1174971Y702110D01*
G01X-1174847Y702084D02*
X-1174907Y702103D01*
G01X-1174792Y702052D02*
X-1174847Y702084D01*
G01X-1174744Y702010D02*
X-1174792Y702052D01*
G01X-1174706Y701960D02*
X-1174744Y702010D01*
G01X-1174679Y701902D02*
X-1174706Y701960D01*
G01X-1173864Y702103D02*
X-1173927Y702110D01*
G01X-1173804Y702084D02*
X-1173864Y702103D01*
G01X-1173749Y702053D02*
X-1173804Y702084D01*
G01X-1173701Y702010D02*
X-1173749Y702053D01*
G01X-1173663Y701960D02*
X-1173701Y702010D01*
G01X-1173636Y701902D02*
X-1173663Y701960D01*
G01X-1173508Y702103D02*
X-1173571Y702110D01*
G01X-1173448Y702084D02*
X-1173508Y702103D01*
G01X-1173393Y702053D02*
X-1173448Y702084D01*
G01X-1173345Y702010D02*
X-1173393Y702053D01*
G01X-1173307Y701960D02*
X-1173345Y702010D01*
G01X-1173280Y701902D02*
X-1173307Y701960D01*
G01X-1160944Y702103D02*
X-1161007Y702110D01*
G01X-1160884Y702084D02*
X-1160944Y702103D01*
G01X-1160829Y702052D02*
X-1160884Y702084D01*
G01X-1160781Y702010D02*
X-1160829Y702052D01*
G01X-1160743Y701960D02*
X-1160781Y702010D01*
G01X-1160716Y701902D02*
X-1160743Y701960D01*
G01X-1160734Y702103D02*
X-1160797Y702110D01*
G01X-1160674Y702084D02*
X-1160734Y702103D01*
G01X-1160619Y702052D02*
X-1160674Y702084D01*
G01X-1160571Y702010D02*
X-1160619Y702052D01*
G01X-1160533Y701960D02*
X-1160571Y702010D01*
G01X-1160506Y701902D02*
X-1160533Y701960D01*
G01X-1159691Y702103D02*
X-1159754Y702110D01*
G01X-1159631Y702084D02*
X-1159691Y702103D01*
G01X-1159576Y702053D02*
X-1159631Y702084D01*
G01X-1159528Y702010D02*
X-1159576Y702053D01*
G01X-1159490Y701960D02*
X-1159528Y702010D01*
G01X-1159463Y701902D02*
X-1159490Y701960D01*
G01X-1159335Y702103D02*
X-1159398Y702110D01*
G01X-1159275Y702084D02*
X-1159335Y702103D01*
G01X-1159220Y702053D02*
X-1159275Y702084D01*
G01X-1159172Y702010D02*
X-1159220Y702053D01*
G01X-1159134Y701960D02*
X-1159172Y702010D01*
G01X-1159107Y701902D02*
X-1159134Y701960D01*
G01X-1173100Y675644D02*
X-1173016Y675623D01*
G01X-1173178Y675679D02*
X-1173100Y675644D01*
G01X-1173245Y675723D02*
X-1173178Y675679D01*
G01X-1173298Y675775D02*
X-1173245Y675723D01*
G01X-1173336Y675834D02*
X-1173298Y675775D01*
G01X-1173356Y675895D02*
X-1173336Y675834D01*
G01X-1158927Y675644D02*
X-1158843Y675623D01*
G01X-1159005Y675679D02*
X-1158927Y675644D01*
G01X-1159072Y675723D02*
X-1159005Y675679D01*
G01X-1159125Y675775D02*
X-1159072Y675723D01*
G01X-1159163Y675834D02*
X-1159125Y675775D01*
G01X-1159183Y675895D02*
X-1159163Y675834D01*
G01X-1173230Y674600D02*
X-1173150Y674587D01*
G01X-1173307Y674625D02*
X-1173230Y674600D01*
G01X-1173378Y674660D02*
X-1173307Y674625D01*
G01X-1173438Y674703D02*
X-1173378Y674660D01*
G01X-1173486Y674753D02*
X-1173438Y674703D01*
G01X-1173519Y674808D02*
X-1173486Y674753D01*
G01X-1173537Y674865D02*
X-1173519Y674808D01*
G01X-1172911Y702019D02*
X-1172817Y702110D01*
G01X-1172920Y701752D02*
X-1172911Y702019D01*
G01X-1172841Y701326D02*
X-1172920Y701752D01*
G01X-1172676Y700764D02*
X-1172841Y701326D01*
G01X-1169339Y674410D02*
X-1169335Y674309D01*
G01X-1169353Y674505D02*
X-1169339Y674410D01*
G01X-1169375Y674587D02*
X-1169353Y674505D01*
G01X-1173410Y698430D02*
X-1173477Y698650D01*
G01X-1173369Y698205D02*
X-1173410Y698430D01*
G01X-1173356Y697977D02*
X-1173369Y698205D01*
G01X-1173033Y698521D02*
X-1173113Y698784D01*
G01X-1172984Y698251D02*
X-1173033Y698521D01*
G01X-1172968Y697977D02*
X-1172984Y698251D01*
G01X-1173621Y698431D02*
X-1173687Y698650D01*
G01X-1173581Y698205D02*
X-1173621Y698431D01*
G01X-1173567Y697977D02*
X-1173581Y698205D01*
G01X-1173007Y700161D02*
X-1173074Y700381D01*
G01X-1172967Y699936D02*
X-1173007Y700161D01*
G01X-1172954Y699707D02*
X-1172967Y699936D01*
G01X-1173954Y674406D02*
X-1173953Y674309D01*
G01X-1173954Y674507D02*
Y674406D01*
G01X-1173955Y674610D02*
X-1173954Y674507D01*
G01X-1168955Y674510D02*
X-1168958Y674610D01*
G01X-1168954Y674409D02*
X-1168955Y674510D01*
G01X-1158738Y702019D02*
X-1158644Y702110D01*
G01X-1158747Y701752D02*
X-1158738Y702019D01*
G01X-1158667Y701326D02*
X-1158747Y701752D01*
G01X-1158503Y700764D02*
X-1158667Y701326D01*
G01X-1155166Y674410D02*
X-1155162Y674309D01*
G01X-1155180Y674505D02*
X-1155166Y674410D01*
G01X-1155202Y674587D02*
X-1155180Y674505D01*
G01X-1172825Y699954D02*
X-1172812Y699741D01*
G01X-1172859Y700169D02*
X-1172825Y699954D01*
G01X-1172914Y700381D02*
X-1172859Y700169D01*
G01X-1158652Y699954D02*
X-1158639Y699741D01*
G01X-1158686Y700169D02*
X-1158652Y699954D01*
G01X-1158740Y700381D02*
X-1158686Y700169D01*
G01X-1171652Y664133D02*
X-1171577Y664117D01*
G01X-1171716Y664175D02*
X-1171652Y664133D01*
G01X-1171758Y664240D02*
X-1171716Y664175D01*
G01X-1171773Y664314D02*
X-1171758Y664240D01*
G01X-1164565Y664133D02*
X-1164490Y664117D01*
G01X-1164629Y664175D02*
X-1164565Y664133D01*
G01X-1164672Y664240D02*
X-1164629Y664175D01*
G01X-1164687Y664314D02*
X-1164672Y664240D01*
G01X-1157478Y664133D02*
X-1157403Y664117D01*
G01X-1157543Y664175D02*
X-1157478Y664133D01*
G01X-1157585Y664240D02*
X-1157543Y664175D01*
G01X-1157600Y664314D02*
X-1157585Y664240D01*
G01X-1173096Y700999D02*
X-1172914Y700381D01*
G01X-1173211Y701482D02*
X-1173096Y700999D01*
G01X-1173280Y701902D02*
X-1173211Y701482D01*
G01X-1158922Y700999D02*
X-1158740Y700381D01*
G01X-1159038Y701482D02*
X-1158922Y700999D01*
G01X-1159107Y701902D02*
X-1159038Y701482D01*
G01X-1168966Y674703D02*
X-1168958Y674610D01*
G01X-1168976Y674788D02*
X-1168966Y674703D01*
G01X-1168988Y674865D02*
X-1168976Y674788D01*
G01X-1172586Y669442D02*
X-1172499Y669432D01*
G01X-1172667Y669472D02*
X-1172586Y669442D01*
G01X-1172741Y669518D02*
X-1172667Y669472D01*
G01X-1172802Y669582D02*
X-1172741Y669518D01*
G01X-1172848Y669656D02*
X-1172802Y669582D01*
G01X-1172877Y669739D02*
X-1172848Y669656D01*
G01X-1172886Y669826D02*
X-1172877Y669739D01*
G01X-1158413Y669442D02*
X-1158325Y669432D01*
G01X-1158494Y669472D02*
X-1158413Y669442D01*
G01X-1158567Y669518D02*
X-1158494Y669472D01*
G01X-1158629Y669582D02*
X-1158567Y669518D01*
G01X-1158675Y669656D02*
X-1158629Y669582D01*
G01X-1158703Y669739D02*
X-1158675Y669656D01*
G01X-1158713Y669826D02*
X-1158703Y669739D01*
G01X-1154802Y674788D02*
X-1154814Y674865D01*
G01X-1154792Y674703D02*
X-1154802Y674788D01*
G01X-1154784Y674610D02*
X-1154792Y674703D01*
G01X-1159237Y698430D02*
X-1159304Y698650D01*
G01X-1159196Y698205D02*
X-1159237Y698430D01*
G01X-1159183Y697977D02*
X-1159196Y698205D01*
G01X-1158859Y698521D02*
X-1158939Y698784D01*
G01X-1158811Y698251D02*
X-1158859Y698521D01*
G01X-1158795Y697977D02*
X-1158811Y698251D01*
G01X-1159448Y698431D02*
X-1159514Y698650D01*
G01X-1159408Y698205D02*
X-1159448Y698431D01*
G01X-1159394Y697977D02*
X-1159408Y698205D01*
G01X-1158834Y700161D02*
X-1158900Y700381D01*
G01X-1158794Y699936D02*
X-1158834Y700161D01*
G01X-1158780Y699707D02*
X-1158794Y699936D01*
G01X-1159780Y674406D02*
X-1159779Y674309D01*
G01X-1159781Y674507D02*
X-1159780Y674406D01*
G01X-1159782Y674610D02*
X-1159781Y674507D01*
G01X-1154782Y674510D02*
X-1154784Y674610D01*
G01X-1154781Y674409D02*
X-1154782Y674510D01*
G01X-1173571Y674412D02*
Y669826D01*
G01X-1173570Y674513D02*
X-1173571Y674412D01*
G01X-1173567Y674610D02*
X-1173570Y674513D01*
G01X-1159398Y674412D02*
Y669826D01*
G01X-1159396Y674513D02*
X-1159398Y674412D01*
G01X-1159394Y674610D02*
X-1159396Y674513D01*
G01X-1173172Y674505D02*
X-1173150Y674587D01*
G01X-1173185Y674410D02*
X-1173172Y674505D01*
G01X-1173190Y674309D02*
X-1173185Y674410D01*
G01X-1158998Y674505D02*
X-1158976Y674587D01*
G01X-1159012Y674410D02*
X-1158998Y674505D01*
G01X-1159017Y674309D02*
X-1159012Y674410D01*
G01X-1168904Y698430D02*
X-1168838Y698650D01*
G01X-1168944Y698205D02*
X-1168904Y698430D01*
G01X-1168958Y697977D02*
X-1168944Y698205D01*
G01X-1154731Y698430D02*
X-1154665Y698650D01*
G01X-1154771Y698205D02*
X-1154731Y698430D01*
G01X-1154784Y697977D02*
X-1154771Y698205D01*
G01X-1169626Y700169D02*
X-1169572Y700381D01*
G01X-1169660Y699954D02*
X-1169626Y700169D01*
G01X-1169674Y699741D02*
X-1169660Y699954D01*
G01X-1155453Y700169D02*
X-1155399Y700381D01*
G01X-1155487Y699954D02*
X-1155453Y700169D01*
G01X-1155500Y699741D02*
X-1155487Y699954D01*
G01X-1173549Y674788D02*
X-1173537Y674865D01*
G01X-1173559Y674703D02*
X-1173549Y674788D01*
G01X-1173567Y674610D02*
X-1173559Y674703D01*
G01X-1159386Y674702D02*
X-1159394Y674610D01*
G01X-1159376Y674788D02*
X-1159386Y674702D01*
G01X-1159364Y674865D02*
X-1159376Y674788D01*
G01X-1169391Y700996D02*
X-1169572Y700381D01*
G01X-1169275Y701478D02*
X-1169391Y700996D01*
G01X-1169206Y701902D02*
X-1169275Y701478D01*
G01X-1155218Y700996D02*
X-1155399Y700381D01*
G01X-1155102Y701478D02*
X-1155218Y700996D01*
G01X-1155033Y701902D02*
X-1155102Y701478D01*
G01X-1168312Y664133D02*
X-1168388Y664117D01*
G01X-1168248Y664176D02*
X-1168312Y664133D01*
G01X-1168205Y664240D02*
X-1168248Y664176D01*
G01X-1168191Y664314D02*
X-1168205Y664240D01*
G01X-1161225Y664133D02*
X-1161301Y664117D01*
G01X-1161161Y664176D02*
X-1161225Y664133D01*
G01X-1161119Y664240D02*
X-1161161Y664176D01*
G01X-1161104Y664314D02*
X-1161119Y664240D01*
G01X-1154139Y664133D02*
X-1154214Y664117D01*
G01X-1154075Y664176D02*
X-1154139Y664133D01*
G01X-1154032Y664240D02*
X-1154075Y664176D01*
G01X-1154018Y664314D02*
X-1154032Y664240D01*
G01X-1169518Y699936D02*
X-1169532Y699707D01*
G01X-1169478Y700161D02*
X-1169518Y699936D01*
G01X-1169412Y700381D02*
X-1169478Y700161D01*
G01X-1155345Y699936D02*
X-1155359Y699707D01*
G01X-1155305Y700161D02*
X-1155345Y699936D01*
G01X-1155239Y700381D02*
X-1155305Y700161D01*
G01X-1169541Y698251D02*
X-1169557Y697977D01*
G01X-1169492Y698521D02*
X-1169541Y698251D01*
G01X-1169412Y698784D02*
X-1169492Y698521D01*
G01X-1155367Y698251D02*
X-1155384Y697977D01*
G01X-1155319Y698521D02*
X-1155367Y698251D01*
G01X-1155239Y698784D02*
X-1155319Y698521D01*
G01X-1169156Y698205D02*
X-1169169Y697977D01*
G01X-1169115Y698430D02*
X-1169156Y698205D01*
G01X-1169048Y698650D02*
X-1169115Y698430D01*
G01X-1154982Y698205D02*
X-1154996Y697977D01*
G01X-1154942Y698430D02*
X-1154982Y698205D01*
G01X-1154875Y698650D02*
X-1154942Y698430D01*
G01X-1155121Y674600D02*
X-1155202Y674587D01*
G01X-1155045Y674625D02*
X-1155121Y674600D01*
G01X-1154974Y674660D02*
X-1155045Y674625D01*
G01X-1154914Y674703D02*
X-1154974Y674660D01*
G01X-1154866Y674753D02*
X-1154914Y674703D01*
G01X-1154832Y674808D02*
X-1154866Y674753D01*
G01X-1154814Y674865D02*
X-1154832Y674808D01*
G01X-1168622Y702103D02*
X-1168558Y702110D01*
G01X-1168681Y702084D02*
X-1168622Y702103D01*
G01X-1168737Y702052D02*
X-1168681Y702084D01*
G01X-1168784Y702010D02*
X-1168737Y702052D01*
G01X-1168822Y701960D02*
X-1168784Y702010D01*
G01X-1168850Y701902D02*
X-1168822Y701960D01*
G01X-1167618Y702103D02*
X-1167554Y702110D01*
G01X-1167678Y702084D02*
X-1167618Y702103D01*
G01X-1167733Y702052D02*
X-1167678Y702084D01*
G01X-1167780Y702010D02*
X-1167733Y702052D01*
G01X-1167819Y701960D02*
X-1167780Y702010D01*
G01X-1167846Y701902D02*
X-1167819Y701960D01*
G01X-1169964Y699951D02*
X-1169847Y700155D01*
G01X-1170061Y699747D02*
X-1169964Y699951D01*
G01X-1154448Y702103D02*
X-1154385Y702110D01*
G01X-1154508Y702084D02*
X-1154448Y702103D01*
G01X-1154564Y702052D02*
X-1154508Y702084D01*
G01X-1154611Y702010D02*
X-1154564Y702052D01*
G01X-1154649Y701960D02*
X-1154611Y702010D01*
G01X-1154676Y701902D02*
X-1154649Y701960D01*
G01X-1153445Y702103D02*
X-1153381Y702110D01*
G01X-1153504Y702084D02*
X-1153445Y702103D01*
G01X-1153560Y702052D02*
X-1153504Y702084D01*
G01X-1153607Y702010D02*
X-1153560Y702052D01*
G01X-1153645Y701960D02*
X-1153607Y702010D01*
G01X-1153673Y701902D02*
X-1153645Y701960D01*
G01X-1155791Y699951D02*
X-1155674Y700155D01*
G01X-1155888Y699747D02*
X-1155791Y699951D01*
G01X-1169545Y700631D02*
X-1169477Y700764D01*
G01X-1169624Y700496D02*
X-1169545Y700631D01*
G01X-1169847Y700155D02*
X-1169624Y700496D01*
G01X-1155372Y700631D02*
X-1155304Y700764D01*
G01X-1155451Y700496D02*
X-1155372Y700631D01*
G01X-1155674Y700155D02*
X-1155451Y700496D01*
G01X-1161216Y664136D02*
X-1161301Y664117D01*
G01X-1161153Y664184D02*
X-1161216Y664136D01*
G01X-1161109Y664251D02*
X-1161153Y664184D01*
G01X-1173040Y702079D02*
X-1172817Y702110D01*
G01X-1173198Y702002D02*
X-1173040Y702079D01*
G01X-1173280Y701902D02*
X-1173198Y702002D01*
G01X-1158867Y702079D02*
X-1158644Y702110D01*
G01X-1159025Y702002D02*
X-1158867Y702079D01*
G01X-1159107Y701902D02*
X-1159025Y702002D01*
G01X-1175386Y664130D02*
X-1175427Y664124D01*
G01X-1175346Y664145D02*
X-1175386Y664130D01*
G01X-1175309Y664170D02*
X-1175346Y664145D01*
G01X-1175277Y664203D02*
X-1175309Y664170D01*
G01X-1154858Y700240D02*
G03X-1154953Y699707I1440J-532D01*
G01X-1159800Y697977D02*
G03X-1159895Y698509I-1535J0D01*
G01X-1159186Y699707D02*
G03X-1159282Y700240I-1536J-1D01*
G01X-1154283Y698509D02*
G03X-1154378Y697977I1440J-532D01*
G01X-1159411Y669826D02*
G03X-1159017Y669432I394J0D01*
G01X-1161616Y669039D02*
G03X-1162010Y669432I-393J0D01*
G01X-1156695D02*
G03X-1157088Y669039I0J-393D01*
G01X-1154529D02*
G03X-1154923Y669432I-393J0D01*
G01X-1159765Y669826D02*
G03X-1159017Y669078I748J0D01*
G01X-1161617Y656440D02*
G03I-709J0D01*
G01Y652110D02*
G03I-709J0D01*
G01X-1154531Y647385D02*
G03I-708J0D01*
G01X-1169031Y700240D02*
G03X-1169126Y699707I1440J-532D01*
G01X-1173973Y697977D02*
G03X-1174068Y698509I-1535J0D01*
G01X-1173360Y699707D02*
G03X-1173455Y700240I-1535J1D01*
G01X-1168456Y698509D02*
G03X-1168552Y697977I1440J-534D01*
G01X-1173584Y669826D02*
G03X-1173190Y669432I394J0D01*
G01X-1175789Y669039D02*
G03X-1176183Y669432I-393J0D01*
G01X-1177955D02*
G03X-1178348Y669039I0J-393D01*
G01X-1163781Y669432D02*
G03X-1164175Y669039I0J-394D01*
G01X-1170868Y669432D02*
G03X-1171262Y669039I0J-394D01*
G01X-1168703D02*
G03X-1169096Y669432I-393J0D01*
G01X-1175790Y652110D02*
G03I-709J0D01*
G01X-1168704Y647385D02*
G03I-708J0D01*
G01X-1175790Y656440D02*
G03I-709J0D01*
G01X-1173938Y669826D02*
G03X-1173190Y669078I748J0D01*
G01X-1189885Y662346D02*
G03X-1185948I1969J0D01*
G01X-1189885D02*
G03X-1185948I1969J0D01*
G01X-1161617Y646598D02*
G03I-709J0D01*
G01X-1154531Y641873D02*
G03I-708J0D01*
G01X-1161617Y642267D02*
G03I-709J0D01*
G01X-1168704Y641873D02*
G03I-708J0D01*
G01X-1175790Y646598D02*
G03I-709J0D01*
G01Y642267D02*
G03I-709J0D01*
G01X-1175243Y638790D02*
G03Y640570I-1299J890D01*
G01Y646113D02*
G03Y647892I-1299J889D01*
G01X-1178314D02*
G03Y646113I1300J-890D01*
G01Y640570D02*
G03Y638790I1300J-890D01*
G01X-1159463Y701902D02*
X-1159837Y701795D01*
G01X-1161090D02*
X-1160716Y701902D01*
G01X-1173636D02*
X-1174010Y701795D01*
G01X-1175263D02*
X-1174889Y701902D01*
G01X-1158939Y698784D02*
X-1159304Y698650D01*
G01X-1159514D02*
X-1159878Y698515D01*
G01X-1158900Y700381D02*
X-1159265Y700246D01*
G01X-1173113Y698784D02*
X-1173477Y698650D01*
G01X-1173687D02*
X-1174051Y698515D01*
G01X-1173074Y700381D02*
X-1173438Y700246D01*
G01X-1152674Y702110D02*
X-1154019Y700764D01*
G01X-1159760Y702110D02*
X-1161106Y700764D01*
G01X-1166847Y702110D02*
X-1168192Y700764D01*
G01X-1173934Y702110D02*
X-1175279Y700764D01*
G01X-1153944Y650530D02*
X-1152566Y652917D01*
G01X-1161030Y650530D02*
X-1159652Y652917D01*
G01X-1168117Y650530D02*
X-1166739Y652917D01*
G01X-1175203Y650530D02*
X-1173825Y652917D01*
G01X-1180912D02*
X-1182290Y650530D01*
G01X-1153088Y701795D02*
X-1154300Y698515D01*
G01X-1154665Y698650D02*
X-1153463Y701902D01*
G01X-1153673D02*
X-1154875Y698650D01*
G01X-1155239Y698785D02*
X-1154127Y701795D01*
G01X-1154874Y700246D02*
X-1154314Y701763D01*
G01X-1154676Y701902D02*
X-1155239Y700381D01*
G01X-1167261Y701795D02*
X-1168473Y698515D01*
G01X-1168838Y698650D02*
X-1167636Y701902D01*
G01X-1167846D02*
X-1169048Y698650D01*
G01X-1169412Y698785D02*
X-1168300Y701795D01*
G01X-1169048Y700246D02*
X-1168487Y701763D01*
G01X-1168850Y701902D02*
X-1169412Y700381D01*
G01X-1158795Y675616D02*
X-1158976Y674587D01*
G01X-1159364Y674865D02*
X-1159183Y675895D01*
G01X-1172968Y675616D02*
X-1173150Y674587D01*
G01X-1173537Y674865D02*
X-1173356Y675895D01*
G01X-1158325Y669629D02*
X-1158251Y670364D01*
G01X-1158638Y670561D02*
X-1158713Y669826D01*
G01X-1172499Y669629D02*
X-1172424Y670364D01*
G01X-1172812Y670561D02*
X-1172886Y669826D01*
G01X-1155500Y699741D02*
X-1155501Y699707D01*
G01X-1155888D02*
Y699747D01*
G01X-1169674Y699741D02*
Y699707D01*
G01X-1170062D02*
X-1170061Y699747D01*
G01X-1154399Y674309D02*
X-1154397Y674610D01*
G01X-1168572Y674309D02*
X-1168570Y674610D01*
G01X-1154524Y669013D02*
X-1154523Y669432D01*
G01X-1168697Y669013D02*
X-1168696Y669432D01*
G01X-1153088Y701795D02*
Y702110D01*
G01X-1154018Y663527D02*
Y674412D01*
G01X-1154127Y701795D02*
Y702110D01*
G01X-1154214Y664117D02*
Y673993D01*
G01X-1154314Y702110D02*
Y694236D01*
G01X-1154397Y674610D02*
Y697977D01*
G01X-1154399Y669432D02*
Y674309D01*
G01X-1154529Y669039D02*
Y665102D01*
G01X-1154781Y674409D02*
X-1154780Y669406D01*
G01X-1154784Y674610D02*
Y697977D01*
G01X-1154971Y699707D02*
Y669432D01*
G01X-1154996Y697977D02*
Y675895D01*
G01X-1155162Y669432D02*
Y674309D01*
G01X-1155359Y699707D02*
Y669432D01*
G01X-1155384Y675616D02*
Y697977D01*
G01X-1155501Y699707D02*
Y669432D01*
G01X-1155888D02*
Y699707D01*
G01X-1157088Y670561D02*
Y665102D01*
G01X-1157403Y673993D02*
Y664117D01*
G01X-1157600Y674412D02*
Y663527D01*
G01X-1158251Y670364D02*
Y699707D01*
G01X-1158325Y669629D02*
Y669432D01*
G01X-1158369D02*
Y669039D01*
G01X-1158638Y699707D02*
Y670561D01*
G01X-1158780Y669826D02*
Y699707D01*
G01X-1158795Y675616D02*
Y697977D01*
G01X-1159017Y669064D02*
Y674309D01*
G01X-1159168Y669826D02*
Y699707D01*
G01X-1159183Y675895D02*
Y697977D01*
G01X-1159394D02*
Y674610D01*
G01X-1159779Y674309D02*
Y669826D01*
G01X-1159782Y697977D02*
Y674610D01*
G01X-1159837Y702110D02*
Y701795D01*
G01X-1160052D02*
Y702110D01*
G01X-1161090D02*
Y701795D01*
G01X-1161104Y663527D02*
Y675174D01*
G01X-1161115D02*
X-1161114Y664251D01*
G01X-1161237Y702110D02*
Y694236D01*
G01X-1161301Y675174D02*
Y664117D01*
G01X-1161616Y669039D02*
Y665102D01*
G01X-1161926Y699157D02*
Y675174D01*
G01X-1164175Y669039D02*
Y665102D01*
G01X-1164490Y675174D02*
Y664117D01*
G01X-1164687Y675174D02*
Y663527D01*
G01X-1165666Y664117D02*
Y699157D01*
G01X-1165764Y694236D02*
Y702110D01*
G01X-1165852Y699157D02*
Y664251D01*
G01X-1165863D02*
Y663527D01*
G01X-1166125Y702110D02*
Y694236D01*
G01X-1167261Y701795D02*
Y702110D01*
G01X-1168191Y663527D02*
Y674412D01*
G01X-1168300Y701795D02*
Y702110D01*
G01X-1168388Y664117D02*
Y673993D01*
G01X-1168487Y702110D02*
Y694236D01*
G01X-1168570Y674610D02*
Y697977D01*
G01X-1168572Y669432D02*
Y674309D01*
G01X-1168703Y669039D02*
Y665102D01*
G01X-1168954Y674409D02*
Y669406D01*
G01X-1168958Y674610D02*
Y697977D01*
G01X-1169144Y699707D02*
Y669432D01*
G01X-1169169Y675895D02*
Y697977D01*
G01X-1169335Y669432D02*
Y674309D01*
G01X-1169532Y699707D02*
Y669432D01*
G01X-1169557Y675616D02*
Y697977D01*
G01X-1169674Y699707D02*
Y669432D01*
G01X-1170062D02*
Y699707D01*
G01X-1158639Y699741D02*
X-1158638Y699707D01*
G01X-1158251Y699747D02*
Y699707D01*
G01X-1154996Y675895D02*
X-1154814Y674865D01*
G01X-1155202Y674587D02*
X-1155384Y675616D01*
G01X-1169169Y675895D02*
X-1168988Y674865D01*
G01X-1169375Y674587D02*
X-1169557Y675616D01*
G01X-1158900Y700381D02*
X-1159463Y701902D01*
G01X-1175427Y664124D02*
X-1175434Y663527D01*
G01X-1175423Y675174D02*
X-1175427Y664124D01*
G01X-1171262Y670561D02*
Y665102D01*
G01X-1171577Y673993D02*
Y664117D01*
G01X-1171773Y674412D02*
Y663527D01*
G01X-1172424Y670364D02*
Y699707D01*
G01X-1172499Y669629D02*
Y669432D01*
G01X-1172542D02*
Y669039D01*
G01X-1172812Y699707D02*
Y670561D01*
G01X-1172954Y669826D02*
Y699707D01*
G01X-1172968Y675616D02*
Y697977D01*
G01X-1173190Y669064D02*
Y674309D01*
G01X-1173341Y669826D02*
Y699707D01*
G01X-1173356Y675895D02*
Y697977D01*
G01X-1173567D02*
Y674610D01*
G01X-1173953Y674309D02*
Y669826D01*
G01X-1173955Y697977D02*
Y674610D01*
G01X-1174010Y701795D02*
Y702110D01*
G01X-1174225Y701795D02*
Y702110D01*
G01X-1175203Y647832D02*
Y650530D01*
G01Y640509D02*
Y646173D01*
G01X-1175243Y646113D02*
Y640570D01*
G01Y653921D02*
Y647892D01*
G01X-1175263Y702110D02*
Y701795D01*
G01X-1175277Y664203D02*
Y663527D01*
G01X-1175410Y702110D02*
Y694236D01*
G01X-1175474Y664117D02*
Y675174D01*
G01X-1175789Y669039D02*
Y665102D01*
G01X-1175888Y669275D02*
Y665338D01*
G01X-1178250Y669275D02*
Y665338D01*
G01X-1178314Y647892D02*
Y653921D01*
G01Y640570D02*
Y646113D01*
G01X-1178348Y669039D02*
Y665102D01*
G01X-1178353Y646173D02*
Y640509D01*
G01Y650530D02*
Y647832D01*
G01X-1178663Y675174D02*
Y664117D01*
G01X-1178860Y664203D02*
Y663527D01*
G01X-1180823Y702110D02*
Y663527D01*
G01X-1189885Y1196849D02*
Y662346D01*
G01Y1196849D02*
Y662346D01*
G01X-1178714Y675174D02*
X-1178711Y664124D01*
G01X-1172812Y699741D02*
Y699707D01*
G01X-1172424Y699747D02*
Y699707D01*
G01X-1178703Y663527D02*
X-1178710Y664124D01*
G01X-1159837Y701795D02*
X-1159265Y700246D01*
G01X-1160052Y701795D02*
X-1158939Y698784D01*
G01X-1159304Y698650D02*
X-1160506Y701902D01*
G01X-1160716D02*
X-1159514Y698650D01*
G01X-1159878Y698515D02*
X-1161090Y701795D01*
G01X-1173074Y700381D02*
X-1173636Y701902D01*
G01X-1174010Y701795D02*
X-1173438Y700246D01*
G01X-1174225Y701795D02*
X-1173113Y698784D01*
G01X-1173477Y698650D02*
X-1174679Y701902D01*
G01X-1174889D02*
X-1173687Y698650D01*
G01X-1174051Y698515D02*
X-1175263Y701795D01*
G01X-1158471Y652917D02*
X-1157093Y650530D01*
G01X-1165558Y652917D02*
X-1164180Y650530D01*
G01X-1172644Y652917D02*
X-1171266Y650530D01*
G01X-1179731Y652917D02*
X-1178353Y650530D01*
G01X-1157234Y700764D02*
X-1158579Y702110D01*
G01X-1164321Y700764D02*
X-1165666Y702110D01*
G01X-1171408Y700764D02*
X-1172753Y702110D01*
G01X-1178494Y700764D02*
X-1179839Y702110D01*
G01X-1155239Y700381D02*
X-1154874Y700246D01*
G01X-1154300Y698515D02*
X-1154665Y698650D01*
G01X-1154875D02*
X-1155239Y698784D01*
G01X-1169412Y700381D02*
X-1169048Y700246D01*
G01X-1153463Y701902D02*
X-1153088Y701795D01*
G01X-1154676Y701902D02*
X-1154314Y701798D01*
G01X-1167636Y701902D02*
X-1167261Y701795D01*
G01X-1168850Y701902D02*
X-1168487Y701798D01*
G01X-1155888Y699747D02*
X-1155500Y699741D01*
G01X-1170061Y699747D02*
X-1169674Y699741D01*
G01X-1180823Y702110D02*
X-1124524D01*
G01X-1159463Y701902D02*
X-1159107D01*
G01X-1173636D02*
X-1173280D01*
G01X-1155033D02*
X-1154676D01*
G01X-1169206D02*
X-1168850D01*
G01X-1174679D02*
X-1174889D01*
G01X-1167636D02*
X-1167846D01*
G01X-1160506D02*
X-1160716D01*
G01X-1153463D02*
X-1153673D01*
G01X-1180823Y701795D02*
X-1168300D01*
G01X-1154127D02*
X-1167261D01*
G01X-1139953D02*
X-1153088D01*
G01X-1175410Y701622D02*
X-1180823D01*
G01X-1161237D02*
X-1165764D01*
G01X-1166125D02*
X-1168487D01*
G01X-1151951D02*
X-1154314D01*
G01X-1175279Y700764D02*
X-1178494D01*
G01X-1168192D02*
X-1173009D01*
G01X-1161106D02*
X-1164321D01*
G01X-1154019D02*
X-1158836D01*
G01X-1155399Y700381D02*
X-1155239D01*
G01X-1169572D02*
X-1169412D01*
G01X-1172914D02*
X-1173074D01*
G01X-1158740D02*
X-1158900D01*
G01X-1155888Y699707D02*
X-1154971D01*
G01X-1159168D02*
X-1158251D01*
G01X-1170062D02*
X-1169144D01*
G01X-1173341D02*
X-1172424D01*
G01X-1161926Y699157D02*
X-1165852D01*
G01X-1173477Y698650D02*
X-1173687D01*
G01X-1159304D02*
X-1159514D01*
G01X-1168838D02*
X-1169048D01*
G01X-1154665D02*
X-1154875D01*
G01X-1155384Y697977D02*
X-1154397D01*
G01X-1159782D02*
X-1158795D01*
G01X-1169557D02*
X-1168570D01*
G01X-1173955D02*
X-1172968D01*
G01X-1172424Y699747D02*
X-1172812Y699741D01*
G01X-1158251Y699747D02*
X-1158639Y699741D01*
G01X-1168300Y701795D02*
X-1167923Y701883D01*
G01X-1154127Y701795D02*
X-1153749Y701883D01*
G01X-1167923D02*
X-1167846Y701902D01*
G01X-1153749Y701883D02*
X-1153673Y701902D01*
G01X-1168838Y698650D02*
X-1168473Y698515D01*
G01X-1169048Y698650D02*
X-1169412Y698784D01*
G01X-1175410Y694236D02*
X-1180823D01*
G01X-1161237D02*
X-1165764D01*
G01X-1166125D02*
X-1168487D01*
G01X-1151951D02*
X-1154314D01*
G01X-1159183Y675895D02*
X-1154996D01*
G01X-1173356D02*
X-1169169D01*
G01X-1169557Y675616D02*
X-1172968D01*
G01X-1155384D02*
X-1158795D01*
G01X-1178714Y675174D02*
X-1175423D01*
G01X-1180335D02*
X-1180823D01*
G01X-1161104D02*
X-1164687D01*
G01X-1154784Y674610D02*
X-1154397D01*
G01X-1168958D02*
X-1168570D01*
G01X-1173567D02*
X-1173955D01*
G01X-1159394D02*
X-1159782D01*
G01X-1158976Y674587D02*
X-1155202D01*
G01X-1173150D02*
X-1169375D01*
G01X-1168191Y674412D02*
X-1171773D01*
G01X-1154018D02*
X-1157600D01*
G01X-1159779Y674309D02*
X-1154399D01*
G01X-1173953D02*
X-1168572D01*
G01X-1168388Y673993D02*
X-1171577D01*
G01X-1154214D02*
X-1157403D01*
G01X-1158638Y670561D02*
X-1157088D01*
G01X-1172812D02*
X-1171262D01*
G01X-1158251Y670364D02*
X-1157088D01*
G01X-1172424D02*
X-1171262D01*
G01X-1173953Y669826D02*
X-1171262D01*
G01X-1157088D02*
X-1159779D01*
G01X-1158325Y669629D02*
X-1157088D01*
G01X-1172499D02*
X-1171262D01*
G01X-1159017Y669445D02*
X-1157088D01*
G01X-1173190D02*
X-1171262D01*
G01X-1176183Y669432D02*
X-1177955D01*
G01X-1171262D02*
X-1172542D01*
G01X-1169096D02*
X-1170868D01*
G01X-1168572D02*
X-1168703D01*
G01X-1162010D02*
X-1163781D01*
G01X-1154923D02*
X-1156695D01*
G01X-1157088D02*
X-1158369D01*
G01X-1154399D02*
X-1154529D01*
G01X-1175888Y669275D02*
X-1178250D01*
G01X-1159017Y669064D02*
X-1157088D01*
G01X-1173190D02*
X-1171262D01*
G01Y669039D02*
X-1172542D01*
G01X-1157088D02*
X-1158369D01*
G01X-1178348Y666936D02*
X-1180823D01*
G01X-1171262D02*
X-1175789D01*
G01X-1164175D02*
X-1168703D01*
G01X-1157088D02*
X-1161616D01*
G01X-1150002D02*
X-1154529D01*
G01X-1175888Y666913D02*
X-1178250D01*
G01X-1154529Y666739D02*
X-1150002D01*
G01X-1161616D02*
X-1157088D01*
G01X-1175789D02*
X-1171262D01*
G01X-1180823D02*
X-1178348D01*
G01X-1164175D02*
X-1168703D01*
G01X-1175888Y665338D02*
X-1178250D01*
G01X-1175789Y665102D02*
X-1178348D01*
G01X-1168703D02*
X-1171262D01*
G01X-1161616D02*
X-1164175D01*
G01X-1154529D02*
X-1157088D01*
G01X-1124524Y664117D02*
X-1180823D01*
G01X-1157600Y663606D02*
X-1154018D01*
G01X-1168191D02*
X-1171773D01*
G01X-1124197Y663527D02*
X-1180823D01*
G01X-1124197Y662739D02*
X-1180335D01*
G01X-1185948Y662346D02*
X-1033979D01*
G01X-1185948D02*
X-1033979D01*
G01X-1175243Y653921D02*
X-1128707D01*
G01X-1178314D02*
X-1180335D01*
G01X-1180912Y652917D02*
X-1179731D01*
G01X-1172644D02*
X-1173825D01*
G01X-1165558D02*
X-1166739D01*
G01X-1158471D02*
X-1159652D01*
G01X-1151385D02*
X-1152566D01*
G01X-1153747Y650871D02*
X-1150203D01*
G01X-1160833D02*
X-1157290D01*
G01X-1167920D02*
X-1164377D01*
G01X-1175007D02*
X-1171463D01*
G01X-1199885Y1217779D02*
Y1003330D01*
G01X-1189885Y1200786D02*
Y1272188D01*
G01Y1196849D02*
G03X-1190301Y1198610I-3937J0D01*
G01X-1189885Y1196849D02*
G03X-1190301Y1198610I-3937J0D01*
G01D02*
X-1208482Y1234973D01*
G01D02*
X-1190301Y1198610D01*
G01X-1183210Y1249666D02*
X-1060795D01*
G01X-1186360D02*
X-1183210D01*
G01X-1208482Y1234973D02*
G03X-1212003Y1237149I-3521J-1761D01*
G01X-1208482Y1234973D02*
G03X-1212003Y1237149I-3521J-1761D01*
G01X-1201779Y1351519D02*
X-892277D01*
G01X-1204928D02*
X-1201779D01*
G01X-1111214Y-368548D02*
Y-564375D01*
G01X-1106381Y-402908D02*
X-998410Y-643706D01*
G01X-1106670Y-365977D02*
X-1065829Y-378259D01*
G01X-1107853Y-395859D02*
X-1053949Y-455666D01*
G01X-1106469Y-364611D02*
G03I-4745J0D01*
G01X-1106194Y-392131D02*
G03I-5020J0D01*
G01X-1099403D02*
G03I-11811J0D01*
G01X-1072838Y557620D02*
X-1082024Y552929D01*
G01X-1086617D02*
X-1074150Y559630D01*
G01X-1091867Y568342D02*
Y536846D01*
G01X-1095804Y555609D02*
Y568342D01*
G01Y536846D02*
Y551589D01*
G01X-1114176D02*
Y536846D01*
G01Y568342D02*
Y555609D01*
G01X-1118113Y536846D02*
Y568342D01*
G01X-1074150Y546228D02*
X-1086617Y552929D01*
G01X-1082024D02*
X-1072838Y548238D01*
G01X-1114176Y555609D02*
X-1095804D01*
G01Y551589D02*
X-1114176D01*
G01Y536846D02*
X-1118113D01*
G01X-1091867D02*
X-1095804D01*
G01X-1100530Y595532D02*
X-1100455Y595909D01*
G01X-1100744Y595213D02*
X-1100530Y595532D01*
G01X-1101063Y594999D02*
X-1100744Y595213D01*
G01X-1101439Y594925D02*
X-1101063Y594999D01*
G01X-1118097Y602191D02*
X-1118172Y601814D01*
G01X-1117884Y602510D02*
X-1118097Y602191D01*
G01X-1117564Y602724D02*
X-1117884Y602510D01*
G01X-1117188Y602799D02*
X-1117564Y602724D01*
G01X-1100530Y619548D02*
X-1100455Y619924D01*
G01X-1100744Y619229D02*
X-1100530Y619548D01*
G01X-1101063Y619015D02*
X-1100744Y619229D01*
G01X-1101439Y618940D02*
X-1101063Y619015D01*
G01X-1100704Y595911D02*
X-1100679Y596132D01*
G01X-1100777Y595704D02*
X-1100704Y595911D01*
G01X-1100894Y595519D02*
X-1100777Y595704D01*
G01X-1101052Y595361D02*
X-1100894Y595519D01*
G01X-1101238Y595245D02*
X-1101052Y595361D01*
G01X-1101445Y595173D02*
X-1101238Y595245D01*
G01X-1101663Y595148D02*
X-1101445Y595173D01*
G01X-1104267Y609745D02*
X-1104403Y609744D01*
G01X-1104131Y609747D02*
X-1104267Y609745D01*
G01X-1114361Y611443D02*
X-1114496Y611441D01*
G01X-1114225Y611444D02*
X-1114361Y611443D01*
G01X-1109879Y605409D02*
X-1110161Y605411D01*
G01X-1109596Y605407D02*
X-1109879Y605409D01*
G01X-1109031Y605407D02*
X-1109596D01*
G01X-1108749Y615779D02*
X-1108467Y615776D01*
G01X-1109031Y615781D02*
X-1108749Y615779D01*
G01X-1109596Y615781D02*
X-1109031D01*
G01X-1114225Y609744D02*
X-1112814D01*
G01X-1114361Y609745D02*
X-1114225Y609744D01*
G01X-1114496Y609747D02*
X-1114361Y609745D01*
G01X-1104403Y611444D02*
X-1105814D01*
G01X-1104267Y611443D02*
X-1104403Y611444D01*
G01X-1104131Y611441D02*
X-1104267Y611443D01*
G01X-1117923Y595911D02*
X-1117948Y596132D01*
G01X-1117850Y595704D02*
X-1117923Y595911D01*
G01X-1117733Y595519D02*
X-1117850Y595704D01*
G01X-1117575Y595361D02*
X-1117733Y595519D01*
G01X-1117389Y595245D02*
X-1117575Y595361D01*
G01X-1117182Y595173D02*
X-1117389Y595245D01*
G01X-1116964Y595148D02*
X-1117182Y595173D01*
G01X-1100704Y601812D02*
X-1100679Y601591D01*
G01X-1100777Y602019D02*
X-1100704Y601812D01*
G01X-1100894Y602205D02*
X-1100777Y602019D01*
G01X-1101052Y602362D02*
X-1100894Y602205D01*
G01X-1101238Y602478D02*
X-1101052Y602362D01*
G01X-1101445Y602550D02*
X-1101238Y602478D01*
G01X-1101663Y602575D02*
X-1101445Y602550D01*
G01X-1118097Y626207D02*
X-1118172Y625830D01*
G01X-1117884Y626526D02*
X-1118097Y626207D01*
G01X-1117564Y626739D02*
X-1117884Y626526D01*
G01X-1117188Y626814D02*
X-1117564Y626739D01*
G01X-1100704Y619927D02*
X-1100679Y620148D01*
G01X-1100777Y619720D02*
X-1100704Y619927D01*
G01X-1100894Y619534D02*
X-1100777Y619720D01*
G01X-1101052Y619377D02*
X-1100894Y619534D01*
G01X-1101238Y619261D02*
X-1101052Y619377D01*
G01X-1101445Y619188D02*
X-1101238Y619261D01*
G01X-1101663Y619164D02*
X-1101445Y619188D01*
G01X-1117923Y625828D02*
X-1117948Y625607D01*
G01X-1117850Y626035D02*
X-1117923Y625828D01*
G01X-1117733Y626220D02*
X-1117850Y626035D01*
G01X-1117575Y626378D02*
X-1117733Y626220D01*
G01X-1117389Y626494D02*
X-1117575Y626378D01*
G01X-1117182Y626566D02*
X-1117389Y626494D01*
G01X-1116964Y626591D02*
X-1117182Y626566D01*
G01X-1100704Y625828D02*
X-1100679Y625607D01*
G01X-1100777Y626035D02*
X-1100704Y625828D01*
G01X-1100894Y626220D02*
X-1100777Y626035D01*
G01X-1101052Y626378D02*
X-1100894Y626220D01*
G01X-1101238Y626494D02*
X-1101052Y626378D01*
G01X-1101445Y626566D02*
X-1101238Y626494D01*
G01X-1101663Y626591D02*
X-1101445Y626566D01*
G01X-1118631Y595427D02*
X-1118550Y595191D01*
G01X-1118759Y595642D02*
X-1118631Y595427D01*
G01X-1118928Y595828D02*
X-1118759Y595642D01*
G01X-1119130Y595983D02*
X-1118928Y595828D01*
G01X-1119358Y596106D02*
X-1119130Y595983D01*
G01X-1097371Y595427D02*
X-1097290Y595191D01*
G01X-1097499Y595642D02*
X-1097371Y595427D01*
G01X-1097668Y595828D02*
X-1097499Y595642D01*
G01X-1097870Y595983D02*
X-1097668Y595828D01*
G01X-1098098Y596106D02*
X-1097870Y595983D01*
G01X-1146896Y594755D02*
X-1146867Y594391D01*
G01X-1146979Y595105D02*
X-1146896Y594755D01*
G01X-1147112Y595426D02*
X-1146979Y595105D01*
G01X-1147285Y595704D02*
X-1147112Y595426D01*
G01X-1147486Y595932D02*
X-1147285Y595704D01*
G01X-1147704Y596106D02*
X-1147486Y595932D01*
G01X-1139809Y594755D02*
X-1139780Y594391D01*
G01X-1139893Y595105D02*
X-1139809Y594755D01*
G01X-1140025Y595426D02*
X-1139893Y595105D01*
G01X-1140198Y595704D02*
X-1140025Y595426D01*
G01X-1140399Y595932D02*
X-1140198Y595704D01*
G01X-1140618Y596106D02*
X-1140399Y595932D01*
G01X-1132723Y594755D02*
X-1132694Y594391D01*
G01X-1132806Y595105D02*
X-1132723Y594755D01*
G01X-1132939Y595426D02*
X-1132806Y595105D01*
G01X-1133111Y595704D02*
X-1132939Y595426D01*
G01X-1133313Y595932D02*
X-1133111Y595704D01*
G01X-1133531Y596106D02*
X-1133313Y595932D01*
G01X-1125636Y594755D02*
X-1125607Y594391D01*
G01X-1125720Y595105D02*
X-1125636Y594755D01*
G01X-1125852Y595426D02*
X-1125720Y595105D01*
G01X-1126025Y595704D02*
X-1125852Y595426D01*
G01X-1126226Y595932D02*
X-1126025Y595704D01*
G01X-1126444Y596106D02*
X-1126226Y595932D01*
G01X-1118549Y594755D02*
X-1118520Y594391D01*
G01X-1118633Y595105D02*
X-1118549Y594755D01*
G01X-1118765Y595426D02*
X-1118633Y595105D01*
G01X-1118938Y595704D02*
X-1118765Y595426D01*
G01X-1119140Y595932D02*
X-1118938Y595704D01*
G01X-1119358Y596106D02*
X-1119140Y595932D01*
G01X-1111463Y594755D02*
X-1111434Y594391D01*
G01X-1111546Y595105D02*
X-1111463Y594755D01*
G01X-1111679Y595426D02*
X-1111546Y595105D01*
G01X-1111852Y595704D02*
X-1111679Y595426D01*
G01X-1112053Y595932D02*
X-1111852Y595704D01*
G01X-1112271Y596106D02*
X-1112053Y595932D01*
G01X-1104376Y594755D02*
X-1104347Y594391D01*
G01X-1104460Y595105D02*
X-1104376Y594755D01*
G01X-1104592Y595426D02*
X-1104460Y595105D01*
G01X-1104765Y595704D02*
X-1104592Y595426D01*
G01X-1104966Y595932D02*
X-1104765Y595704D01*
G01X-1105185Y596106D02*
X-1104966Y595932D01*
G01X-1097289Y594755D02*
X-1097260Y594391D01*
G01X-1097373Y595105D02*
X-1097289Y594755D01*
G01X-1097506Y595426D02*
X-1097373Y595105D01*
G01X-1097678Y595704D02*
X-1097506Y595426D01*
G01X-1097880Y595932D02*
X-1097678Y595704D01*
G01X-1098098Y596106D02*
X-1097880Y595932D01*
G01X-1090203Y594755D02*
X-1090174Y594391D01*
G01X-1090286Y595105D02*
X-1090203Y594755D01*
G01X-1090419Y595426D02*
X-1090286Y595105D01*
G01X-1090592Y595704D02*
X-1090419Y595426D01*
G01X-1090793Y595932D02*
X-1090592Y595704D01*
G01X-1091011Y596106D02*
X-1090793Y595932D01*
G01X-1083116Y594755D02*
X-1083087Y594391D01*
G01X-1083200Y595105D02*
X-1083116Y594755D01*
G01X-1083332Y595426D02*
X-1083200Y595105D01*
G01X-1083505Y595704D02*
X-1083332Y595426D01*
G01X-1083707Y595932D02*
X-1083505Y595704D01*
G01X-1083925Y596106D02*
X-1083707Y595932D01*
G01X-1147339Y595884D02*
X-1147704Y596106D01*
G01X-1147076Y595603D02*
X-1147339Y595884D01*
G01X-1146920Y595290D02*
X-1147076Y595603D01*
G01X-1146867Y594962D02*
X-1146920Y595290D01*
G01X-1140252Y595884D02*
X-1140618Y596106D01*
G01X-1139989Y595603D02*
X-1140252Y595884D01*
G01X-1139833Y595290D02*
X-1139989Y595603D01*
G01X-1139780Y594962D02*
X-1139833Y595290D01*
G01X-1133165Y595884D02*
X-1133531Y596106D01*
G01X-1132903Y595603D02*
X-1133165Y595884D01*
G01X-1132746Y595290D02*
X-1132903Y595603D01*
G01X-1132694Y594962D02*
X-1132746Y595290D01*
G01X-1118528Y595086D02*
X-1118550Y595207D01*
G01X-1118520Y594962D02*
X-1118528Y595086D01*
G01X-1117564Y594999D02*
X-1117188Y594925D01*
G01X-1117884Y595213D02*
X-1117564Y594999D01*
G01X-1118097Y595532D02*
X-1117884Y595213D01*
G01X-1118172Y595909D02*
X-1118097Y595532D01*
G01X-1117564Y619015D02*
X-1117188Y618940D01*
G01X-1117884Y619228D02*
X-1117564Y619015D01*
G01X-1118097Y619548D02*
X-1117884Y619228D01*
G01X-1118172Y619924D02*
X-1118097Y619548D01*
G01X-1101063Y602724D02*
X-1101439Y602799D01*
G01X-1100744Y602510D02*
X-1101063Y602724D01*
G01X-1100530Y602191D02*
X-1100744Y602510D01*
G01X-1100455Y601814D02*
X-1100530Y602191D01*
G01X-1101063Y626739D02*
X-1101439Y626814D01*
G01X-1100744Y626526D02*
X-1101063Y626739D01*
G01X-1100530Y626207D02*
X-1100744Y626526D01*
G01X-1100455Y625830D02*
X-1100530Y626207D01*
G01X-1126079Y595884D02*
X-1126444Y596106D01*
G01X-1125816Y595603D02*
X-1126079Y595884D01*
G01X-1125660Y595290D02*
X-1125816Y595603D01*
G01X-1125607Y594962D02*
X-1125660Y595290D01*
G01X-1111906Y595884D02*
X-1112271Y596106D01*
G01X-1111643Y595603D02*
X-1111906Y595884D01*
G01X-1111486Y595290D02*
X-1111643Y595603D01*
G01X-1111434Y594962D02*
X-1111486Y595290D01*
G01X-1104819Y595884D02*
X-1105185Y596106D01*
G01X-1104556Y595603D02*
X-1104819Y595884D01*
G01X-1104400Y595290D02*
X-1104556Y595603D01*
G01X-1104347Y594962D02*
X-1104400Y595290D01*
G01X-1090646Y595884D02*
X-1091011Y596106D01*
G01X-1090383Y595603D02*
X-1090646Y595884D01*
G01X-1090227Y595290D02*
X-1090383Y595603D01*
G01X-1090174Y594962D02*
X-1090227Y595290D01*
G01X-1117185Y619189D02*
X-1116964Y619164D01*
G01X-1117392Y619262D02*
X-1117185Y619189D01*
G01X-1117578Y619379D02*
X-1117392Y619262D01*
G01X-1117735Y619537D02*
X-1117578Y619379D01*
G01X-1117852Y619723D02*
X-1117735Y619537D01*
G01X-1117924Y619930D02*
X-1117852Y619723D01*
G01X-1117948Y620148D02*
X-1117924Y619930D01*
G01X-1097268Y595086D02*
X-1097290Y595207D01*
G01X-1097260Y594962D02*
X-1097268Y595086D01*
G01X-1114501Y610876D02*
X-1114496Y611441D01*
G01X-1114501Y610311D02*
Y610876D01*
G01X-1114496Y609747D02*
X-1114501Y610311D01*
G01X-1104127D02*
X-1104131Y609747D01*
G01X-1104127Y610876D02*
Y610311D01*
G01X-1104131Y611441D02*
X-1104127Y610876D01*
G01X-1110162Y605547D02*
X-1110161Y605411D01*
G01X-1110163Y605683D02*
X-1110162Y605547D01*
G01X-1108465Y615641D02*
X-1108467Y615776D01*
G01X-1108464Y615505D02*
X-1108465Y615641D01*
G01Y605547D02*
X-1108467Y605411D01*
G01X-1108464Y605683D02*
X-1108465Y605547D01*
G01X-1108464Y607094D02*
Y605683D01*
G01X-1110163Y615505D02*
X-1110164Y614094D01*
G01X-1110162Y615641D02*
X-1110163Y615505D01*
G01X-1110161Y615776D02*
X-1110162Y615641D01*
G01X-1121643Y595086D02*
X-1121621Y595207D01*
G01X-1121650Y594962D02*
X-1121643Y595086D01*
G01X-1149377Y595932D02*
X-1149159Y596106D01*
G01X-1149579Y595704D02*
X-1149377Y595932D01*
G01X-1149752Y595426D02*
X-1149579Y595704D01*
G01X-1149884Y595105D02*
X-1149752Y595426D01*
G01X-1149968Y594755D02*
X-1149884Y595105D01*
G01X-1149997Y594391D02*
X-1149968Y594755D01*
G01X-1142291Y595932D02*
X-1142073Y596106D01*
G01X-1142492Y595704D02*
X-1142291Y595932D01*
G01X-1142665Y595426D02*
X-1142492Y595704D01*
G01X-1142797Y595105D02*
X-1142665Y595426D01*
G01X-1142881Y594755D02*
X-1142797Y595105D01*
G01X-1142910Y594391D02*
X-1142881Y594755D01*
G01X-1135204Y595932D02*
X-1134986Y596106D01*
G01X-1135406Y595704D02*
X-1135204Y595932D01*
G01X-1135578Y595426D02*
X-1135406Y595704D01*
G01X-1135711Y595105D02*
X-1135578Y595426D01*
G01X-1135794Y594755D02*
X-1135711Y595105D01*
G01X-1135823Y594391D02*
X-1135794Y594755D01*
G01X-1128118Y595932D02*
X-1127899Y596106D01*
G01X-1128319Y595704D02*
X-1128118Y595932D01*
G01X-1128492Y595426D02*
X-1128319Y595704D01*
G01X-1128624Y595105D02*
X-1128492Y595426D01*
G01X-1128708Y594755D02*
X-1128624Y595105D01*
G01X-1128737Y594391D02*
X-1128708Y594755D01*
G01X-1121031Y595932D02*
X-1120813Y596106D01*
G01X-1121232Y595704D02*
X-1121031Y595932D01*
G01X-1121405Y595426D02*
X-1121232Y595704D01*
G01X-1121538Y595105D02*
X-1121405Y595426D01*
G01X-1121621Y594755D02*
X-1121538Y595105D01*
G01X-1121650Y594391D02*
X-1121621Y594755D01*
G01X-1113944Y595932D02*
X-1113726Y596106D01*
G01X-1114146Y595704D02*
X-1113944Y595932D01*
G01X-1114319Y595426D02*
X-1114146Y595704D01*
G01X-1114451Y595105D02*
X-1114319Y595426D01*
G01X-1114535Y594755D02*
X-1114451Y595105D01*
G01X-1114564Y594391D02*
X-1114535Y594755D01*
G01X-1117185Y602550D02*
X-1116964Y602575D01*
G01X-1117392Y602477D02*
X-1117185Y602550D01*
G01X-1117578Y602360D02*
X-1117392Y602477D01*
G01X-1117735Y602202D02*
X-1117578Y602360D01*
G01X-1117852Y602016D02*
X-1117735Y602202D01*
G01X-1117924Y601809D02*
X-1117852Y602016D01*
G01X-1117948Y601591D02*
X-1117924Y601809D01*
G01X-1149621Y595798D02*
X-1149159Y596106D01*
G01X-1149903Y595398D02*
X-1149621Y595798D01*
G01X-1149997Y594962D02*
X-1149903Y595398D01*
G01X-1083559Y595884D02*
X-1083925Y596106D01*
G01X-1083297Y595603D02*
X-1083559Y595884D01*
G01X-1083140Y595290D02*
X-1083297Y595603D01*
G01X-1083087Y594962D02*
X-1083140Y595290D01*
G01X-1100383Y595086D02*
X-1100361Y595207D01*
G01X-1100390Y594962D02*
X-1100383Y595086D01*
G01X-1106858Y595932D02*
X-1106639Y596106D01*
G01X-1107059Y595704D02*
X-1106858Y595932D01*
G01X-1107232Y595426D02*
X-1107059Y595704D01*
G01X-1107364Y595105D02*
X-1107232Y595426D01*
G01X-1107448Y594755D02*
X-1107364Y595105D01*
G01X-1107477Y594391D02*
X-1107448Y594755D01*
G01X-1099771Y595932D02*
X-1099553Y596106D01*
G01X-1099973Y595704D02*
X-1099771Y595932D01*
G01X-1100145Y595426D02*
X-1099973Y595704D01*
G01X-1100278Y595105D02*
X-1100145Y595426D01*
G01X-1100361Y594755D02*
X-1100278Y595105D01*
G01X-1100390Y594391D02*
X-1100361Y594755D01*
G01X-1092685Y595932D02*
X-1092466Y596106D01*
G01X-1092886Y595704D02*
X-1092685Y595932D01*
G01X-1093059Y595426D02*
X-1092886Y595704D01*
G01X-1093191Y595105D02*
X-1093059Y595426D01*
G01X-1093275Y594755D02*
X-1093191Y595105D01*
G01X-1093304Y594391D02*
X-1093275Y594755D01*
G01X-1085598Y595932D02*
X-1085380Y596106D01*
G01X-1085799Y595704D02*
X-1085598Y595932D01*
G01X-1085972Y595426D02*
X-1085799Y595704D01*
G01X-1086105Y595105D02*
X-1085972Y595426D01*
G01X-1086188Y594755D02*
X-1086105Y595105D01*
G01X-1086217Y594391D02*
X-1086188Y594755D01*
G01X-1142534Y595798D02*
X-1142073Y596106D01*
G01X-1142816Y595398D02*
X-1142534Y595798D01*
G01X-1142910Y594962D02*
X-1142816Y595398D01*
G01X-1135448Y595798D02*
X-1134986Y596106D01*
G01X-1135729Y595398D02*
X-1135448Y595798D01*
G01X-1135823Y594962D02*
X-1135729Y595398D01*
G01X-1128361Y595798D02*
X-1127899Y596106D01*
G01X-1128643Y595398D02*
X-1128361Y595798D01*
G01X-1128737Y594962D02*
X-1128643Y595398D01*
G01X-1114188Y595798D02*
X-1113726Y596106D01*
G01X-1114470Y595398D02*
X-1114188Y595798D01*
G01X-1114564Y594962D02*
X-1114470Y595398D01*
G01X-1107101Y595798D02*
X-1106639Y596106D01*
G01X-1107383Y595398D02*
X-1107101Y595798D01*
G01X-1107477Y594962D02*
X-1107383Y595398D01*
G01X-1092928Y595798D02*
X-1092466Y596106D01*
G01X-1093210Y595398D02*
X-1092928Y595798D01*
G01X-1093304Y594962D02*
X-1093210Y595398D01*
G01X-1085842Y595798D02*
X-1085380Y596106D01*
G01X-1086123Y595398D02*
X-1085842Y595798D01*
G01X-1086217Y594962D02*
X-1086123Y595398D01*
G01X-1121039Y595985D02*
X-1120813Y596106D01*
G01X-1121240Y595831D02*
X-1121039Y595985D01*
G01X-1121409Y595645D02*
X-1121240Y595831D01*
G01X-1121539Y595429D02*
X-1121409Y595645D01*
G01X-1121621Y595191D02*
X-1121539Y595429D01*
G01X-1099779Y595985D02*
X-1099553Y596106D01*
G01X-1099980Y595831D02*
X-1099779Y595985D01*
G01X-1100149Y595645D02*
X-1099980Y595831D01*
G01X-1100279Y595429D02*
X-1100149Y595645D01*
G01X-1100361Y595191D02*
X-1100279Y595429D01*
G01X-1083664Y637543D02*
G03I-709J0D01*
G01Y633212D02*
G03I-709J0D01*
G01X-1086227Y634019D02*
G03X-1083077I1575J0D01*
G01X-1090751Y637936D02*
G03I-709J0D01*
G01Y632425D02*
G03I-709J0D01*
G01X-1100400Y634019D02*
G03X-1097251I1575J0D01*
G01X-1093314D02*
G03X-1090164I1575J0D01*
G01X-1107487D02*
G03X-1104337I1575J0D01*
G01X-1114573D02*
G03X-1111424I1574J0D01*
G01X-1121660D02*
G03X-1118510I1575J0D01*
G01X-1104590Y638094D02*
G03I-4744J0D01*
G01X-1101440Y638114D02*
G03I-7874J0D01*
G01X-1126184Y637543D02*
G03I-709J0D01*
G01Y633212D02*
G03I-709J0D01*
G01X-1128747Y634019D02*
G03X-1125597I1575J0D01*
G01X-1133271Y637936D02*
G03I-708J0D01*
G01Y632425D02*
G03I-708J0D01*
G01X-1135833Y634019D02*
G03X-1132684I1575J0D01*
G01X-1083664Y627700D02*
G03I-709J0D01*
G01Y623369D02*
G03I-709J0D01*
G01Y619039D02*
G03I-709J0D01*
G01Y613527D02*
G03I-709J0D01*
G01X-1082684Y614334D02*
G03I-1968J0D01*
G01X-1083664Y609196D02*
G03I-709J0D01*
G01Y604865D02*
G03I-709J0D01*
G01Y599354D02*
G03I-709J0D01*
G01Y595023D02*
G03I-709J0D01*
G01X-1083920Y596114D02*
G03X-1085384I-732J-1394D01*
G01X-1097621Y630043D02*
G03X-1097030Y630633I0J591D01*
G01X-1090751Y628094D02*
G03I-709J0D01*
G01Y623763D02*
G03I-709J0D01*
G01X-1097621Y629649D02*
G03X-1096636Y630633I0J985D01*
G01X-1090361Y629511D02*
G03X-1089377Y630495I0J984D01*
G01X-1094101D02*
G03X-1093117Y629511I984J0D01*
G01X-1090751Y618251D02*
G03I-709J0D01*
G01Y613921D02*
G03I-709J0D01*
G01X-1096857Y614334D02*
G03I-1968J0D01*
G01X-1103944D02*
G03I-1968J0D01*
G01X-1089770D02*
G03I-1969J0D01*
G01X-1122621Y630633D02*
G03X-1122030Y630043I590J0D01*
G01X-1126184Y627700D02*
G03I-709J0D01*
G01X-1133271Y628094D02*
G03I-708J0D01*
G01X-1126184Y623369D02*
G03I-709J0D01*
G01X-1133271Y623763D02*
G03I-708J0D01*
G01X-1123014Y630633D02*
G03X-1122030Y629649I984J0D01*
G01X-1125794Y629511D02*
G03X-1124810Y630495I0J984D01*
G01X-1129534D02*
G03X-1128550Y629511I984J0D01*
G01X-1126184Y619039D02*
G03I-709J0D01*
G01X-1133271Y618251D02*
G03I-708J0D01*
G01Y613921D02*
G03I-708J0D01*
G01X-1126184Y613527D02*
G03I-709J0D01*
G01X-1125203Y614334D02*
G03I-1969J0D01*
G01X-1132290D02*
G03I-1969J0D01*
G01X-1111030D02*
G03I-1969J0D01*
G01X-1118117D02*
G03I-1968J0D01*
G01X-1090751Y609590D02*
G03I-709J0D01*
G01Y604078D02*
G03I-709J0D01*
G01X-1105623Y610594D02*
G03I-3691J0D01*
G01X-1105014D02*
G03I-4300J0D01*
G01X-1104885D02*
G03I-4429J0D01*
G01X-1114081Y609745D02*
G03X-1110162Y605826I4768J849D01*
G01Y615361D02*
G03X-1114081Y611442I848J-4767D01*
G01X-1104546D02*
G03X-1108465Y615361I-4768J-849D01*
G01Y605826D02*
G03X-1104546Y609745I-849J4768D01*
G01X-1104314Y610574D02*
G03I-5020J0D01*
G01X-1100964Y610594D02*
G03I-8350J0D01*
G01X-1090751Y599747D02*
G03I-709J0D01*
G01X-1105180Y596114D02*
G03X-1106644I-732J-1394D01*
G01X-1098093D02*
G03X-1099557I-732J-1394D01*
G01X-1091007D02*
G03X-1092471I-732J-1394D01*
G01X-1126184Y609196D02*
G03I-709J0D01*
G01X-1133271Y609590D02*
G03I-708J0D01*
G01X-1126184Y604865D02*
G03I-709J0D01*
G01X-1133271Y604078D02*
G03I-708J0D01*
G01Y599747D02*
G03I-708J0D01*
G01X-1126184Y599354D02*
G03I-709J0D01*
G01Y595023D02*
G03I-709J0D01*
G01X-1133526Y596114D02*
G03X-1134991I-732J-1394D01*
G01X-1126440D02*
G03X-1127904I-732J-1394D01*
G01X-1119353D02*
G03X-1120817I-732J-1394D01*
G01X-1112267D02*
G03X-1113731I-732J-1394D01*
G01X-1140357Y637543D02*
G03I-709J0D01*
G01X-1147444Y637936D02*
G03I-709J0D01*
G01Y632425D02*
G03I-709J0D01*
G01X-1140357Y633212D02*
G03I-709J0D01*
G01Y627700D02*
G03I-709J0D01*
G01X-1147444Y628094D02*
G03I-709J0D01*
G01X-1140357Y623369D02*
G03I-709J0D01*
G01X-1147444Y623763D02*
G03I-709J0D01*
G01X-1142920Y634019D02*
G03X-1139770I1575J0D01*
G01X-1150007D02*
G03X-1146857I1575J0D01*
G01X-1140357Y619039D02*
G03I-709J0D01*
G01X-1147444Y618251D02*
G03I-709J0D01*
G01Y613921D02*
G03I-709J0D01*
G01X-1140357Y613527D02*
G03I-709J0D01*
G01Y609196D02*
G03I-709J0D01*
G01X-1147444Y609590D02*
G03I-709J0D01*
G01X-1139377Y614334D02*
G03I-1968J0D01*
G01X-1146463D02*
G03I-1969J0D01*
G01X-1140357Y604865D02*
G03I-709J0D01*
G01X-1147444Y604078D02*
G03I-709J0D01*
G01Y599747D02*
G03I-709J0D01*
G01X-1140357Y599354D02*
G03I-709J0D01*
G01Y595023D02*
G03I-709J0D01*
G01X-1147700Y596114D02*
G03X-1149164I-732J-1394D01*
G01X-1140613D02*
G03X-1142077I-732J-1394D01*
G01X-1105814Y609744D02*
X-1107494Y608774D01*
G01X-1108404Y609684D02*
X-1107564Y610169D01*
G01X-1110224Y611504D02*
X-1111064Y611019D01*
G01X-1112814Y611444D02*
X-1111134Y612414D01*
G01X-1097192Y636088D02*
X-1097979Y635633D01*
G01X-1090203Y588625D02*
X-1091385Y587444D01*
G01X-1097290Y588625D02*
X-1098471Y587444D01*
G01X-1104377Y636088D02*
X-1105164Y635633D01*
G01X-1111463Y636088D02*
X-1112251Y635633D01*
G01X-1118451Y636088D02*
X-1119239Y635633D01*
G01X-1100455Y601814D02*
X-1100679Y601591D01*
G01X-1101663Y602575D02*
X-1101439Y602799D01*
G01X-1118550Y588625D02*
X-1119731Y587444D01*
G01X-1116964Y595148D02*
X-1117188Y594925D01*
G01X-1118172Y595909D02*
X-1117948Y596132D01*
G01X-1125636Y588625D02*
X-1126818Y587444D01*
G01X-1111134Y608774D02*
X-1107494Y612414D01*
G01X-1100455Y625830D02*
X-1100679Y625607D01*
G01X-1101663Y626591D02*
X-1101439Y626814D01*
G01X-1116964Y619164D02*
X-1117188Y618940D01*
G01X-1118172Y619924D02*
X-1117948Y620148D01*
G01X-1103478Y638114D02*
X-1109314Y632278D01*
G01X-1104314Y638114D02*
X-1109314Y633114D01*
G01Y636539D02*
X-1107739Y638114D01*
G01X-1090203Y636555D02*
X-1090991Y635191D01*
G01X-1107494Y608774D02*
X-1108464Y607094D01*
G01X-1108404Y609684D02*
X-1108889Y608844D01*
G01X-1110224Y611504D02*
X-1109739Y612344D01*
G01X-1111134Y612414D02*
X-1110164Y614094D01*
G01X-1125636Y636976D02*
X-1126424Y635612D01*
G01X-1110164Y607094D02*
X-1108464Y614094D01*
G01X-1110161Y605411D02*
X-1108467Y615776D01*
G01X-1083077Y634019D02*
Y650530D01*
G01X-1083087Y594962D02*
Y589019D01*
G01X-1086217Y594962D02*
Y589019D01*
G01X-1086227Y650530D02*
Y634019D01*
G01X-1089377Y653921D02*
Y630495D01*
G01X-1115243Y661280D02*
X-1116463Y591381D01*
G01X-1116227Y661280D02*
X-1117448Y591381D01*
G01X-1090164Y634019D02*
Y638850D01*
G01X-1090174Y594962D02*
Y589019D01*
G01X-1090203Y588625D02*
Y591381D01*
G01Y638790D02*
Y636555D01*
G01X-1093274D02*
Y638790D01*
G01Y591381D02*
Y588625D01*
G01X-1093304Y594962D02*
Y589019D01*
G01X-1093314Y638850D02*
Y634019D01*
G01X-1094101Y653921D02*
Y630495D01*
G01X-1095295Y675174D02*
Y586460D01*
G01X-1096636D02*
Y683015D01*
G01X-1097030D02*
Y630633D01*
G01X-1097192Y636088D02*
Y654098D01*
G01X-1097251Y634019D02*
Y636054D01*
G01X-1097260Y594962D02*
Y589019D01*
G01X-1097290Y599255D02*
Y588625D01*
G01X-1097621Y630043D02*
Y629649D01*
G01X-1100361Y588625D02*
Y599255D01*
G01X-1100390Y589019D02*
Y594962D01*
G01X-1100400Y636054D02*
Y634019D01*
G01X-1100455Y619924D02*
Y625830D01*
G01Y595909D02*
Y601814D01*
G01X-1100459Y654098D02*
Y636088D01*
G01X-1100679Y620148D02*
Y625607D01*
G01Y596132D02*
Y601591D01*
G01X-1101663Y619164D02*
Y626591D01*
G01Y595148D02*
Y602575D01*
G01X-1104337Y634019D02*
Y650530D01*
G01X-1104347Y594962D02*
Y589019D01*
G01X-1104377Y654098D02*
Y636088D01*
G01X-1106714Y611019D02*
Y610169D01*
G01X-1107448Y654098D02*
Y636088D01*
G01X-1107477Y589019D02*
Y594962D01*
G01X-1107487Y650530D02*
Y634019D01*
G01X-1108464Y614094D02*
Y615505D01*
G01X-1108889Y612344D02*
Y613194D01*
G01Y607994D02*
Y608844D01*
G01X-1109314Y636539D02*
Y632278D01*
G01X-1109739Y608844D02*
Y607994D01*
G01Y613194D02*
Y612344D01*
G01X-1110164Y607094D02*
X-1110163Y605683D01*
G01X-1111424Y634019D02*
Y650530D01*
G01X-1111434Y594962D02*
Y589019D01*
G01X-1111463Y636088D02*
Y654098D01*
G01X-1111914Y611019D02*
Y610169D01*
G01X-1114534Y654098D02*
Y636088D01*
G01X-1114564Y589019D02*
Y594962D01*
G01X-1114573Y650530D02*
Y634019D01*
G01X-1116964Y619164D02*
Y626591D01*
G01Y595148D02*
Y602575D01*
G01X-1117948Y620148D02*
Y625607D01*
G01Y601591D02*
Y596132D01*
G01X-1118172Y601814D02*
Y595909D01*
G01Y625830D02*
Y619924D01*
G01X-1118451Y636088D02*
Y654098D01*
G01X-1118510Y634019D02*
Y636054D01*
G01X-1118520Y594962D02*
Y589019D01*
G01X-1118550Y599255D02*
Y588625D01*
G01X-1121621D02*
Y599255D01*
G01X-1121650Y589019D02*
Y594962D01*
G01X-1121660Y636054D02*
Y634019D01*
G01X-1121719Y654098D02*
Y636088D01*
G01X-1122030Y630043D02*
Y629649D01*
G01X-1122621Y630633D02*
Y683015D01*
G01X-1123014D02*
Y586460D01*
G01X-1124197Y675174D02*
Y586460D01*
G01X-1124810Y653921D02*
Y630495D01*
G01X-1125597Y634019D02*
Y639271D01*
G01X-1125607Y594962D02*
Y589019D01*
G01X-1125636Y591381D02*
Y588625D01*
G01Y639211D02*
Y636976D01*
G01X-1128707Y591381D02*
Y588625D01*
G01Y639211D02*
Y636976D01*
G01X-1128737Y594962D02*
Y589019D01*
G01X-1128747Y639271D02*
Y634019D01*
G01X-1129534Y653921D02*
Y630495D01*
G01X-1102920Y661280D02*
X-1101699Y591381D01*
G01X-1102684D02*
X-1103904Y661280D01*
G01X-1108467Y605411D02*
X-1110161Y615776D01*
G01X-1108464Y607094D02*
X-1110164Y614094D01*
G01X-1132684Y634019D02*
Y650530D01*
G01X-1132694Y594962D02*
Y589019D01*
G01X-1135823Y594962D02*
Y589019D01*
G01X-1135833Y650530D02*
Y634019D01*
G01X-1139770D02*
Y650530D01*
G01X-1139780Y594962D02*
Y589019D01*
G01X-1142910Y594962D02*
Y589019D01*
G01X-1142920Y650530D02*
Y634019D01*
G01X-1146857D02*
Y650530D01*
G01X-1146867Y594962D02*
Y589019D01*
G01X-1149997Y594962D02*
Y589019D01*
G01X-1150007Y650530D02*
Y634019D01*
G01X-1093274Y636555D02*
X-1092487Y635191D01*
G01X-1108464Y614094D02*
X-1107494Y612414D01*
G01X-1108404Y611504D02*
X-1108889Y612344D01*
G01X-1110224Y609684D02*
X-1109739Y608844D01*
G01X-1110164Y607094D02*
X-1111134Y608774D01*
G01X-1128707Y636976D02*
X-1127920Y635612D01*
G01X-1110888Y638114D02*
X-1109314Y636539D01*
G01X-1114314Y638114D02*
X-1109314Y633114D01*
G01Y632278D02*
X-1115149Y638114D01*
G01X-1100679Y620148D02*
X-1100455Y619924D01*
G01X-1101439Y618940D02*
X-1101663Y619164D01*
G01X-1117188Y626814D02*
X-1116964Y626591D01*
G01X-1117948Y625607D02*
X-1118172Y625830D01*
G01X-1107494Y608774D02*
X-1111134Y612414D01*
G01X-1100679Y596132D02*
X-1100455Y595909D01*
G01X-1093274Y588625D02*
X-1092093Y587444D01*
G01X-1101439Y594925D02*
X-1101663Y595148D01*
G01X-1100361Y588625D02*
X-1099180Y587444D01*
G01X-1117188Y602799D02*
X-1116964Y602575D01*
G01X-1117948Y601591D02*
X-1118172Y601814D01*
G01X-1121621Y588625D02*
X-1120440Y587444D01*
G01X-1128707Y588625D02*
X-1127526Y587444D01*
G01X-1099672Y635633D02*
X-1100459Y636088D01*
G01X-1106660Y635633D02*
X-1107448Y636088D01*
G01X-1113747Y635633D02*
X-1114534Y636088D01*
G01X-1120932Y635633D02*
X-1121719Y636088D01*
G01X-1107494Y612414D02*
X-1105814Y611444D01*
G01X-1107564Y611019D02*
X-1108404Y611504D01*
G01X-1110224Y609684D02*
X-1111064Y610169D01*
G01X-1111134Y608774D02*
X-1112814Y609744D01*
G01Y611444D02*
X-1105814Y609744D01*
G01X-1114496Y611441D02*
X-1104131Y609747D01*
G01X-1119239Y635633D02*
X-1120932D01*
G01X-1112251D02*
X-1113747D01*
G01X-1105164D02*
X-1106660D01*
G01X-1097979D02*
X-1099672D01*
G01X-1126424Y635612D02*
X-1127920D01*
G01X-1090991Y635191D02*
X-1092487D01*
G01X-1123014Y632172D02*
X-1096636D01*
G01X-1124810Y632034D02*
X-1129534D01*
G01X-1089377D02*
X-1094101D01*
G01X-1097030Y630633D02*
X-1096636D01*
G01X-1123014D02*
X-1122621D01*
G01X-1122030Y630043D02*
X-1097621D01*
G01Y629649D02*
X-1122030D01*
G01X-1125794Y629511D02*
X-1128550D01*
G01X-1090361D02*
X-1093117D01*
G01X-1101439Y626814D02*
X-1117188D01*
G01X-1116964Y626591D02*
X-1101663D01*
G01X-1117948Y625607D02*
X-1100679D01*
G01Y620148D02*
X-1117948D01*
G01X-1101663Y619164D02*
X-1116964D01*
G01X-1117188Y618940D02*
X-1101439D01*
G01X-1108889Y613194D02*
X-1109739D01*
G01X-1112814Y611444D02*
X-1114225D01*
G01X-1111064Y611019D02*
X-1111914D01*
G01X-1106714D02*
X-1107564D01*
G01Y610169D02*
X-1106714D01*
G01X-1111914D02*
X-1111064D01*
G01X-1105814Y609744D02*
X-1104403D01*
G01X-1109739Y607994D02*
X-1108889D01*
G01X-1101439Y602799D02*
X-1117188D01*
G01X-1101663Y602575D02*
X-1116964D01*
G01X-1117948Y601591D02*
X-1100679D01*
G01X-1039157Y599905D02*
X-1095295D01*
G01X-1097290Y599255D02*
X-1096636D01*
G01X-1118550D02*
X-1100361D01*
G01X-1123014D02*
X-1121621D01*
G01X-1100679Y596132D02*
X-1117948D01*
G01X-1098098Y596106D02*
X-1092466D01*
G01X-1105185D02*
X-1099553D01*
G01X-1119358D02*
X-1113726D01*
G01X-1126444D02*
X-1120813D01*
G01X-1142073D02*
X-1147704D01*
G01X-1134986D02*
X-1140618D01*
G01X-1127899D02*
X-1133531D01*
G01X-1106639D02*
X-1112271D01*
G01X-1085380D02*
X-1091011D01*
G01X-1078293D02*
X-1083925D01*
G01X-1101663Y595148D02*
X-1116964D01*
G01X-1117188Y594925D02*
X-1101439D01*
G01X-1039157Y593862D02*
X-1095295D01*
G01X-1039157Y593389D02*
X-1095295D01*
G01X-1121650Y591454D02*
X-1123014D01*
G01X-1114564D02*
X-1118520D01*
G01X-1107477D02*
X-1111434D01*
G01X-1100390D02*
X-1104347D01*
G01X-1096636D02*
X-1097260D01*
G01X-1096636Y589806D02*
X-1123014D01*
G01X-1039157D02*
X-1095295D01*
G01X-1125636Y588625D02*
X-1128707D01*
G01X-1118550D02*
X-1121621D01*
G01X-1097290D02*
X-1100361D01*
G01X-1090203D02*
X-1093274D01*
G01X-1120440Y587444D02*
X-1119731D01*
G01X-1126818D02*
X-1127526D01*
G01X-1098471D02*
X-1099180D01*
G01X-1091385D02*
X-1092093D01*
G01X-1123014Y586460D02*
X-1096636D01*
G01X-1039157D02*
X-1095295D01*
G01X-1110161Y615776D02*
X-1109596Y615781D01*
G01X-1108467Y605411D02*
X-1109031Y605407D01*
G01X-1114496Y609747D02*
X-1104131Y611441D01*
G01X-1112814Y609744D02*
X-1105814Y611444D01*
G01X-1095804Y568342D02*
X-1091867D01*
G01X-1118113D02*
X-1114176D01*
G01X-1084150Y675833D02*
X-1084130Y675895D01*
G01X-1084188Y675774D02*
X-1084150Y675833D01*
G01X-1084242Y675722D02*
X-1084188Y675774D01*
G01X-1084309Y675678D02*
X-1084242Y675722D01*
G01X-1084386Y675644D02*
X-1084309Y675678D01*
G01X-1084470Y675623D02*
X-1084386Y675644D01*
G01X-1126669Y675833D02*
X-1126649Y675895D01*
G01X-1126708Y675774D02*
X-1126669Y675833D01*
G01X-1126762Y675722D02*
X-1126708Y675774D01*
G01X-1126829Y675678D02*
X-1126762Y675722D01*
G01X-1126906Y675644D02*
X-1126829Y675678D01*
G01X-1126989Y675623D02*
X-1126906Y675644D01*
G01X-1140843Y675833D02*
X-1140823Y675895D01*
G01X-1140881Y675774D02*
X-1140843Y675833D01*
G01X-1140935Y675722D02*
X-1140881Y675774D01*
G01X-1141002Y675678D02*
X-1140935Y675722D01*
G01X-1141079Y675644D02*
X-1141002Y675678D01*
G01X-1141162Y675623D02*
X-1141079Y675644D01*
G01X-1090419Y664118D02*
X-1090435Y664117D01*
G01X-1090403Y664120D02*
X-1090419Y664118D01*
G01X-1090387Y664124D02*
X-1090403Y664120D01*
G01X-1125852Y664118D02*
X-1125868Y664117D01*
G01X-1125836Y664120D02*
X-1125852Y664118D01*
G01X-1125821Y664124D02*
X-1125836Y664120D01*
G01X-1083166Y674116D02*
X-1083151Y674190D01*
G01X-1083208Y674051D02*
X-1083166Y674116D01*
G01X-1083272Y674009D02*
X-1083208Y674051D01*
G01X-1083348Y673993D02*
X-1083272Y674009D01*
G01X-1139859Y674116D02*
X-1139844Y674190D01*
G01X-1139901Y674051D02*
X-1139859Y674116D01*
G01X-1139965Y674009D02*
X-1139901Y674051D01*
G01X-1140041Y673993D02*
X-1139965Y674009D01*
G01X-1101042Y668564D02*
X-1100967Y668940D01*
G01X-1101255Y668244D02*
X-1101042Y668564D01*
G01X-1101575Y668031D02*
X-1101255Y668244D01*
G01X-1101951Y667956D02*
X-1101575Y668031D01*
G01X-1118609Y679160D02*
X-1118684Y678783D01*
G01X-1118396Y679479D02*
X-1118609Y679160D01*
G01X-1118076Y679692D02*
X-1118396Y679479D01*
G01X-1117700Y679767D02*
X-1118076Y679692D01*
G01X-1116148Y661652D02*
X-1116227Y661280D01*
G01X-1115933Y661965D02*
X-1116148Y661652D01*
G01X-1115616Y662174D02*
X-1115933Y661965D01*
G01X-1115243Y662247D02*
X-1115616Y662174D01*
G01X-1122985Y683227D02*
X-1123014Y683015D01*
G01X-1122895Y683431D02*
X-1122985Y683227D01*
G01X-1122741Y683612D02*
X-1122895Y683431D01*
G01X-1122517Y683747D02*
X-1122741Y683612D01*
G01X-1122227Y683802D02*
X-1122517Y683747D01*
G01X-1083967Y674807D02*
X-1083948Y674865D01*
G01X-1084000Y674753D02*
X-1083967Y674807D01*
G01X-1084049Y674702D02*
X-1084000Y674753D01*
G01X-1084110Y674659D02*
X-1084049Y674702D01*
G01X-1084180Y674624D02*
X-1084110Y674659D01*
G01X-1084256Y674600D02*
X-1084180Y674624D01*
G01X-1084336Y674587D02*
X-1084256Y674600D01*
G01X-1126486Y674807D02*
X-1126468Y674865D01*
G01X-1126520Y674753D02*
X-1126486Y674807D01*
G01X-1126569Y674702D02*
X-1126520Y674753D01*
G01X-1126629Y674659D02*
X-1126569Y674702D01*
G01X-1126699Y674624D02*
X-1126629Y674659D01*
G01X-1126776Y674600D02*
X-1126699Y674624D01*
G01X-1126856Y674587D02*
X-1126776Y674600D01*
G01X-1108904Y672594D02*
X-1108817Y672779D01*
G01X-1108993Y672431D02*
X-1108904Y672594D01*
G01X-1109084Y672288D02*
X-1108993Y672431D01*
G01X-1109178Y672167D02*
X-1109084Y672288D01*
G01X-1109275Y672070D02*
X-1109178Y672167D01*
G01X-1109376Y671998D02*
X-1109275Y672070D01*
G01X-1109477Y671955D02*
X-1109376Y671998D01*
G01X-1109573Y671942D02*
X-1109477Y671955D01*
G01X-1101147Y668874D02*
X-1101122Y669095D01*
G01X-1101220Y668667D02*
X-1101147Y668874D01*
G01X-1101337Y668481D02*
X-1101220Y668667D01*
G01X-1101495Y668324D02*
X-1101337Y668481D01*
G01X-1101681Y668208D02*
X-1101495Y668324D01*
G01X-1101888Y668135D02*
X-1101681Y668208D01*
G01X-1102106Y668111D02*
X-1101888Y668135D01*
G01X-1084478Y675621D02*
X-1084470Y675623D01*
G01X-1084486Y675620D02*
X-1084478Y675621D01*
G01X-1084494Y675619D02*
X-1084486Y675620D01*
G01X-1084503Y675618D02*
X-1084494Y675619D01*
G01X-1084511Y675617D02*
X-1084503Y675618D01*
G01X-1084518Y675616D02*
X-1084511Y675617D01*
G01X-1126998Y675621D02*
X-1126989Y675623D01*
G01X-1127006Y675620D02*
X-1126998Y675621D01*
G01X-1127014Y675619D02*
X-1127006Y675620D01*
G01X-1127022Y675618D02*
X-1127014Y675619D01*
G01X-1127030Y675617D02*
X-1127022Y675618D01*
G01X-1127037Y675616D02*
X-1127030Y675617D01*
G01X-1141171Y675621D02*
X-1141162Y675623D01*
G01X-1141179Y675620D02*
X-1141171Y675621D01*
G01X-1141187Y675619D02*
X-1141179Y675620D01*
G01X-1141195Y675618D02*
X-1141187Y675619D01*
G01X-1141204Y675617D02*
X-1141195Y675618D01*
G01X-1141210Y675616D02*
X-1141204Y675617D01*
G01X-1115857Y661287D02*
X-1115671Y661286D01*
G01X-1116014Y661287D02*
X-1115857D01*
G01X-1119733Y684765D02*
X-1119809Y684770D01*
G01X-1119519Y684763D02*
X-1119733Y684765D01*
G01X-1102945Y661284D02*
X-1102920Y661280D01*
G01X-1103018Y661286D02*
X-1102945Y661284D01*
G01X-1103135Y661287D02*
X-1103018Y661286D01*
G01X-1118504Y668874D02*
X-1118529Y669095D01*
G01X-1118431Y668667D02*
X-1118504Y668874D01*
G01X-1118314Y668481D02*
X-1118431Y668667D01*
G01X-1118156Y668324D02*
X-1118314Y668481D01*
G01X-1117970Y668208D02*
X-1118156Y668324D01*
G01X-1117763Y668135D02*
X-1117970Y668208D01*
G01X-1117545Y668111D02*
X-1117763Y668135D01*
G01X-1101147Y678849D02*
X-1101122Y678628D01*
G01X-1101220Y679056D02*
X-1101147Y678849D01*
G01X-1101337Y679242D02*
X-1101220Y679056D01*
G01X-1101495Y679399D02*
X-1101337Y679242D01*
G01X-1101681Y679515D02*
X-1101495Y679399D01*
G01X-1101888Y679588D02*
X-1101681Y679515D01*
G01X-1102106Y679612D02*
X-1101888Y679588D01*
G01X-1151657Y664205D02*
X-1151685Y664251D01*
G01X-1151623Y664167D02*
X-1151657Y664205D01*
G01X-1151583Y664139D02*
X-1151623Y664167D01*
G01X-1151538Y664123D02*
X-1151583Y664139D01*
G01X-1151493Y664117D02*
X-1151538Y664123D01*
G01X-1137483Y664205D02*
X-1137511Y664251D01*
G01X-1137450Y664167D02*
X-1137483Y664205D01*
G01X-1137409Y664139D02*
X-1137450Y664167D01*
G01X-1137365Y664123D02*
X-1137409Y664139D01*
G01X-1137320Y664117D02*
X-1137365Y664123D01*
G01X-1080790Y664205D02*
X-1080818Y664251D01*
G01X-1080757Y664167D02*
X-1080790Y664205D01*
G01X-1080717Y664139D02*
X-1080757Y664167D01*
G01X-1080672Y664123D02*
X-1080717Y664139D01*
G01X-1080627Y664117D02*
X-1080672Y664123D01*
G01X-1143418Y674132D02*
X-1143427Y674190D01*
G01X-1143396Y674083D02*
X-1143418Y674132D01*
G01X-1143363Y674044D02*
X-1143396Y674083D01*
G01X-1143322Y674015D02*
X-1143363Y674044D01*
G01X-1143276Y673998D02*
X-1143322Y674015D01*
G01X-1143230Y673993D02*
X-1143276Y673998D01*
G01X-1129245Y674132D02*
X-1129254Y674190D01*
G01X-1129223Y674083D02*
X-1129245Y674132D01*
G01X-1129190Y674044D02*
X-1129223Y674083D01*
G01X-1129149Y674015D02*
X-1129190Y674044D01*
G01X-1129103Y673998D02*
X-1129149Y674015D01*
G01X-1129057Y673993D02*
X-1129103Y673998D01*
G01X-1086726Y674132D02*
X-1086734Y674190D01*
G01X-1086703Y674083D02*
X-1086726Y674132D01*
G01X-1086670Y674044D02*
X-1086703Y674083D01*
G01X-1086629Y674015D02*
X-1086670Y674044D01*
G01X-1086583Y673998D02*
X-1086629Y674015D01*
G01X-1086537Y673993D02*
X-1086583Y673998D01*
G01X-1109670Y671955D02*
X-1109771Y671998D01*
G01X-1109573Y671942D02*
X-1109670Y671955D01*
G01X-1099160Y684469D02*
X-1099212Y684770D01*
G01X-1099018Y684199D02*
X-1099160Y684469D01*
G01X-1098801Y683986D02*
X-1099018Y684199D01*
G01X-1098529Y683849D02*
X-1098801Y683986D01*
G01X-1098228Y683802D02*
X-1098529Y683849D01*
G01X-1102972Y661580D02*
X-1102920Y661280D01*
G01X-1103113Y661850D02*
X-1102972Y661580D01*
G01X-1103331Y662063D02*
X-1103113Y661850D01*
G01X-1103603Y662200D02*
X-1103331Y662063D01*
G01X-1103904Y662247D02*
X-1103603Y662200D01*
G01X-1145172Y674807D02*
X-1145191Y674865D01*
G01X-1145139Y674753D02*
X-1145172Y674807D01*
G01X-1145090Y674702D02*
X-1145139Y674753D01*
G01X-1145029Y674659D02*
X-1145090Y674702D01*
G01X-1144959Y674624D02*
X-1145029Y674659D01*
G01X-1144883Y674600D02*
X-1144959Y674624D01*
G01X-1144803Y674587D02*
X-1144883Y674600D01*
G01X-1130999Y674807D02*
X-1131018Y674865D01*
G01X-1130965Y674753D02*
X-1130999Y674807D01*
G01X-1130916Y674702D02*
X-1130965Y674753D01*
G01X-1130856Y674659D02*
X-1130916Y674702D01*
G01X-1130786Y674624D02*
X-1130856Y674659D01*
G01X-1130710Y674600D02*
X-1130786Y674624D01*
G01X-1130630Y674587D02*
X-1130710Y674600D01*
G01X-1144630Y675617D02*
X-1144622Y675616D01*
G01X-1144638Y675618D02*
X-1144630Y675617D01*
G01X-1144646Y675619D02*
X-1144638Y675618D01*
G01X-1144655Y675620D02*
X-1144646Y675619D01*
G01X-1144663Y675621D02*
X-1144655Y675620D01*
G01X-1144670Y675623D02*
X-1144663Y675621D01*
G01X-1130457Y675617D02*
X-1130448Y675616D01*
G01X-1130465Y675618D02*
X-1130457Y675617D01*
G01X-1130473Y675619D02*
X-1130465Y675618D01*
G01X-1130481Y675620D02*
X-1130473Y675619D01*
G01X-1130490Y675621D02*
X-1130481Y675620D01*
G01X-1130496Y675623D02*
X-1130490Y675621D01*
G01X-1087937Y675617D02*
X-1087929Y675616D01*
G01X-1087945Y675618D02*
X-1087937Y675617D01*
G01X-1087954Y675619D02*
X-1087945Y675618D01*
G01X-1087962Y675620D02*
X-1087954Y675619D01*
G01X-1087970Y675621D02*
X-1087962Y675620D01*
G01X-1087977Y675623D02*
X-1087970Y675621D01*
G01X-1144937Y669533D02*
X-1144995Y669826D01*
G01X-1144766Y669274D02*
X-1144937Y669533D01*
G01X-1144503Y669099D02*
X-1144766Y669274D01*
G01X-1144195Y669039D02*
X-1144503Y669099D01*
G01X-1130764Y669533D02*
X-1130822Y669826D01*
G01X-1130593Y669274D02*
X-1130764Y669533D01*
G01X-1130329Y669099D02*
X-1130593Y669274D01*
G01X-1130022Y669039D02*
X-1130329Y669099D01*
G01X-1088245Y669533D02*
X-1088302Y669826D01*
G01X-1088073Y669274D02*
X-1088245Y669533D01*
G01X-1087810Y669099D02*
X-1088073Y669274D01*
G01X-1087502Y669039D02*
X-1087810Y669099D01*
G01X-1144554Y669633D02*
X-1144607Y669826D01*
G01X-1144404Y669487D02*
X-1144554Y669633D01*
G01X-1144195Y669432D02*
X-1144404Y669487D01*
G01X-1130381Y669633D02*
X-1130434Y669826D01*
G01X-1130231Y669487D02*
X-1130381Y669633D01*
G01X-1130022Y669432D02*
X-1130231Y669487D01*
G01X-1087861Y669633D02*
X-1087914Y669826D01*
G01X-1087711Y669487D02*
X-1087861Y669633D01*
G01X-1087502Y669432D02*
X-1087711Y669487D01*
G01X-1129073Y664118D02*
X-1129057Y664117D01*
G01X-1129089Y664120D02*
X-1129073Y664118D01*
G01X-1129104Y664124D02*
X-1129089Y664120D01*
G01X-1093640Y664118D02*
X-1093624Y664117D01*
G01X-1093656Y664120D02*
X-1093640Y664118D01*
G01X-1093671Y664124D02*
X-1093656Y664120D01*
G01X-1114251Y704424D02*
X-1114502Y704275D01*
G01X-1114000Y704472D02*
X-1114251Y704424D01*
G01X-1105147Y704472D02*
X-1104896Y704424D01*
G01X-1105413D02*
X-1105147Y704472D01*
G01X-1119426Y704002D02*
X-1119478Y703702D01*
G01X-1119284Y704271D02*
X-1119426Y704002D01*
G01X-1119067Y704485D02*
X-1119284Y704271D01*
G01X-1118795Y704622D02*
X-1119067Y704485D01*
G01X-1118494Y704669D02*
X-1118795Y704622D01*
G01X-1119108Y703709D02*
X-1118922Y703707D01*
G01X-1119265Y703709D02*
X-1119108D01*
G01X-1119381Y703707D02*
X-1119265Y703709D01*
G01X-1119454Y703705D02*
X-1119381Y703707D01*
G01X-1119478Y703702D02*
X-1119454Y703705D01*
G01X-1082569Y701961D02*
X-1082596Y701902D01*
G01X-1082530Y702011D02*
X-1082569Y701961D01*
G01X-1082482Y702053D02*
X-1082530Y702011D01*
G01X-1082427Y702084D02*
X-1082482Y702053D01*
G01X-1082367Y702103D02*
X-1082427Y702084D01*
G01X-1082305Y702110D02*
X-1082367Y702103D01*
G01X-1084139Y701961D02*
X-1084166Y701902D01*
G01X-1084100Y702011D02*
X-1084139Y701961D01*
G01X-1084052Y702053D02*
X-1084100Y702011D01*
G01X-1083997Y702084D02*
X-1084052Y702053D01*
G01X-1083937Y702103D02*
X-1083997Y702084D01*
G01X-1083875Y702110D02*
X-1083937Y702103D01*
G01X-1125088Y701961D02*
X-1125116Y701902D01*
G01X-1125050Y702011D02*
X-1125088Y701961D01*
G01X-1125002Y702053D02*
X-1125050Y702011D01*
G01X-1124947Y702084D02*
X-1125002Y702053D01*
G01X-1124887Y702103D02*
X-1124947Y702084D01*
G01X-1124825Y702110D02*
X-1124887Y702103D01*
G01X-1126658Y701961D02*
X-1126686Y701902D01*
G01X-1126620Y702011D02*
X-1126658Y701961D01*
G01X-1126572Y702053D02*
X-1126620Y702011D01*
G01X-1126517Y702084D02*
X-1126572Y702053D01*
G01X-1126457Y702103D02*
X-1126517Y702084D01*
G01X-1126395Y702110D02*
X-1126457Y702103D01*
G01X-1139261Y701961D02*
X-1139289Y701902D01*
G01X-1139223Y702011D02*
X-1139261Y701961D01*
G01X-1139175Y702053D02*
X-1139223Y702011D01*
G01X-1139120Y702084D02*
X-1139175Y702053D01*
G01X-1139060Y702103D02*
X-1139120Y702084D01*
G01X-1138998Y702110D02*
X-1139060Y702103D01*
G01X-1140831Y701961D02*
X-1140859Y701902D01*
G01X-1140793Y702011D02*
X-1140831Y701961D01*
G01X-1140745Y702053D02*
X-1140793Y702011D01*
G01X-1140690Y702084D02*
X-1140745Y702053D01*
G01X-1140630Y702103D02*
X-1140690Y702084D01*
G01X-1140568Y702110D02*
X-1140630Y702103D01*
G01X-1099641Y703707D02*
X-1099568Y703705D01*
G01X-1099758Y703709D02*
X-1099641Y703707D01*
G01X-1099916Y703709D02*
X-1099758D01*
G01X-1100102Y703707D02*
X-1099916Y703709D01*
G01X-1100527Y703702D02*
X-1100102Y703707D01*
G01X-1141256Y700366D02*
X-1141226Y700381D01*
G01X-1141304Y700360D02*
X-1141256Y700366D01*
G01X-1141366Y700361D02*
X-1141304Y700360D01*
G01X-1127083Y700366D02*
X-1127052Y700381D01*
G01X-1127131Y700360D02*
X-1127083Y700366D01*
G01X-1127192Y700361D02*
X-1127131Y700360D01*
G01X-1084563Y700366D02*
X-1084533Y700381D01*
G01X-1084611Y700360D02*
X-1084563Y700366D01*
G01X-1084673Y700361D02*
X-1084611Y700360D01*
G01X-1099595Y704002D02*
X-1099543Y703702D01*
G01X-1099737Y704271D02*
X-1099595Y704002D01*
G01X-1099954Y704485D02*
X-1099737Y704271D01*
G01X-1100226Y704622D02*
X-1099954Y704485D01*
G01X-1100527Y704669D02*
X-1100226Y704622D01*
G01X-1146256Y701883D02*
X-1145879Y701795D01*
G01X-1146333Y701902D02*
X-1146256Y701883D01*
G01X-1132083D02*
X-1131706Y701795D01*
G01X-1132159Y701902D02*
X-1132083Y701883D01*
G01X-1089563D02*
X-1089186Y701795D01*
G01X-1089640Y701902D02*
X-1089563Y701883D01*
G01X-1144488Y700360D02*
X-1144427Y700361D01*
G01X-1144536Y700366D02*
X-1144488Y700360D01*
G01X-1144567Y700381D02*
X-1144536Y700366D01*
G01X-1130315Y700360D02*
X-1130254Y700361D01*
G01X-1130363Y700366D02*
X-1130315Y700360D01*
G01X-1130394Y700381D02*
X-1130363Y700366D01*
G01X-1087796Y700360D02*
X-1087734Y700361D01*
G01X-1087843Y700366D02*
X-1087796Y700360D01*
G01X-1087874Y700381D02*
X-1087843Y700366D01*
G01X-1129145Y664130D02*
X-1129104Y664124D01*
G01X-1129185Y664145D02*
X-1129145Y664130D01*
G01X-1129222Y664170D02*
X-1129185Y664145D01*
G01X-1129254Y664203D02*
X-1129222Y664170D01*
G01X-1141300Y701322D02*
X-1141463Y700764D01*
G01X-1141219Y701747D02*
X-1141300Y701322D01*
G01X-1141227Y702016D02*
X-1141219Y701747D01*
G01X-1141322Y702110D02*
X-1141227Y702016D01*
G01X-1127126Y701322D02*
X-1127290Y700764D01*
G01X-1127046Y701747D02*
X-1127126Y701322D01*
G01X-1127054Y702016D02*
X-1127046Y701747D01*
G01X-1127149Y702110D02*
X-1127054Y702016D01*
G01X-1093712Y664130D02*
X-1093671Y664124D01*
G01X-1093752Y664145D02*
X-1093712Y664130D01*
G01X-1093789Y664170D02*
X-1093752Y664145D01*
G01X-1093821Y664203D02*
X-1093789Y664170D01*
G01X-1141095Y702078D02*
X-1141322Y702110D01*
G01X-1140948Y702008D02*
X-1141095Y702078D01*
G01X-1140859Y701902D02*
X-1140948Y702008D01*
G01X-1126922Y702078D02*
X-1127149Y702110D01*
G01X-1126775Y702008D02*
X-1126922Y702078D01*
G01X-1126686Y701902D02*
X-1126775Y702008D01*
G01X-1113607Y672172D02*
X-1113557Y672292D01*
G01X-1113662Y672075D02*
X-1113607Y672172D01*
G01X-1113723Y672003D02*
X-1113662Y672075D01*
G01X-1113786Y671959D02*
X-1113723Y672003D01*
G01X-1113854Y671942D02*
X-1113786Y671959D01*
G01X-1113927Y671954D02*
X-1113854Y671942D01*
G01X-1114004Y671996D02*
X-1113927Y671954D01*
G01X-1114085Y672067D02*
X-1114004Y671996D01*
G01X-1114166Y672164D02*
X-1114085Y672067D01*
G01X-1114249Y672285D02*
X-1114166Y672164D01*
G01X-1144175Y699951D02*
X-1144078Y699747D01*
G01X-1144292Y700155D02*
X-1144175Y699951D01*
G01X-1144515Y700496D02*
X-1144292Y700155D01*
G01X-1130002Y699951D02*
X-1129905Y699747D01*
G01X-1130119Y700155D02*
X-1130002Y699951D01*
G01X-1130342Y700496D02*
X-1130119Y700155D01*
G01X-1110154Y672431D02*
X-1110243Y672594D01*
G01X-1110063Y672288D02*
X-1110154Y672431D01*
G01X-1144594Y700631D02*
X-1144515Y700496D01*
G01X-1144662Y700764D02*
X-1144594Y700631D01*
G01X-1144232Y669639D02*
X-1144152Y669629D01*
G01X-1144308Y669657D02*
X-1144232Y669639D01*
G01X-1144377Y669682D02*
X-1144308Y669657D01*
G01X-1144437Y669712D02*
X-1144377Y669682D01*
G01X-1144485Y669748D02*
X-1144437Y669712D01*
G01X-1144520Y669786D02*
X-1144485Y669748D01*
G01X-1144540Y669826D02*
X-1144520Y669786D01*
G01X-1144157Y670374D02*
X-1144077Y670364D01*
G01X-1144233Y670392D02*
X-1144157Y670374D01*
G01X-1144302Y670417D02*
X-1144233Y670392D01*
G01X-1144362Y670447D02*
X-1144302Y670417D01*
G01X-1144411Y670482D02*
X-1144362Y670447D01*
G01X-1144445Y670521D02*
X-1144411Y670482D01*
G01X-1144465Y670561D02*
X-1144445Y670521D01*
G01X-1130059Y669639D02*
X-1129979Y669629D01*
G01X-1130134Y669657D02*
X-1130059Y669639D01*
G01X-1130204Y669682D02*
X-1130134Y669657D01*
G01X-1130264Y669712D02*
X-1130204Y669682D01*
G01X-1130312Y669748D02*
X-1130264Y669712D01*
G01X-1130347Y669786D02*
X-1130312Y669748D01*
G01X-1130367Y669826D02*
X-1130347Y669786D01*
G01X-1129984Y670374D02*
X-1129904Y670364D01*
G01X-1130060Y670392D02*
X-1129984Y670374D01*
G01X-1130129Y670417D02*
X-1130060Y670392D01*
G01X-1130189Y670447D02*
X-1130129Y670417D01*
G01X-1130237Y670482D02*
X-1130189Y670447D01*
G01X-1130272Y670521D02*
X-1130237Y670482D01*
G01X-1130292Y670561D02*
X-1130272Y670521D01*
G01X-1084607Y701322D02*
X-1084770Y700764D01*
G01X-1084527Y701747D02*
X-1084607Y701322D01*
G01X-1084535Y702016D02*
X-1084527Y701747D01*
G01X-1084629Y702110D02*
X-1084535Y702016D01*
G01X-1084402Y702078D02*
X-1084629Y702110D01*
G01X-1084255Y702008D02*
X-1084402Y702078D01*
G01X-1084166Y701902D02*
X-1084255Y702008D01*
G01X-1087482Y699951D02*
X-1087385Y699747D01*
G01X-1087599Y700155D02*
X-1087482Y699951D01*
G01X-1087822Y700496D02*
X-1087599Y700155D01*
G01X-1130421Y700631D02*
X-1130342Y700496D01*
G01X-1130489Y700764D02*
X-1130421Y700631D01*
G01X-1087539Y669639D02*
X-1087459Y669629D01*
G01X-1087615Y669657D02*
X-1087539Y669639D01*
G01X-1087684Y669682D02*
X-1087615Y669657D01*
G01X-1087744Y669712D02*
X-1087684Y669682D01*
G01X-1087792Y669748D02*
X-1087744Y669712D01*
G01X-1087827Y669786D02*
X-1087792Y669748D01*
G01X-1087847Y669826D02*
X-1087827Y669786D01*
G01X-1087464Y670374D02*
X-1087384Y670364D01*
G01X-1087540Y670392D02*
X-1087464Y670374D01*
G01X-1087609Y670417D02*
X-1087540Y670392D01*
G01X-1087669Y670447D02*
X-1087609Y670417D01*
G01X-1087718Y670482D02*
X-1087669Y670447D01*
G01X-1087752Y670521D02*
X-1087718Y670482D01*
G01X-1087772Y670561D02*
X-1087752Y670521D01*
G01X-1146771Y702103D02*
X-1146834Y702110D01*
G01X-1146711Y702084D02*
X-1146771Y702103D01*
G01X-1146655Y702052D02*
X-1146711Y702084D01*
G01X-1146608Y702010D02*
X-1146655Y702052D01*
G01X-1146570Y701960D02*
X-1146608Y702010D01*
G01X-1146543Y701902D02*
X-1146570Y701960D01*
G01X-1146561Y702103D02*
X-1146624Y702110D01*
G01X-1146501Y702084D02*
X-1146561Y702103D01*
G01X-1146445Y702052D02*
X-1146501Y702084D01*
G01X-1146398Y702010D02*
X-1146445Y702052D01*
G01X-1146360Y701960D02*
X-1146398Y702010D01*
G01X-1146333Y701902D02*
X-1146360Y701960D01*
G01X-1145518Y702103D02*
X-1145581Y702110D01*
G01X-1145458Y702084D02*
X-1145518Y702103D01*
G01X-1145403Y702053D02*
X-1145458Y702084D01*
G01X-1145355Y702010D02*
X-1145403Y702053D01*
G01X-1145317Y701960D02*
X-1145355Y702010D01*
G01X-1145289Y701902D02*
X-1145317Y701960D01*
G01X-1145161Y702103D02*
X-1145225Y702110D01*
G01X-1145102Y702084D02*
X-1145161Y702103D01*
G01X-1145047Y702053D02*
X-1145102Y702084D01*
G01X-1144999Y702010D02*
X-1145047Y702053D01*
G01X-1144961Y701960D02*
X-1144999Y702010D01*
G01X-1144933Y701902D02*
X-1144961Y701960D01*
G01X-1132598Y702103D02*
X-1132661Y702110D01*
G01X-1132538Y702084D02*
X-1132598Y702103D01*
G01X-1132482Y702052D02*
X-1132538Y702084D01*
G01X-1132435Y702010D02*
X-1132482Y702052D01*
G01X-1132397Y701960D02*
X-1132435Y702010D01*
G01X-1132370Y701902D02*
X-1132397Y701960D01*
G01X-1132387Y702103D02*
X-1132451Y702110D01*
G01X-1132328Y702084D02*
X-1132387Y702103D01*
G01X-1132272Y702052D02*
X-1132328Y702084D01*
G01X-1132225Y702010D02*
X-1132272Y702052D01*
G01X-1132187Y701960D02*
X-1132225Y702010D01*
G01X-1132159Y701902D02*
X-1132187Y701960D01*
G01X-1131344Y702103D02*
X-1131408Y702110D01*
G01X-1131285Y702084D02*
X-1131344Y702103D01*
G01X-1131230Y702053D02*
X-1131285Y702084D01*
G01X-1131182Y702010D02*
X-1131230Y702053D01*
G01X-1131144Y701960D02*
X-1131182Y702010D01*
G01X-1131116Y701902D02*
X-1131144Y701960D01*
G01X-1130988Y702103D02*
X-1131052Y702110D01*
G01X-1130928Y702084D02*
X-1130988Y702103D01*
G01X-1130874Y702053D02*
X-1130928Y702084D01*
G01X-1130825Y702010D02*
X-1130874Y702053D01*
G01X-1130787Y701960D02*
X-1130825Y702010D01*
G01X-1130760Y701902D02*
X-1130787Y701960D01*
G01X-1109670Y671955D02*
X-1109573Y671942D01*
G01X-1109771Y671998D02*
X-1109670Y671955D01*
G01X-1109872Y672070D02*
X-1109771Y671998D01*
G01X-1109969Y672167D02*
X-1109872Y672070D01*
G01X-1110063Y672288D02*
X-1109969Y672167D01*
G01X-1110154Y672431D02*
X-1110063Y672288D01*
G01X-1110243Y672594D02*
X-1110154Y672431D01*
G01X-1110330Y672779D02*
X-1110243Y672594D01*
G01X-1144754Y675644D02*
X-1144670Y675623D01*
G01X-1144832Y675679D02*
X-1144754Y675644D01*
G01X-1144899Y675723D02*
X-1144832Y675679D01*
G01X-1144952Y675775D02*
X-1144899Y675723D01*
G01X-1144989Y675834D02*
X-1144952Y675775D01*
G01X-1145009Y675895D02*
X-1144989Y675834D01*
G01X-1130580Y675644D02*
X-1130496Y675623D01*
G01X-1130659Y675679D02*
X-1130580Y675644D01*
G01X-1130725Y675723D02*
X-1130659Y675679D01*
G01X-1130779Y675775D02*
X-1130725Y675723D01*
G01X-1130816Y675834D02*
X-1130779Y675775D01*
G01X-1130836Y675895D02*
X-1130816Y675834D01*
G01X-1144565Y702019D02*
X-1144471Y702110D01*
G01X-1144574Y701752D02*
X-1144565Y702019D01*
G01X-1144494Y701326D02*
X-1144574Y701752D01*
G01X-1144329Y700764D02*
X-1144494Y701326D01*
G01X-1130391Y702019D02*
X-1130298Y702110D01*
G01X-1130400Y701752D02*
X-1130391Y702019D01*
G01X-1130321Y701326D02*
X-1130400Y701752D01*
G01X-1130156Y700764D02*
X-1130321Y701326D01*
G01X-1140993Y674410D02*
X-1140988Y674309D01*
G01X-1141007Y674505D02*
X-1140993Y674410D01*
G01X-1141029Y674587D02*
X-1141007Y674505D01*
G01X-1144479Y699954D02*
X-1144465Y699741D01*
G01X-1144513Y700169D02*
X-1144479Y699954D01*
G01X-1144567Y700381D02*
X-1144513Y700169D01*
G01X-1150392Y664133D02*
X-1150317Y664117D01*
G01X-1150456Y664175D02*
X-1150392Y664133D01*
G01X-1150498Y664240D02*
X-1150456Y664175D01*
G01X-1150514Y664314D02*
X-1150498Y664240D01*
G01X-1143305Y664133D02*
X-1143230Y664117D01*
G01X-1143370Y664175D02*
X-1143305Y664133D01*
G01X-1143412Y664240D02*
X-1143370Y664175D01*
G01X-1143427Y664314D02*
X-1143412Y664240D01*
G01X-1136219Y664133D02*
X-1136144Y664117D01*
G01X-1136283Y664175D02*
X-1136219Y664133D01*
G01X-1136325Y664240D02*
X-1136283Y664175D01*
G01X-1136340Y664314D02*
X-1136325Y664240D01*
G01X-1140629Y674788D02*
X-1140641Y674865D01*
G01X-1140619Y674703D02*
X-1140629Y674788D01*
G01X-1140611Y674610D02*
X-1140619Y674703D01*
G01X-1126456Y674788D02*
X-1126468Y674865D01*
G01X-1126446Y674703D02*
X-1126456Y674788D01*
G01X-1126438Y674610D02*
X-1126446Y674703D01*
G01X-1145063Y698430D02*
X-1145131Y698650D01*
G01X-1145023Y698205D02*
X-1145063Y698430D01*
G01X-1145009Y697977D02*
X-1145023Y698205D01*
G01X-1130890Y698430D02*
X-1130957Y698650D01*
G01X-1130850Y698205D02*
X-1130890Y698430D01*
G01X-1130836Y697977D02*
X-1130850Y698205D01*
G01X-1144686Y698521D02*
X-1144766Y698784D01*
G01X-1144638Y698251D02*
X-1144686Y698521D01*
G01X-1144622Y697977D02*
X-1144638Y698251D01*
G01X-1130513Y698521D02*
X-1130593Y698784D01*
G01X-1130465Y698251D02*
X-1130513Y698521D01*
G01X-1130448Y697977D02*
X-1130465Y698251D01*
G01X-1145274Y698431D02*
X-1145341Y698650D01*
G01X-1145234Y698205D02*
X-1145274Y698431D01*
G01X-1145221Y697977D02*
X-1145234Y698205D01*
G01X-1131101Y698431D02*
X-1131167Y698650D01*
G01X-1131061Y698205D02*
X-1131101Y698431D01*
G01X-1131048Y697977D02*
X-1131061Y698205D01*
G01X-1144661Y700161D02*
X-1144727Y700381D01*
G01X-1144621Y699936D02*
X-1144661Y700161D01*
G01X-1144607Y699707D02*
X-1144621Y699936D01*
G01X-1130488Y700161D02*
X-1130554Y700381D01*
G01X-1130447Y699936D02*
X-1130488Y700161D01*
G01X-1130434Y699707D02*
X-1130447Y699936D01*
G01X-1126834Y674505D02*
X-1126856Y674587D01*
G01X-1126820Y674410D02*
X-1126834Y674505D01*
G01X-1126815Y674309D02*
X-1126820Y674410D01*
G01X-1145607Y674406D02*
X-1145606Y674309D01*
G01X-1145607Y674507D02*
Y674406D01*
G01X-1145609Y674610D02*
X-1145607Y674507D01*
G01X-1140609Y674510D02*
X-1140611Y674610D01*
G01X-1140607Y674409D02*
X-1140609Y674510D01*
G01X-1131434Y674406D02*
X-1131433Y674309D01*
G01X-1131434Y674507D02*
Y674406D01*
G01X-1131435Y674610D02*
X-1131434Y674507D01*
G01X-1145225Y674412D02*
Y669826D01*
G01X-1145223Y674513D02*
X-1145225Y674412D01*
G01X-1145221Y674610D02*
X-1145223Y674513D01*
G01X-1144825Y674505D02*
X-1144803Y674587D01*
G01X-1144839Y674410D02*
X-1144825Y674505D01*
G01X-1144844Y674309D02*
X-1144839Y674410D01*
G01X-1140558Y698430D02*
X-1140491Y698650D01*
G01X-1140598Y698205D02*
X-1140558Y698430D01*
G01X-1140611Y697977D02*
X-1140598Y698205D01*
G01X-1141280Y700169D02*
X-1141226Y700381D01*
G01X-1141314Y699954D02*
X-1141280Y700169D01*
G01X-1141327Y699741D02*
X-1141314Y699954D01*
G01X-1087901Y700631D02*
X-1087822Y700496D01*
G01X-1087969Y700764D02*
X-1087901Y700631D01*
G01X-1090078Y702103D02*
X-1090141Y702110D01*
G01X-1090018Y702084D02*
X-1090078Y702103D01*
G01X-1089962Y702052D02*
X-1090018Y702084D01*
G01X-1089915Y702010D02*
X-1089962Y702052D01*
G01X-1089877Y701960D02*
X-1089915Y702010D01*
G01X-1089850Y701902D02*
X-1089877Y701960D01*
G01X-1089868Y702103D02*
X-1089931Y702110D01*
G01X-1089808Y702084D02*
X-1089868Y702103D01*
G01X-1089752Y702052D02*
X-1089808Y702084D01*
G01X-1089705Y702010D02*
X-1089752Y702052D01*
G01X-1089667Y701960D02*
X-1089705Y702010D01*
G01X-1089640Y701902D02*
X-1089667Y701960D01*
G01X-1088825Y702103D02*
X-1088888Y702110D01*
G01X-1088765Y702084D02*
X-1088825Y702103D01*
G01X-1088710Y702053D02*
X-1088765Y702084D01*
G01X-1088662Y702010D02*
X-1088710Y702053D01*
G01X-1088624Y701960D02*
X-1088662Y702010D01*
G01X-1088597Y701902D02*
X-1088624Y701960D01*
G01X-1088468Y702103D02*
X-1088532Y702110D01*
G01X-1088409Y702084D02*
X-1088468Y702103D01*
G01X-1088354Y702053D02*
X-1088409Y702084D01*
G01X-1088306Y702010D02*
X-1088354Y702053D01*
G01X-1088268Y701960D02*
X-1088306Y702010D01*
G01X-1088240Y701902D02*
X-1088268Y701960D01*
G01X-1088061Y675644D02*
X-1087977Y675623D01*
G01X-1088139Y675679D02*
X-1088061Y675644D01*
G01X-1088206Y675723D02*
X-1088139Y675679D01*
G01X-1088259Y675775D02*
X-1088206Y675723D01*
G01X-1088297Y675834D02*
X-1088259Y675775D01*
G01X-1088316Y675895D02*
X-1088297Y675834D01*
G01X-1088191Y674600D02*
X-1088110Y674587D01*
G01X-1088267Y674625D02*
X-1088191Y674600D01*
G01X-1088338Y674660D02*
X-1088267Y674625D01*
G01X-1088398Y674703D02*
X-1088338Y674660D01*
G01X-1088446Y674753D02*
X-1088398Y674703D01*
G01X-1088480Y674808D02*
X-1088446Y674753D01*
G01X-1088498Y674865D02*
X-1088480Y674808D01*
G01X-1087872Y702019D02*
X-1087778Y702110D01*
G01X-1087881Y701752D02*
X-1087872Y702019D01*
G01X-1087801Y701326D02*
X-1087881Y701752D01*
G01X-1087637Y700764D02*
X-1087801Y701326D01*
G01X-1084300Y674410D02*
X-1084295Y674309D01*
G01X-1084314Y674505D02*
X-1084300Y674410D01*
G01X-1084336Y674587D02*
X-1084314Y674505D01*
G01X-1130306Y699954D02*
X-1130292Y699741D01*
G01X-1130339Y700169D02*
X-1130306Y699954D01*
G01X-1130394Y700381D02*
X-1130339Y700169D01*
G01X-1115814Y704384D02*
X-1115787Y704275D01*
G01X-1115828Y704450D02*
X-1115814Y704384D01*
G01X-1115833Y704472D02*
X-1115828Y704450D01*
G01X-1100154Y704595D02*
X-1100527Y704669D01*
G01X-1099837Y704386D02*
X-1100154Y704595D01*
G01X-1099623Y704073D02*
X-1099837Y704386D01*
G01X-1099543Y703702D02*
X-1099623Y704073D01*
G01X-1104730Y672595D02*
X-1104645Y672779D01*
G01X-1104812Y672433D02*
X-1104730Y672595D01*
G01X-1104894Y672292D02*
X-1104812Y672433D01*
G01X-1104974Y672172D02*
X-1104894Y672292D01*
G01X-1105054Y672075D02*
X-1104974Y672172D01*
G01X-1105133Y672003D02*
X-1105054Y672075D01*
G01X-1105207Y671959D02*
X-1105133Y672003D01*
G01X-1105279Y671942D02*
X-1105207Y671959D01*
G01X-1105349Y671954D02*
X-1105279Y671942D01*
G01X-1105416Y671995D02*
X-1105349Y671954D01*
G01X-1105479Y672067D02*
X-1105416Y671995D01*
G01X-1105536Y672164D02*
X-1105479Y672067D01*
G01X-1105588Y672285D02*
X-1105536Y672164D01*
G01X-1105634Y672428D02*
X-1105588Y672285D01*
G01X-1105676Y672593D02*
X-1105634Y672428D01*
G01X-1105714Y672779D02*
X-1105676Y672593D01*
G01X-1118076Y668031D02*
X-1117700Y667956D01*
G01X-1118395Y668244D02*
X-1118076Y668031D01*
G01X-1118609Y668563D02*
X-1118395Y668244D01*
G01X-1118684Y668940D02*
X-1118609Y668563D01*
G01X-1101575Y679692D02*
X-1101951Y679767D01*
G01X-1101255Y679479D02*
X-1101575Y679692D01*
G01X-1101042Y679160D02*
X-1101255Y679479D01*
G01X-1100967Y678783D02*
X-1101042Y679160D01*
G01X-1110664Y704537D02*
X-1110620Y704275D01*
G01X-1110686Y704669D02*
X-1110664Y704537D01*
G01X-1144749Y700999D02*
X-1144567Y700381D01*
G01X-1144865Y701482D02*
X-1144749Y700999D01*
G01X-1144933Y701902D02*
X-1144865Y701482D01*
G01X-1130576Y700999D02*
X-1130394Y700381D01*
G01X-1130691Y701482D02*
X-1130576Y700999D01*
G01X-1130760Y701902D02*
X-1130691Y701482D01*
G01X-1129152Y673348D02*
X-1129108Y673330D01*
G01X-1129192Y673377D02*
X-1129152Y673348D01*
G01X-1129224Y673416D02*
X-1129192Y673377D01*
G01X-1129246Y673464D02*
X-1129224Y673416D01*
G01X-1129254Y673520D02*
X-1129246Y673464D01*
G01X-1144239Y669442D02*
X-1144152Y669432D01*
G01X-1144321Y669472D02*
X-1144239Y669442D01*
G01X-1144394Y669518D02*
X-1144321Y669472D01*
G01X-1144456Y669582D02*
X-1144394Y669518D01*
G01X-1144502Y669656D02*
X-1144456Y669582D01*
G01X-1144530Y669739D02*
X-1144502Y669656D01*
G01X-1144540Y669826D02*
X-1144530Y669739D01*
G01X-1130066Y669442D02*
X-1129979Y669432D01*
G01X-1130148Y669472D02*
X-1130066Y669442D01*
G01X-1130221Y669518D02*
X-1130148Y669472D01*
G01X-1130283Y669582D02*
X-1130221Y669518D01*
G01X-1130329Y669656D02*
X-1130283Y669582D01*
G01X-1130357Y669739D02*
X-1130329Y669656D01*
G01X-1130367Y669826D02*
X-1130357Y669739D01*
G01X-1097265Y683734D02*
X-1097424Y683802D01*
G01X-1097139Y683552D02*
X-1097265Y683734D01*
G01X-1097058Y683299D02*
X-1097139Y683552D01*
G01X-1097030Y683015D02*
X-1097058Y683299D01*
G01X-1088371Y698430D02*
X-1088438Y698650D01*
G01X-1088330Y698205D02*
X-1088371Y698430D01*
G01X-1088316Y697977D02*
X-1088330Y698205D01*
G01X-1087993Y698521D02*
X-1088073Y698784D01*
G01X-1087945Y698251D02*
X-1087993Y698521D01*
G01X-1087929Y697977D02*
X-1087945Y698251D01*
G01X-1088582Y698431D02*
X-1088648Y698650D01*
G01X-1088541Y698205D02*
X-1088582Y698431D01*
G01X-1088528Y697977D02*
X-1088541Y698205D01*
G01X-1087968Y700161D02*
X-1088034Y700381D01*
G01X-1087928Y699936D02*
X-1087968Y700161D01*
G01X-1087914Y699707D02*
X-1087928Y699936D01*
G01X-1126435Y674510D02*
X-1126438Y674610D01*
G01X-1126434Y674409D02*
X-1126435Y674510D01*
G01X-1088914Y674406D02*
X-1088913Y674309D01*
G01X-1088914Y674507D02*
Y674406D01*
G01X-1088916Y674610D02*
X-1088914Y674507D01*
G01X-1131051Y674412D02*
X-1131052Y669826D01*
G01X-1131050Y674513D02*
X-1131051Y674412D01*
G01X-1131048Y674610D02*
X-1131050Y674513D01*
G01X-1130652Y674505D02*
X-1130630Y674587D01*
G01X-1130666Y674410D02*
X-1130652Y674505D01*
G01X-1130670Y674309D02*
X-1130666Y674410D01*
G01X-1126384Y698430D02*
X-1126318Y698650D01*
G01X-1126425Y698205D02*
X-1126384Y698430D01*
G01X-1126438Y697977D02*
X-1126425Y698205D01*
G01X-1127107Y700169D02*
X-1127052Y700381D01*
G01X-1127141Y699954D02*
X-1127107Y700169D01*
G01X-1127154Y699741D02*
X-1127141Y699954D01*
G01X-1117766Y679587D02*
X-1117545Y679612D01*
G01X-1117973Y679514D02*
X-1117766Y679587D01*
G01X-1118158Y679397D02*
X-1117973Y679514D01*
G01X-1118316Y679239D02*
X-1118158Y679397D01*
G01X-1118432Y679053D02*
X-1118316Y679239D01*
G01X-1118504Y678846D02*
X-1118432Y679053D01*
G01X-1118529Y678628D02*
X-1118504Y678846D01*
G01X-1145213Y674702D02*
X-1145221Y674610D01*
G01X-1145203Y674788D02*
X-1145213Y674702D01*
G01X-1145191Y674865D02*
X-1145203Y674788D01*
G01X-1131040Y674702D02*
X-1131048Y674610D01*
G01X-1131030Y674788D02*
X-1131040Y674702D01*
G01X-1131018Y674865D02*
X-1131030Y674788D01*
G01X-1141045Y700996D02*
X-1141226Y700381D01*
G01X-1140929Y701478D02*
X-1141045Y700996D01*
G01X-1140859Y701902D02*
X-1140929Y701478D01*
G01X-1126871Y700996D02*
X-1127052Y700381D01*
G01X-1126756Y701478D02*
X-1126871Y700996D01*
G01X-1126686Y701902D02*
X-1126756Y701478D01*
G01X-1120220Y683986D02*
X-1120492Y683849D01*
G01X-1120003Y684199D02*
X-1120220Y683986D01*
G01X-1119861Y684469D02*
X-1120003Y684199D01*
G01X-1119809Y684770D02*
X-1119861Y684469D01*
G01X-1147052Y664133D02*
X-1147128Y664117D01*
G01X-1146988Y664176D02*
X-1147052Y664133D01*
G01X-1146945Y664240D02*
X-1146988Y664176D01*
G01X-1146931Y664314D02*
X-1146945Y664240D01*
G01X-1139966Y664133D02*
X-1140041Y664117D01*
G01X-1139902Y664176D02*
X-1139966Y664133D01*
G01X-1139859Y664240D02*
X-1139902Y664176D01*
G01X-1139844Y664314D02*
X-1139859Y664240D01*
G01X-1132879Y664133D02*
X-1132955Y664117D01*
G01X-1132815Y664176D02*
X-1132879Y664133D01*
G01X-1132772Y664240D02*
X-1132815Y664176D01*
G01X-1132758Y664314D02*
X-1132772Y664240D01*
G01X-1125793Y674008D02*
X-1125868Y673993D01*
G01X-1125729Y674051D02*
X-1125793Y674008D01*
G01X-1125686Y674116D02*
X-1125729Y674051D01*
G01X-1125671Y674190D02*
X-1125686Y674116D01*
G01X-1141172Y699936D02*
X-1141185Y699707D01*
G01X-1141132Y700161D02*
X-1141172Y699936D01*
G01X-1141066Y700381D02*
X-1141132Y700161D01*
G01X-1141194Y698251D02*
X-1141210Y697977D01*
G01X-1141146Y698521D02*
X-1141194Y698251D01*
G01X-1141066Y698784D02*
X-1141146Y698521D01*
G01X-1140809Y698205D02*
X-1140823Y697977D01*
G01X-1140769Y698430D02*
X-1140809Y698205D01*
G01X-1140701Y698650D02*
X-1140769Y698430D01*
G01X-1087786Y699954D02*
X-1087772Y699741D01*
G01X-1087820Y700169D02*
X-1087786Y699954D01*
G01X-1087874Y700381D02*
X-1087820Y700169D01*
G01X-1086612Y664133D02*
X-1086537Y664117D01*
G01X-1086677Y664175D02*
X-1086612Y664133D01*
G01X-1086719Y664240D02*
X-1086677Y664175D01*
G01X-1086734Y664314D02*
X-1086719Y664240D01*
G01X-1088056Y700999D02*
X-1087874Y700381D01*
G01X-1088172Y701482D02*
X-1088056Y700999D01*
G01X-1088240Y701902D02*
X-1088172Y701482D01*
G01X-1083926Y674703D02*
X-1083918Y674610D01*
G01X-1083936Y674788D02*
X-1083926Y674703D01*
G01X-1083948Y674865D02*
X-1083936Y674788D01*
G01X-1097135Y683747D02*
X-1097424Y683802D01*
G01X-1096913Y683614D02*
X-1097135Y683747D01*
G01X-1096757Y683434D02*
X-1096913Y683614D01*
G01X-1096666Y683230D02*
X-1096757Y683434D01*
G01X-1096637Y683015D02*
X-1096666Y683230D01*
G01X-1087546Y669442D02*
X-1087459Y669432D01*
G01X-1087628Y669472D02*
X-1087546Y669442D01*
G01X-1087701Y669518D02*
X-1087628Y669472D01*
G01X-1087763Y669582D02*
X-1087701Y669518D01*
G01X-1087809Y669656D02*
X-1087763Y669582D01*
G01X-1087837Y669739D02*
X-1087809Y669656D01*
G01X-1087847Y669826D02*
X-1087837Y669739D01*
G01X-1083916Y674510D02*
X-1083918Y674610D01*
G01X-1083915Y674409D02*
X-1083916Y674510D01*
G01X-1088532Y674412D02*
Y669826D01*
G01X-1088530Y674513D02*
X-1088532Y674412D01*
G01X-1088528Y674610D02*
X-1088530Y674513D01*
G01X-1088132Y674505D02*
X-1088110Y674587D01*
G01X-1088146Y674410D02*
X-1088132Y674505D01*
G01X-1088151Y674309D02*
X-1088146Y674410D01*
G01X-1083865Y698430D02*
X-1083798Y698650D01*
G01X-1083905Y698205D02*
X-1083865Y698430D01*
G01X-1083918Y697977D02*
X-1083905Y698205D01*
G01X-1084587Y700169D02*
X-1084533Y700381D01*
G01X-1084621Y699954D02*
X-1084587Y700169D01*
G01X-1084634Y699741D02*
X-1084621Y699954D01*
G01X-1088510Y674788D02*
X-1088498Y674865D01*
G01X-1088520Y674703D02*
X-1088510Y674788D01*
G01X-1088528Y674610D02*
X-1088520Y674703D01*
G01X-1084352Y700996D02*
X-1084533Y700381D01*
G01X-1084236Y701478D02*
X-1084352Y700996D01*
G01X-1084166Y701902D02*
X-1084236Y701478D01*
G01X-1118867Y704595D02*
X-1118494Y704669D01*
G01X-1119184Y704386D02*
X-1118867Y704595D01*
G01X-1119398Y704073D02*
X-1119184Y704386D01*
G01X-1119478Y703702D02*
X-1119398Y704073D01*
G01X-1103318Y704450D02*
X-1103314Y704472D01*
G01X-1103333Y704386D02*
X-1103318Y704450D01*
G01X-1103359Y704275D02*
X-1103333Y704386D01*
G01X-1126999Y699936D02*
X-1127012Y699707D01*
G01X-1126959Y700161D02*
X-1126999Y699936D01*
G01X-1126892Y700381D02*
X-1126959Y700161D01*
G01X-1127021Y698251D02*
X-1127037Y697977D01*
G01X-1126973Y698521D02*
X-1127021Y698251D01*
G01X-1126893Y698784D02*
X-1126973Y698521D01*
G01X-1126636Y698205D02*
X-1126649Y697977D01*
G01X-1126595Y698430D02*
X-1126636Y698205D01*
G01X-1126528Y698650D02*
X-1126595Y698430D01*
G01X-1140948Y674600D02*
X-1141029Y674587D01*
G01X-1140872Y674625D02*
X-1140948Y674600D01*
G01X-1140801Y674660D02*
X-1140872Y674625D01*
G01X-1140741Y674703D02*
X-1140801Y674660D01*
G01X-1140693Y674753D02*
X-1140741Y674703D01*
G01X-1140659Y674808D02*
X-1140693Y674753D01*
G01X-1140641Y674865D02*
X-1140659Y674808D01*
G01X-1114172Y672172D02*
X-1114253Y672292D01*
G01X-1114092Y672075D02*
X-1114172Y672172D01*
G01X-1114014Y672003D02*
X-1114092Y672075D01*
G01X-1113939Y671959D02*
X-1114014Y672003D01*
G01X-1113868Y671942D02*
X-1113939Y671959D01*
G01X-1113798Y671954D02*
X-1113868Y671942D01*
G01X-1113731Y671996D02*
X-1113798Y671954D01*
G01X-1113668Y672067D02*
X-1113731Y671996D01*
G01X-1113611Y672164D02*
X-1113668Y672067D01*
G01X-1113559Y672285D02*
X-1113611Y672164D01*
G01X-1113511Y672433D02*
X-1113559Y672285D01*
G01X-1140275Y702103D02*
X-1140212Y702110D01*
G01X-1140335Y702084D02*
X-1140275Y702103D01*
G01X-1140390Y702052D02*
X-1140335Y702084D01*
G01X-1140438Y702010D02*
X-1140390Y702052D01*
G01X-1140476Y701960D02*
X-1140438Y702010D01*
G01X-1140503Y701902D02*
X-1140476Y701960D01*
G01X-1139271Y702103D02*
X-1139208Y702110D01*
G01X-1139331Y702084D02*
X-1139271Y702103D01*
G01X-1139387Y702052D02*
X-1139331Y702084D01*
G01X-1139434Y702010D02*
X-1139387Y702052D01*
G01X-1139472Y701960D02*
X-1139434Y702010D01*
G01X-1139499Y701902D02*
X-1139472Y701960D01*
G01X-1126102Y702103D02*
X-1126038Y702110D01*
G01X-1126162Y702084D02*
X-1126102Y702103D01*
G01X-1126217Y702052D02*
X-1126162Y702084D01*
G01X-1126265Y702010D02*
X-1126217Y702052D01*
G01X-1126303Y701960D02*
X-1126265Y702010D01*
G01X-1126330Y701902D02*
X-1126303Y701960D01*
G01X-1125098Y702103D02*
X-1125035Y702110D01*
G01X-1125158Y702084D02*
X-1125098Y702103D01*
G01X-1125213Y702052D02*
X-1125158Y702084D01*
G01X-1125261Y702010D02*
X-1125213Y702052D01*
G01X-1125299Y701960D02*
X-1125261Y702010D01*
G01X-1125326Y701902D02*
X-1125299Y701960D01*
G01X-1141618Y699951D02*
X-1141500Y700155D01*
G01X-1141715Y699747D02*
X-1141618Y699951D01*
G01X-1127444D02*
X-1127327Y700155D01*
G01X-1127542Y699747D02*
X-1127444Y699951D01*
G01X-1141199Y700631D02*
X-1141130Y700764D01*
G01X-1141277Y700496D02*
X-1141199Y700631D01*
G01X-1141500Y700155D02*
X-1141277Y700496D01*
G01X-1083273Y664133D02*
X-1083348Y664117D01*
G01X-1083209Y664176D02*
X-1083273Y664133D01*
G01X-1083166Y664240D02*
X-1083209Y664176D01*
G01X-1083151Y664314D02*
X-1083166Y664240D01*
G01X-1084479Y699936D02*
X-1084493Y699707D01*
G01X-1084439Y700161D02*
X-1084479Y699936D01*
G01X-1084373Y700381D02*
X-1084439Y700161D01*
G01X-1084501Y698251D02*
X-1084518Y697977D01*
G01X-1084453Y698521D02*
X-1084501Y698251D01*
G01X-1084373Y698784D02*
X-1084453Y698521D01*
G01X-1084116Y698205D02*
X-1084130Y697977D01*
G01X-1084076Y698430D02*
X-1084116Y698205D01*
G01X-1084009Y698650D02*
X-1084076Y698430D01*
G01X-1083582Y702103D02*
X-1083519Y702110D01*
G01X-1083642Y702084D02*
X-1083582Y702103D01*
G01X-1083698Y702052D02*
X-1083642Y702084D01*
G01X-1083745Y702010D02*
X-1083698Y702052D01*
G01X-1083783Y701960D02*
X-1083745Y702010D01*
G01X-1083810Y701902D02*
X-1083783Y701960D01*
G01X-1082578Y702103D02*
X-1082515Y702110D01*
G01X-1082638Y702084D02*
X-1082578Y702103D01*
G01X-1082694Y702052D02*
X-1082638Y702084D01*
G01X-1082741Y702010D02*
X-1082694Y702052D01*
G01X-1082779Y701960D02*
X-1082741Y702010D01*
G01X-1082806Y701902D02*
X-1082779Y701960D01*
G01X-1084925Y699951D02*
X-1084808Y700155D01*
G01X-1085022Y699747D02*
X-1084925Y699951D01*
G01X-1104813Y672433D02*
X-1104730Y672595D01*
G01X-1104894Y672292D02*
X-1104813Y672433D01*
G01X-1127025Y700631D02*
X-1126957Y700764D01*
G01X-1127104Y700496D02*
X-1127025Y700631D01*
G01X-1127327Y700155D02*
X-1127104Y700496D01*
G01X-1084506Y700631D02*
X-1084437Y700764D01*
G01X-1084584Y700496D02*
X-1084506Y700631D01*
G01X-1084808Y700155D02*
X-1084584Y700496D01*
G01X-1147043Y664136D02*
X-1147128Y664117D01*
G01X-1146980Y664184D02*
X-1147043Y664136D01*
G01X-1146936Y664251D02*
X-1146980Y664184D01*
G01X-1132870Y664136D02*
X-1132955Y664117D01*
G01X-1132807Y664184D02*
X-1132870Y664136D01*
G01X-1132763Y664251D02*
X-1132807Y664184D01*
G01X-1144694Y702079D02*
X-1144471Y702110D01*
G01X-1144852Y702002D02*
X-1144694Y702079D01*
G01X-1144933Y701902D02*
X-1144852Y702002D01*
G01X-1130521Y702079D02*
X-1130298Y702110D01*
G01X-1130679Y702002D02*
X-1130521Y702079D01*
G01X-1130760Y701902D02*
X-1130679Y702002D01*
G01X-1088001Y702079D02*
X-1087778Y702110D01*
G01X-1088159Y702002D02*
X-1088001Y702079D01*
G01X-1088240Y701902D02*
X-1088159Y702002D01*
G01X-1090347Y664130D02*
X-1090388Y664124D01*
G01X-1090307Y664145D02*
X-1090347Y664130D01*
G01X-1090270Y664170D02*
X-1090307Y664145D01*
G01X-1090238Y664203D02*
X-1090270Y664170D01*
G01X-1125780Y664130D02*
X-1125821Y664124D01*
G01X-1125740Y664145D02*
X-1125780Y664130D01*
G01X-1125703Y664170D02*
X-1125740Y664145D01*
G01X-1125671Y664203D02*
X-1125703Y664170D01*
G01X-1122593Y683299D02*
X-1122621Y683015D01*
G01X-1122511Y683553D02*
X-1122593Y683299D01*
G01X-1122384Y683736D02*
X-1122511Y683553D01*
G01X-1122227Y683802D02*
X-1122384Y683736D01*
G01X-1125679Y673464D02*
X-1125671Y673520D01*
G01X-1125701Y673415D02*
X-1125679Y673464D01*
G01X-1125733Y673377D02*
X-1125701Y673415D01*
G01X-1125773Y673348D02*
X-1125733Y673377D01*
G01X-1125817Y673330D02*
X-1125773Y673348D01*
G01X-1083992Y700240D02*
G03X-1084087Y699707I1440J-532D01*
G01X-1083417Y698509D02*
G03X-1083512Y697977I1440J-532D01*
G01X-1085829Y669432D02*
G03X-1086222Y669039I0J-393D01*
G01X-1083663D02*
G03X-1084057Y669432I-393J0D01*
G01X-1099543Y703702D02*
G03X-1100527Y704669I-984J-17D01*
G01X-1088934Y697977D02*
G03X-1089029Y698509I-1535J0D01*
G01X-1088320Y699707D02*
G03X-1088416Y700240I-1536J-1D01*
G01X-1088545Y669826D02*
G03X-1088151Y669432I394J0D01*
G01X-1090750Y669039D02*
G03X-1091144Y669432I-393J0D01*
G01X-1092915D02*
G03X-1093309Y669039I0J-394D01*
G01X-1088899Y669826D02*
G03X-1088151Y669078I748J0D01*
G01X-1096636Y683015D02*
G03X-1097424Y683802I-787J0D01*
G01X-1099212Y684770D02*
G03X-1098228Y683802I984J16D01*
G01X-1083664Y647385D02*
G03I-709J0D01*
G01Y641873D02*
G03I-709J0D01*
G01X-1090751Y652110D02*
G03I-709J0D01*
G01Y656440D02*
G03I-709J0D01*
G01X-1102920Y661280D02*
G03X-1103904Y662247I-984J-17D01*
G01X-1090203Y646113D02*
G03Y647892I-1300J889D01*
G01X-1093274D02*
G03Y646113I1299J-890D01*
G01X-1090751Y646598D02*
G03I-709J0D01*
G01Y642267D02*
G03I-709J0D01*
G01X-1090203Y638790D02*
G03Y640570I-1300J890D01*
G01X-1093274D02*
G03Y638790I1299J-890D01*
G01X-1131064Y669826D02*
G03X-1130670Y669432I394J0D01*
G01X-1135435D02*
G03X-1135829Y669039I0J-394D01*
G01X-1133270D02*
G03X-1133663Y669432I-393J0D01*
G01X-1128348D02*
G03X-1128742Y669039I0J-394D01*
G01X-1126183D02*
G03X-1126577Y669432I-393J0D01*
G01X-1131419Y669826D02*
G03X-1130670Y669078I748J0D01*
G01X-1122227Y683802D02*
G03X-1123014Y683015I0J-787D01*
G01X-1120793Y683802D02*
G03X-1119809Y684770I0J984D01*
G01X-1118494Y704669D02*
G03X-1119478Y703702I0J-984D01*
G01X-1126511Y700240D02*
G03X-1126607Y699707I1440J-534D01*
G01X-1131453Y697977D02*
G03X-1131549Y698509I-1536J-2D01*
G01X-1130840Y699707D02*
G03X-1130935Y700240I-1535J1D01*
G01X-1125937Y698509D02*
G03X-1126032Y697977I1441J-532D01*
G01X-1115243Y662247D02*
G03X-1116227Y661280I0J-984D01*
G01X-1133271Y656440D02*
G03I-708J0D01*
G01Y652110D02*
G03I-708J0D01*
G01X-1126184Y647385D02*
G03I-709J0D01*
G01X-1125636Y646533D02*
G03Y648313I-1300J890D01*
G01X-1128707D02*
G03Y646533I1299J-890D01*
G01X-1126184Y641873D02*
G03I-709J0D01*
G01X-1125636Y639211D02*
G03Y640990I-1300J890D01*
G01X-1128707D02*
G03Y639211I1299J-889D01*
G01X-1133271Y646598D02*
G03I-708J0D01*
G01Y642267D02*
G03I-708J0D01*
G01X-1140685Y700240D02*
G03X-1140780Y699707I1441J-532D01*
G01X-1145626Y697977D02*
G03X-1145722Y698509I-1536J-2D01*
G01X-1145013Y699707D02*
G03X-1145108Y700240I-1536J1D01*
G01X-1140110Y698509D02*
G03X-1140205Y697977I1440J-532D01*
G01X-1145237Y669826D02*
G03X-1144844Y669432I394J0D01*
G01X-1149608D02*
G03X-1150002Y669039I0J-394D01*
G01X-1147443D02*
G03X-1147836Y669432I-393J0D01*
G01X-1142522D02*
G03X-1142915Y669039I0J-393D01*
G01X-1140356D02*
G03X-1140750Y669432I-393J0D01*
G01X-1145592Y669826D02*
G03X-1144844Y669078I748J0D01*
G01X-1147444Y656440D02*
G03I-709J0D01*
G01Y652110D02*
G03I-709J0D01*
G01X-1140357Y647385D02*
G03I-709J0D01*
G01X-1147444Y646598D02*
G03I-709J0D01*
G01X-1140357Y641873D02*
G03I-709J0D01*
G01X-1147444Y642267D02*
G03I-709J0D01*
G01X-1109314Y639688D02*
X-1110888Y638114D01*
G01X-1109314Y643114D02*
X-1114314Y638114D01*
G01X-1088597Y701902D02*
X-1088971Y701795D01*
G01X-1090224D02*
X-1089850Y701902D01*
G01X-1131116D02*
X-1131491Y701795D01*
G01X-1132744D02*
X-1132369Y701902D01*
G01X-1145289D02*
X-1145664Y701795D01*
G01X-1146917D02*
X-1146543Y701902D01*
G01X-1088073Y698784D02*
X-1088438Y698650D01*
G01X-1088648D02*
X-1089012Y698515D01*
G01X-1088034Y700381D02*
X-1088398Y700246D01*
G01X-1130593Y698784D02*
X-1130957Y698650D01*
G01X-1131167D02*
X-1131532Y698515D01*
G01X-1130554Y700381D02*
X-1130918Y700246D01*
G01X-1144766Y698784D02*
X-1145131Y698650D01*
G01X-1145341D02*
X-1145705Y698515D01*
G01X-1144727Y700381D02*
X-1145091Y700246D01*
G01X-1110330Y704275D02*
X-1110066Y704386D01*
G01X-1105413Y704424D02*
X-1105714Y704275D01*
G01X-1109275Y672070D02*
X-1109376Y671998D01*
G01X-1115149Y638114D02*
X-1109314Y643949D01*
G01X-1100967Y678783D02*
X-1101122Y678628D01*
G01X-1102106Y679612D02*
X-1101951Y679767D01*
G01X-1081808Y702110D02*
X-1083153Y700764D01*
G01X-1117545Y668111D02*
X-1117700Y667956D01*
G01X-1118684Y668940D02*
X-1118529Y669095D01*
G01X-1088894Y702110D02*
X-1090239Y700764D01*
G01X-1104633Y696243D02*
X-1103845Y697031D01*
G01X-1103297Y704275D02*
X-1102903Y704669D01*
G01X-1103117D02*
X-1103314Y704472D01*
G01X-1103302Y704275D02*
X-1102914Y704669D01*
G01X-1083077Y650530D02*
X-1081699Y652917D01*
G01X-1090164Y650530D02*
X-1088786Y652917D01*
G01X-1097192Y650632D02*
X-1095873Y652917D01*
G01X-1104337Y650530D02*
X-1102959Y652917D01*
G01X-1124918Y702110D02*
X-1126263Y700764D01*
G01X-1131414Y702110D02*
X-1132759Y700764D01*
G01X-1138501Y702110D02*
X-1139846Y700764D01*
G01X-1145587Y702110D02*
X-1146932Y700764D01*
G01X-1105739Y704275D02*
X-1105370Y704669D01*
G01X-1103332Y704275D02*
X-1102974Y704669D01*
G01X-1104399Y704275D02*
X-1104078Y704669D01*
G01X-1105879Y704275D02*
X-1105651Y704669D01*
G01X-1111424Y650530D02*
X-1110046Y652917D01*
G01X-1118451Y650632D02*
X-1117133Y652917D01*
G01X-1125597Y650530D02*
X-1124208Y652936D01*
G01X-1132684Y650530D02*
X-1131306Y652917D01*
G01X-1139770Y650530D02*
X-1138392Y652917D01*
G01X-1146857Y650530D02*
X-1145479Y652917D01*
G01X-1082222Y701795D02*
X-1083434Y698515D01*
G01X-1083798Y698650D02*
X-1082596Y701902D01*
G01X-1082806D02*
X-1084009Y698650D01*
G01X-1084373Y698785D02*
X-1083260Y701795D01*
G01X-1084008Y700246D02*
X-1083448Y701763D01*
G01X-1083810Y701902D02*
X-1084373Y700381D01*
G01X-1110392Y704275D02*
X-1110228Y704669D01*
G01X-1124742Y701795D02*
X-1125954Y698515D01*
G01X-1126318Y698650D02*
X-1125116Y701902D01*
G01X-1125326D02*
X-1126528Y698650D01*
G01X-1126893Y698785D02*
X-1125780Y701795D01*
G01X-1126528Y700246D02*
X-1125967Y701763D01*
G01X-1126330Y701902D02*
X-1126892Y700381D01*
G01X-1138915Y701795D02*
X-1140127Y698515D01*
G01X-1140491Y698650D02*
X-1139289Y701902D01*
G01X-1139499D02*
X-1140701Y698650D01*
G01X-1141066Y698785D02*
X-1139953Y701795D01*
G01X-1140701Y700246D02*
X-1140140Y701763D01*
G01X-1140503Y701902D02*
X-1141066Y700381D01*
G01X-1104582Y704275D02*
X-1104444Y704669D01*
G01X-1113470Y672595D02*
X-1113513Y672428D01*
G01X-1104888Y666086D02*
X-1103510Y671944D01*
G01X-1103318Y704450D02*
X-1103333Y704385D01*
G01X-1113433Y672779D02*
X-1113471Y672593D01*
G01X-1103359Y672779D02*
X-1103422Y672433D01*
G01X-1103394Y672593D02*
X-1103510Y671942D01*
G01X-1087929Y675616D02*
X-1088110Y674587D01*
G01X-1088498Y674865D02*
X-1088316Y675895D01*
G01X-1108483Y704537D02*
X-1108461Y704669D01*
G01X-1108527Y704275D02*
X-1108461Y704669D01*
G01X-1087459Y669629D02*
X-1087384Y670364D01*
G01X-1087772Y670561D02*
X-1087847Y669826D01*
G01X-1090388Y664124D02*
X-1090395Y663527D01*
G01X-1084634Y699741D02*
X-1084635Y699707D01*
G01X-1085022D02*
Y699747D01*
G01X-1083533Y674309D02*
X-1083531Y674610D01*
G01X-1083657Y669013D02*
Y669432D01*
G01X-1080627Y664117D02*
Y699157D01*
G01X-1080725Y694236D02*
Y702110D01*
G01X-1080813Y699157D02*
Y664251D01*
G01X-1080823D02*
Y663527D01*
G01X-1081085Y702110D02*
Y694236D01*
G01X-1082222Y701795D02*
Y702110D01*
G01X-1083151Y663527D02*
Y674412D01*
G01X-1083260Y701795D02*
Y702110D01*
G01X-1083348Y664117D02*
Y673993D01*
G01X-1083448Y702110D02*
Y694236D01*
G01X-1083531Y674610D02*
Y697977D01*
G01X-1083533Y669432D02*
Y674309D01*
G01X-1083663Y669039D02*
Y665102D01*
G01X-1083915Y674409D02*
X-1083914Y669406D01*
G01X-1083918Y674610D02*
Y697977D01*
G01X-1084105Y699707D02*
Y669432D01*
G01X-1084130Y675895D02*
Y697977D01*
G01X-1084295Y669432D02*
Y674309D01*
G01X-1084493Y699707D02*
Y669432D01*
G01X-1084518Y675616D02*
Y697977D01*
G01X-1084635Y699707D02*
Y669432D01*
G01X-1085022D02*
Y699707D01*
G01X-1086222Y670561D02*
Y665102D01*
G01X-1086537Y673993D02*
Y664117D01*
G01X-1086734Y674412D02*
Y663527D01*
G01X-1087384Y670364D02*
Y699707D01*
G01X-1087459Y669629D02*
Y669432D01*
G01X-1087502D02*
Y669039D01*
G01X-1087772Y699707D02*
Y670561D01*
G01X-1087914Y669826D02*
Y699707D01*
G01X-1087929Y675616D02*
Y697977D01*
G01X-1088151Y669064D02*
Y674309D01*
G01X-1088302Y669826D02*
Y699707D01*
G01X-1088316Y675895D02*
Y697977D01*
G01X-1088528D02*
Y674610D01*
G01X-1088913Y674309D02*
Y669826D01*
G01X-1088916Y697977D02*
Y674610D01*
G01X-1088971Y701795D02*
Y702110D01*
G01X-1089186Y701795D02*
Y702110D01*
G01X-1087772Y699741D02*
Y699707D01*
G01X-1087385Y699747D02*
X-1087384Y699707D01*
G01X-1084130Y675895D02*
X-1083948Y674865D01*
G01X-1084336Y674587D02*
X-1084518Y675616D01*
G01X-1130448D02*
X-1130630Y674587D01*
G01X-1131018Y674865D02*
X-1130836Y675895D01*
G01X-1144622Y675616D02*
X-1144803Y674587D01*
G01X-1145191Y674865D02*
X-1145009Y675895D01*
G01X-1129979Y669629D02*
X-1129904Y670364D01*
G01X-1130292Y670561D02*
X-1130367Y669826D01*
G01X-1144152Y669629D02*
X-1144077Y670364D01*
G01X-1144465Y670561D02*
X-1144540Y669826D01*
G01X-1118494Y703702D02*
X-1118824Y684770D01*
G01X-1119478Y703702D02*
X-1119809Y684770D01*
G01X-1125821Y664124D02*
X-1125829Y663527D01*
G01X-1127154Y699741D02*
Y699707D01*
G01X-1127542D02*
Y699747D01*
G01X-1126052Y674309D02*
X-1126050Y674610D01*
G01X-1126177Y669013D02*
X-1126176Y669432D01*
G01X-1125817Y673330D02*
X-1125821Y664124D01*
G01X-1090384Y675174D02*
X-1090387Y664124D01*
G01X-1090164Y647832D02*
Y650530D01*
G01Y640509D02*
Y646173D01*
G01X-1090203Y646113D02*
Y640570D01*
G01Y653921D02*
Y647892D01*
G01X-1090224Y702110D02*
Y701795D01*
G01X-1090238Y664203D02*
Y663527D01*
G01X-1090371Y702110D02*
Y694236D01*
G01X-1090435Y664117D02*
Y675174D01*
G01X-1090750Y669039D02*
Y665102D01*
G01X-1090848Y669275D02*
Y665338D01*
G01X-1093210Y669275D02*
Y665338D01*
G01X-1093274Y647892D02*
Y653921D01*
G01Y640570D02*
Y646113D01*
G01X-1093309Y669039D02*
Y665102D01*
G01X-1093314Y646173D02*
Y640509D01*
G01Y650530D02*
Y647832D01*
G01X-1093624Y675174D02*
Y664117D01*
G01X-1093821Y664203D02*
Y663527D01*
G01X-1095784Y702110D02*
Y663527D01*
G01X-1097424Y663232D02*
Y683802D01*
G01X-1100197Y684770D02*
Y683802D01*
G01X-1100223Y697031D02*
Y704621D01*
G01X-1100527Y703702D02*
Y704669D01*
G01X-1100967Y668940D02*
Y678783D01*
G01X-1101122Y669095D02*
Y678628D01*
G01X-1101768Y704275D02*
Y704669D01*
G01X-1101809Y704275D02*
Y704669D01*
G01X-1101891D02*
Y704275D01*
G01X-1101932Y704669D02*
Y704275D01*
G01X-1102014Y704669D02*
Y704275D01*
G01X-1102055Y704669D02*
Y704275D01*
G01X-1102106Y668111D02*
Y679612D01*
G01X-1102137Y704669D02*
Y704275D01*
G01X-1102178Y704669D02*
Y704275D01*
G01X-1102219Y704669D02*
Y704275D01*
G01X-1102260Y704669D02*
Y704275D01*
G01X-1102323Y704669D02*
Y780694D01*
G01X-1102383Y704669D02*
Y704275D01*
G01X-1102424Y704669D02*
Y704275D01*
G01X-1103162Y704669D02*
Y704275D01*
G01X-1103297D02*
Y658015D01*
G01X-1103302D02*
Y704275D01*
G01X-1103314Y704472D02*
Y704669D01*
G01X-1103332Y704275D02*
Y658015D01*
G01X-1103359Y704275D02*
Y672779D01*
G01X-1103408Y704669D02*
Y704275D01*
G01X-1103510Y658015D02*
Y671944D01*
G01X-1103904Y662247D02*
Y661280D01*
G01X-1104399Y704275D02*
Y658015D01*
G01X-1104582Y704275D02*
Y658015D01*
G01X-1104633Y662247D02*
Y696243D01*
G01X-1104645Y672779D02*
Y704275D01*
G01X-1105714Y704669D02*
Y672779D01*
G01X-1105739Y704275D02*
Y658015D01*
G01X-1105879Y704275D02*
Y658015D01*
G01X-1108527Y704275D02*
X-1108526Y658015D01*
G01X-1108755Y704275D02*
Y658015D01*
G01X-1108817Y672779D02*
Y704275D01*
G01X-1108854D02*
Y704669D01*
G01X-1109018Y704275D02*
Y704669D01*
G01X-1109100Y704275D02*
Y704669D01*
G01X-1109182D02*
Y704275D01*
G01X-1109264D02*
Y704669D01*
G01X-1109305D02*
Y704275D01*
G01X-1109314Y639688D02*
Y643949D01*
G01X-1109510Y704275D02*
Y704669D01*
G01X-1109675Y704275D02*
Y704669D01*
G01X-1109839D02*
Y704275D01*
G01X-1110044Y704669D02*
Y704275D01*
G01X-1110085D02*
Y704669D01*
G01X-1110249D02*
Y704275D01*
G01X-1110330D02*
Y672779D01*
G01X-1110392Y704275D02*
Y658015D01*
G01X-1110495Y704669D02*
Y704275D01*
G01X-1110620Y658015D02*
Y704275D01*
G01X-1113268D02*
Y658015D01*
G01X-1113408Y704275D02*
Y658015D01*
G01X-1113433Y704669D02*
Y672779D01*
G01X-1114502Y704275D02*
Y672779D01*
G01X-1114514Y662247D02*
Y696243D01*
G01X-1114565Y704275D02*
Y658015D01*
G01X-1114748Y704275D02*
Y658015D01*
G01X-1115154Y704275D02*
Y704669D01*
G01X-1115243Y662247D02*
Y661280D01*
G01X-1115318Y704275D02*
Y704669D01*
G01X-1115400D02*
Y704275D01*
G01X-1115482Y704669D02*
Y704275D01*
G01X-1115636Y658015D02*
Y671944D01*
G01X-1115787Y704275D02*
Y672779D01*
G01X-1115815Y658015D02*
Y704275D01*
G01X-1115833Y704472D02*
Y704669D01*
G01X-1115845Y704275D02*
Y658015D01*
G01X-1115850Y704275D02*
Y658015D01*
G01X-1116548Y704669D02*
Y704275D01*
G01X-1116794D02*
Y704669D01*
G01X-1116823D02*
Y780694D01*
G01X-1117545Y668111D02*
Y679612D01*
G01X-1118494Y703702D02*
Y704669D01*
G01X-1118529Y678628D02*
Y669095D01*
G01X-1118684Y678783D02*
Y668940D01*
G01X-1118824Y684770D02*
Y683802D01*
G01X-1118924Y704570D02*
Y697031D01*
G01X-1122227Y663232D02*
Y683802D01*
G01X-1124524Y663527D02*
Y702110D01*
G01X-1124742Y701795D02*
Y702110D01*
G01X-1125597Y648253D02*
Y650530D01*
G01Y640930D02*
Y646594D01*
G01X-1125636Y646533D02*
Y640990D01*
G01Y653921D02*
Y648313D01*
G01X-1125671Y664203D02*
Y663527D01*
G01Y674412D02*
Y673520D01*
G01X-1125780Y701795D02*
Y702110D01*
G01X-1125868Y664117D02*
Y673993D01*
G01X-1125967Y702110D02*
Y694236D01*
G01X-1126050Y674610D02*
Y697977D01*
G01X-1126053Y669432D02*
Y674309D01*
G01X-1126183Y669039D02*
Y665102D01*
G01X-1126281Y669275D02*
Y665338D01*
G01X-1126434Y669406D02*
Y674409D01*
G01X-1126438Y697977D02*
Y674610D01*
G01X-1126624Y699707D02*
Y669432D01*
G01X-1126649Y697977D02*
Y675895D01*
G01X-1126815Y669432D02*
Y674309D01*
G01X-1127012Y699707D02*
Y669432D01*
G01X-1127037Y675616D02*
Y697977D01*
G01X-1127154Y699707D02*
Y669432D01*
G01X-1127542D02*
Y699707D01*
G01X-1128644Y669275D02*
Y665338D01*
G01X-1128707Y646533D02*
Y640990D01*
G01Y653921D02*
Y648313D01*
G01X-1128742Y670561D02*
Y665102D01*
G01X-1128747Y646594D02*
Y640930D01*
G01Y650530D02*
Y648253D01*
G01X-1129057Y673993D02*
Y664117D01*
G01X-1129254Y664203D02*
Y663527D01*
G01Y674412D02*
Y673520D01*
G01X-1129904Y670364D02*
Y699707D01*
G01X-1129979Y669629D02*
Y669432D01*
G01X-1130022D02*
Y669039D01*
G01X-1093675Y675174D02*
X-1093671Y664124D01*
G01X-1129108Y673330D02*
X-1129104Y664124D01*
G01X-1093664Y663527D02*
X-1093671Y664124D01*
G01X-1099543Y703702D02*
X-1099212Y684770D01*
G01X-1100527Y703702D02*
X-1100197Y684770D01*
G01X-1110664Y704537D02*
X-1110686Y704669D01*
G01X-1126649Y675895D02*
X-1126468Y674865D01*
G01X-1126856Y674587D02*
X-1127037Y675616D01*
G01X-1115637Y671942D02*
X-1115659Y672067D01*
G01X-1115647Y672003D02*
X-1115787Y672779D01*
G01X-1115829Y704450D02*
X-1115833Y704472D01*
G01X-1114259Y666086D02*
X-1115637Y671944D01*
G01X-1115787Y704275D02*
X-1115814Y704386D01*
G01X-1105676Y672593D02*
X-1105634Y672428D01*
G01X-1114565Y704275D02*
X-1114703Y704669D01*
G01X-1088034Y700381D02*
X-1088597Y701902D01*
G01X-1088971Y701795D02*
X-1088398Y700246D01*
G01X-1089186Y701795D02*
X-1088073Y698784D01*
G01X-1088438Y698650D02*
X-1089640Y701902D01*
G01X-1089850D02*
X-1088648Y698650D01*
G01X-1089012Y698515D02*
X-1090224Y701795D01*
G01X-1108755Y704275D02*
X-1108919Y704669D01*
G01X-1141327Y699741D02*
X-1141328Y699707D01*
G01X-1141715D02*
Y699747D01*
G01X-1140226Y674309D02*
X-1140224Y674610D01*
G01X-1140350Y669013D02*
Y669432D01*
G01X-1130292Y699707D02*
Y670561D01*
G01X-1130434Y669826D02*
Y699707D01*
G01X-1130448Y675616D02*
Y697977D01*
G01X-1130670Y669064D02*
Y674309D01*
G01X-1130822Y669826D02*
Y699707D01*
G01X-1130836Y675895D02*
Y697977D01*
G01X-1131048D02*
Y674610D01*
G01X-1131433Y674309D02*
Y669826D01*
G01X-1131435Y697977D02*
Y674610D01*
G01X-1131491Y702110D02*
Y701795D01*
G01X-1131706D02*
Y702110D01*
G01X-1132744D02*
Y701795D01*
G01X-1132758Y663527D02*
Y675174D01*
G01X-1132769D02*
X-1132768Y664251D01*
G01X-1132890Y702110D02*
Y694236D01*
G01X-1132955Y675174D02*
Y664117D01*
G01X-1133270Y669039D02*
Y665102D01*
G01X-1133579Y699157D02*
Y675174D01*
G01X-1135829Y669039D02*
Y665102D01*
G01X-1136144Y675174D02*
Y664117D01*
G01X-1136340Y675174D02*
Y663527D01*
G01X-1137320Y664117D02*
Y699157D01*
G01X-1137418Y694236D02*
Y702110D01*
G01X-1137506Y699157D02*
Y664251D01*
G01X-1137516D02*
Y663527D01*
G01X-1137778Y702110D02*
Y694236D01*
G01X-1138915Y701795D02*
Y702110D01*
G01X-1139844Y663527D02*
Y674412D01*
G01X-1139953Y701795D02*
Y702110D01*
G01X-1140041Y664117D02*
Y673993D01*
G01X-1140140Y702110D02*
Y694236D01*
G01X-1140223Y674610D02*
Y697977D01*
G01X-1140226Y669432D02*
Y674309D01*
G01X-1140356Y669039D02*
Y665102D01*
G01X-1140607Y674409D02*
Y669406D01*
G01X-1140611Y674610D02*
Y697977D01*
G01X-1140798Y699707D02*
Y669432D01*
G01X-1140823Y697977D02*
Y675895D01*
G01X-1140988Y669432D02*
Y674309D01*
G01X-1141185Y699707D02*
Y669432D01*
G01X-1141210Y675616D02*
Y697977D01*
G01X-1141328Y699707D02*
Y669432D01*
G01X-1141715D02*
Y699707D01*
G01X-1142915Y670561D02*
Y665102D01*
G01X-1143230Y673993D02*
Y664117D01*
G01X-1143427Y674412D02*
Y663527D01*
G01X-1144077Y670364D02*
Y699707D01*
G01X-1144152Y669629D02*
Y669432D01*
G01X-1144195D02*
Y669039D01*
G01X-1144465Y699707D02*
Y670561D01*
G01X-1144607Y669826D02*
Y699707D01*
G01X-1144622Y675616D02*
Y697977D01*
G01X-1144844Y669064D02*
Y674309D01*
G01X-1144995Y669826D02*
Y699707D01*
G01X-1145009Y675895D02*
Y697977D01*
G01X-1145221D02*
Y674610D01*
G01X-1145606Y674309D02*
Y669826D01*
G01X-1145609Y697977D02*
Y674610D01*
G01X-1145664Y702110D02*
Y701795D01*
G01X-1145879D02*
Y702110D01*
G01X-1146917D02*
Y701795D01*
G01X-1146931Y663527D02*
Y675174D01*
G01X-1146942D02*
X-1146941Y664251D01*
G01X-1147064Y702110D02*
Y694236D01*
G01X-1147128Y675174D02*
Y664117D01*
G01X-1147443Y669039D02*
Y665102D01*
G01X-1147753Y699157D02*
Y675174D01*
G01X-1150002Y669039D02*
Y665102D01*
G01X-1150317Y675174D02*
Y664117D01*
G01X-1150514Y675174D02*
Y663527D01*
G01X-1151493Y664117D02*
Y699157D01*
G01X-1151591Y694236D02*
Y702110D01*
G01X-1151679Y699157D02*
Y664251D01*
G01X-1151690D02*
Y663527D01*
G01X-1151951Y702110D02*
Y694236D01*
G01X-1130292Y699741D02*
Y699707D01*
G01X-1144465Y699741D02*
Y699707D01*
G01X-1129905Y699747D02*
X-1129904Y699707D01*
G01X-1144078Y699747D02*
X-1144077Y699707D01*
G01X-1129096Y663527D02*
X-1129104Y664124D01*
G01X-1140823Y675895D02*
X-1140641Y674865D01*
G01X-1141029Y674587D02*
X-1141210Y675616D01*
G01X-1130554Y700381D02*
X-1131116Y701902D01*
G01X-1131491Y701795D02*
X-1130918Y700246D01*
G01X-1131706Y701795D02*
X-1130593Y698784D01*
G01X-1130957Y698650D02*
X-1132159Y701902D01*
G01X-1132370D02*
X-1131167Y698650D01*
G01X-1131532Y698515D02*
X-1132744Y701795D01*
G01X-1144727Y700381D02*
X-1145289Y701902D01*
G01X-1145664Y701795D02*
X-1145091Y700246D01*
G01X-1145879Y701795D02*
X-1144766Y698784D01*
G01X-1145131Y698650D02*
X-1146333Y701902D01*
G01X-1146543D02*
X-1145341Y698650D01*
G01X-1145705Y698515D02*
X-1146917Y701795D01*
G01X-1114502Y672779D02*
X-1114416Y672593D01*
G01X-1114332Y672428D02*
X-1114417Y672595D01*
G01X-1080518Y652917D02*
X-1079140Y650530D01*
G01X-1087605Y652917D02*
X-1086227Y650530D01*
G01X-1094692Y652917D02*
X-1093314Y650530D01*
G01X-1101778Y652917D02*
X-1100459Y650632D01*
G01X-1114249Y672285D02*
X-1114334Y672433D01*
G01X-1113268Y704275D02*
X-1113496Y704669D01*
G01X-1113268Y704275D02*
X-1113496Y704669D01*
G01X-1079282Y700764D02*
X-1080627Y702110D01*
G01X-1086368Y700764D02*
X-1087713Y702110D01*
G01X-1108865Y652917D02*
X-1107487Y650530D01*
G01X-1115951Y652917D02*
X-1114573Y650530D01*
G01X-1123038Y652917D02*
X-1121719Y650632D01*
G01X-1130125Y652917D02*
X-1128747Y650530D01*
G01X-1137211Y652917D02*
X-1135833Y650530D01*
G01X-1144298Y652917D02*
X-1142920Y650530D01*
G01X-1151385Y652917D02*
X-1150007Y650530D01*
G01X-1114748Y704275D02*
X-1115069Y704669D01*
G01X-1115815Y704275D02*
X-1116173Y704669D01*
G01X-1113408Y704275D02*
X-1113777Y704669D01*
G01X-1116233D02*
X-1115845Y704275D01*
G01X-1093455Y700764D02*
X-1094800Y702110D01*
G01X-1116030Y704669D02*
X-1115833Y704472D01*
G01X-1115850Y704275D02*
X-1116244Y704669D01*
G01X-1114514Y696243D02*
X-1115302Y697031D01*
G01X-1130233Y702110D02*
X-1128888Y700764D01*
G01X-1101122Y669095D02*
X-1100967Y668940D01*
G01X-1101951Y667956D02*
X-1102106Y668111D01*
G01X-1137320Y702110D02*
X-1135974Y700764D01*
G01X-1117700Y679767D02*
X-1117545Y679612D01*
G01X-1118529Y678628D02*
X-1118684Y678783D01*
G01X-1143061Y700764D02*
X-1144406Y702110D01*
G01X-1104645Y704275D02*
X-1104896Y704424D01*
G01X-1150148Y700764D02*
X-1151493Y702110D01*
G01X-1109314Y643949D02*
X-1103478Y638114D01*
G01X-1109314Y643114D02*
X-1104314Y638114D01*
G01X-1107739D02*
X-1109314Y639688D01*
G01X-1113433Y704275D02*
X-1113734Y704424D01*
G01X-1108817Y704275D02*
X-1109082Y704386D01*
G01X-1084373Y700381D02*
X-1084008Y700246D01*
G01X-1083798Y698650D02*
X-1083434Y698515D01*
G01X-1084009Y698650D02*
X-1084373Y698784D01*
G01X-1126892Y700381D02*
X-1126528Y700246D01*
G01X-1125954Y698515D02*
X-1126318Y698650D01*
G01X-1126528D02*
X-1126893Y698784D01*
G01X-1141066Y700381D02*
X-1140701Y700246D01*
G01X-1140127Y698515D02*
X-1140491Y698650D01*
G01X-1140701D02*
X-1141066Y698784D01*
G01X-1082596Y701902D02*
X-1082222Y701795D01*
G01X-1083810Y701902D02*
X-1083448Y701798D01*
G01X-1124742Y701795D02*
X-1125116Y701902D01*
G01X-1126330D02*
X-1125967Y701798D01*
G01X-1139289Y701902D02*
X-1138915Y701795D01*
G01X-1140503Y701902D02*
X-1140140Y701798D01*
G01X-1109331Y704451D02*
X-1109078Y704385D01*
G01X-1114000Y704472D02*
X-1113734Y704424D01*
G01X-1099568Y703705D02*
X-1099543Y703702D01*
G01X-1109573Y704472D02*
X-1109327Y704450D01*
G01X-1085022Y699747D02*
X-1084634Y699741D01*
G01X-1127542Y699747D02*
X-1127154Y699741D01*
G01X-1141715Y699747D02*
X-1141327Y699741D01*
G01X-1118922Y703707D02*
X-1118494Y703702D01*
G01X-1100527Y704669D02*
X-1118494D01*
G01X-1108854Y704275D02*
X-1113433D01*
G01X-1114502D02*
X-1116794D01*
G01X-1105714D02*
X-1108817D01*
G01X-1101768D02*
X-1104645D01*
G01X-1100527Y703702D02*
X-1118494D01*
G01X-1095784Y702110D02*
X-1039485D01*
G01X-1145289Y701902D02*
X-1144933D01*
G01X-1084166D02*
X-1083810D01*
G01X-1088597D02*
X-1088240D01*
G01X-1126686D02*
X-1126330D01*
G01X-1131116D02*
X-1130760D01*
G01X-1140859D02*
X-1140503D01*
G01X-1146333D02*
X-1146543D01*
G01X-1139289D02*
X-1139499D01*
G01X-1132159D02*
X-1132370D01*
G01X-1125116D02*
X-1125326D01*
G01X-1089640D02*
X-1089850D01*
G01X-1082596D02*
X-1082806D01*
G01X-1095784Y701795D02*
X-1083260D01*
G01X-1125780D02*
X-1138915D01*
G01X-1124524D02*
X-1124742D01*
G01X-1069087D02*
X-1082222D01*
G01X-1147064Y701622D02*
X-1151591D01*
G01X-1137778D02*
X-1140140D01*
G01X-1132890D02*
X-1137418D01*
G01X-1124524D02*
X-1125967D01*
G01X-1090371D02*
X-1095784D01*
G01X-1081085D02*
X-1083448D01*
G01X-1076198D02*
X-1080725D01*
G01X-1146932Y700764D02*
X-1150148D01*
G01X-1139846D02*
X-1144662D01*
G01X-1132759D02*
X-1135974D01*
G01X-1126263D02*
X-1130489D01*
G01X-1090239D02*
X-1093455D01*
G01X-1083153D02*
X-1087969D01*
G01X-1084533Y700381D02*
X-1084373D01*
G01X-1127052D02*
X-1126892D01*
G01X-1141226D02*
X-1141066D01*
G01X-1144567D02*
X-1144727D01*
G01X-1130394D02*
X-1130554D01*
G01X-1087874D02*
X-1088034D01*
G01X-1088302Y699707D02*
X-1087384D01*
G01X-1085022D02*
X-1084105D01*
G01X-1127542D02*
X-1126624D01*
G01X-1130822D02*
X-1129904D01*
G01X-1141715D02*
X-1140798D01*
G01X-1144995D02*
X-1144077D01*
G01X-1147753Y699157D02*
X-1151678D01*
G01X-1133579D02*
X-1137505D01*
G01X-1076886D02*
X-1080812D01*
G01X-1145131Y698650D02*
X-1145341D01*
G01X-1083798D02*
X-1084009D01*
G01X-1140491D02*
X-1140701D01*
G01X-1130957D02*
X-1131167D01*
G01X-1126318D02*
X-1126528D01*
G01X-1088438D02*
X-1088648D01*
G01X-1084518Y697977D02*
X-1083531D01*
G01X-1088916D02*
X-1087929D01*
G01X-1131435D02*
X-1130448D01*
G01X-1141210D02*
X-1140223D01*
G01X-1145609D02*
X-1144622D01*
G01X-1126050D02*
X-1127037D01*
G01X-1144078Y699747D02*
X-1144465Y699741D01*
G01X-1129905Y699747D02*
X-1130292Y699741D01*
G01X-1087385Y699747D02*
X-1087772Y699741D01*
G01X-1109573Y704472D02*
X-1109821Y704450D01*
G01X-1139953Y701795D02*
X-1139576Y701883D01*
G01X-1125780Y701795D02*
X-1125403Y701883D01*
G01X-1139576D02*
X-1139499Y701902D01*
G01X-1125403Y701883D02*
X-1125326Y701902D01*
G01X-1110070Y704385D02*
X-1109817Y704450D01*
G01X-1115671Y661286D02*
X-1115243Y661280D01*
G01X-1099819Y684765D02*
X-1100197Y684770D01*
G01X-1099822Y684765D02*
X-1099499Y684763D01*
G01X-1103133Y661287D02*
X-1103292D01*
G01X-1119595Y697031D02*
X-1099426D01*
G01X-1104633Y696243D02*
X-1114514D01*
G01X-1124524Y694235D02*
X-1125967D01*
G01X-1147064Y694236D02*
X-1151591D01*
G01X-1137778D02*
X-1140140D01*
G01X-1132890D02*
X-1137418D01*
G01X-1090371D02*
X-1095784D01*
G01X-1081085D02*
X-1083448D01*
G01X-1076198D02*
X-1080725D01*
G01X-1100197Y684770D02*
X-1118824D01*
G01X-1097424Y683802D02*
X-1122227D01*
G01X-1123014Y683015D02*
X-1096636D01*
G01X-1101951Y679767D02*
X-1117700D01*
G01X-1102106Y679612D02*
X-1117545D01*
G01X-1118529Y678628D02*
X-1101122D01*
G01X-1088316Y675895D02*
X-1084130D01*
G01X-1130836D02*
X-1126649D01*
G01X-1145009D02*
X-1140823D01*
G01X-1141210Y675616D02*
X-1144622D01*
G01X-1127037D02*
X-1130448D01*
G01X-1084518D02*
X-1087929D01*
G01X-1093675Y675174D02*
X-1090384D01*
G01X-1146931D02*
X-1150514D01*
G01X-1132758D02*
X-1136340D01*
G01X-1124197D02*
X-1124524D01*
G01X-1095295D02*
X-1095784D01*
G01X-1083918Y674610D02*
X-1083531D01*
G01X-1140611D02*
X-1140223D01*
G01X-1145221D02*
X-1145609D01*
G01X-1131048D02*
X-1131435D01*
G01X-1126050D02*
X-1126438D01*
G01X-1088528D02*
X-1088916D01*
G01X-1088110Y674587D02*
X-1084336D01*
G01X-1130630D02*
X-1126856D01*
G01X-1144803D02*
X-1141029D01*
G01X-1139844Y674412D02*
X-1143427D01*
G01X-1125671D02*
X-1129254D01*
G01X-1083151D02*
X-1086734D01*
G01X-1088913Y674309D02*
X-1083533D01*
G01X-1145606D02*
X-1140226D01*
G01X-1126053D02*
X-1131433D01*
G01X-1140041Y673993D02*
X-1143230D01*
G01X-1125868D02*
X-1129057D01*
G01X-1083348D02*
X-1086537D01*
G01X-1129254Y673743D02*
X-1125671D01*
G01X-1129108Y673330D02*
X-1125817D01*
G01X-1114502Y672779D02*
X-1115787D01*
G01X-1110330D02*
X-1113433D01*
G01X-1105714D02*
X-1108817D01*
G01X-1103359D02*
X-1104645D01*
G01X-1087772Y670561D02*
X-1086222D01*
G01X-1130292D02*
X-1128742D01*
G01X-1144465D02*
X-1142915D01*
G01X-1087384Y670364D02*
X-1086222D01*
G01X-1129904D02*
X-1128742D01*
G01X-1144077D02*
X-1142915D01*
G01X-1088913Y669826D02*
X-1086222D01*
G01X-1142915D02*
X-1145606D01*
G01X-1128742D02*
X-1131433D01*
G01X-1087459Y669629D02*
X-1086222D01*
G01X-1129979D02*
X-1128742D01*
G01X-1144152D02*
X-1142915D01*
G01X-1088151Y669445D02*
X-1086222D01*
G01X-1130670D02*
X-1128742D01*
G01X-1144844D02*
X-1142915D01*
G01X-1128348Y669432D02*
X-1126577D01*
G01X-1147836D02*
X-1149608D01*
G01X-1140750D02*
X-1142522D01*
G01X-1142915D02*
X-1144195D01*
G01X-1140226D02*
X-1140356D01*
G01X-1133663D02*
X-1135435D01*
G01X-1128742D02*
X-1130022D01*
G01X-1126053D02*
X-1126183D01*
G01X-1091144D02*
X-1092915D01*
G01X-1084057D02*
X-1085829D01*
G01X-1086222D02*
X-1087502D01*
G01X-1083533D02*
X-1083663D01*
G01X-1126281Y669275D02*
X-1128644D01*
G01X-1090848D02*
X-1093210D01*
G01X-1101122Y669095D02*
X-1118529D01*
G01X-1088151Y669064D02*
X-1086222D01*
G01X-1130670D02*
X-1128742D01*
G01X-1144844D02*
X-1142915D01*
G01Y669039D02*
X-1144195D01*
G01X-1128742D02*
X-1130022D01*
G01X-1086222D02*
X-1087502D01*
G01X-1128644Y668417D02*
X-1126281D01*
G01X-1102106Y668111D02*
X-1117545D01*
G01X-1117700Y667956D02*
X-1101951D01*
G01X-1126183Y666936D02*
X-1124524D01*
G01X-1142915D02*
X-1147443D01*
G01X-1135829D02*
X-1140356D01*
G01X-1128742D02*
X-1133270D01*
G01X-1093309D02*
X-1095784D01*
G01X-1086222D02*
X-1090750D01*
G01X-1079136D02*
X-1083663D01*
G01X-1126281Y666913D02*
X-1128644D01*
G01X-1090848D02*
X-1093210D01*
G01X-1090750Y666739D02*
X-1086222D01*
G01X-1095784D02*
X-1093309D01*
G01X-1126183D02*
X-1124524D01*
G01X-1133270D02*
X-1128742D01*
G01X-1140356D02*
X-1135829D01*
G01X-1147443D02*
X-1142915D01*
G01X-1079136D02*
X-1083663D01*
G01X-1114259Y666086D02*
X-1104888D01*
G01X-1126281Y665338D02*
X-1128644D01*
G01X-1090848D02*
X-1093210D01*
G01X-1147443Y665102D02*
X-1150002D01*
G01X-1140356D02*
X-1142915D01*
G01X-1133270D02*
X-1135829D01*
G01X-1126183D02*
X-1128742D01*
G01X-1090750D02*
X-1093309D01*
G01X-1083663D02*
X-1086222D01*
G01X-1039485Y664117D02*
X-1095784D01*
G01X-1129254Y663606D02*
X-1125671D01*
G01X-1139844D02*
X-1143427D01*
G01X-1083151D02*
X-1086734D01*
G01X-1039157Y663527D02*
X-1095784D01*
G01X-1096636Y663232D02*
X-1123014D01*
G01X-1039157Y662739D02*
X-1095295D01*
G01X-1123014Y662444D02*
X-1096636D01*
G01X-1103904Y662247D02*
X-1115243D01*
G01X-1103904Y661280D02*
X-1115243D01*
G01X-1103297Y658015D02*
X-1115850D01*
G01X-1119522Y684763D02*
X-1119199Y684765D01*
G01X-1103290Y661287D02*
X-1103478Y661286D01*
G01X-1099502Y684763D02*
X-1099288Y684765D01*
G01X-1116131Y661286D02*
X-1116014Y661287D01*
G01X-1103476Y661286D02*
X-1103904Y661280D01*
G01X-1119202Y684765D02*
X-1118824Y684770D01*
G01X-1116203Y661284D02*
X-1116131Y661286D01*
G01X-1099212Y684770D02*
X-1099286Y684765D01*
G01X-1116227Y661280D02*
X-1116203Y661284D01*
G01X-1120492Y683849D02*
X-1120793Y683802D01*
G01X-1083260Y701795D02*
X-1082883Y701883D01*
G01D02*
X-1082806Y701902D01*
G01X-1121719Y654098D02*
X-1123014D01*
G01X-1114534D02*
X-1118451D01*
G01X-1107448D02*
X-1111463D01*
G01X-1100459D02*
X-1104377D01*
G01X-1096636D02*
X-1097192D01*
G01X-1090203Y653921D02*
X-1043668D01*
G01X-1124197D02*
X-1125636D01*
G01X-1093274D02*
X-1095295D01*
G01X-1095873Y652917D02*
X-1094692D01*
G01X-1124219D02*
X-1123038D01*
G01X-1145479D02*
X-1144298D01*
G01X-1137211D02*
X-1138392D01*
G01X-1130125D02*
X-1131306D01*
G01X-1115951D02*
X-1117133D01*
G01X-1108865D02*
X-1110046D01*
G01X-1101778D02*
X-1102959D01*
G01X-1087605D02*
X-1088786D01*
G01X-1080518D02*
X-1081699D01*
G01X-1146660Y650871D02*
X-1143117D01*
G01X-1107739Y638114D02*
X-1103478D01*
G01X-1115149D02*
X-1110888D01*
G01X-1111278Y790299D02*
X-1116823Y780694D01*
G01X-1107869Y790299D02*
X-1102323Y780694D01*
G01X-1116823D02*
X-1102323D01*
G01X-1107869Y790299D02*
G03X-1111278I-1705J-985D01*
G01D02*
X-1107869D01*
G01X-1018653Y-714465D02*
Y-733402D01*
G01X-1038070Y-714465D02*
X143525D01*
G01X-1050800Y-455666D02*
X-943976D01*
G01X-1053949D02*
X-1050800D01*
G01X-1062680Y-378259D02*
X-955855D01*
G01X-1065829D02*
X-1062680D01*
G01X-1035859Y-340359D02*
G03X-1031922I1968J0D01*
G01Y60286D02*
Y-340359D01*
G01X-1005347Y-222249D02*
G03I-6890J0D01*
G01X-993536D02*
G03I-18701J0D01*
G01X-1002591Y-56894D02*
G03I-6890J0D01*
G01X-990780D02*
G03I-18701J0D01*
G01X-1031506Y62047D02*
G03X-1031922Y60286I3521J-1761D01*
G01X-1013325Y98409D02*
X-1031507Y62047D01*
G01X-1009804Y100586D02*
G03X-1013325Y98410I0J-3937D01*
G01X-1009804Y100586D02*
X-757513D01*
G01X-1021000Y557620D02*
X-1019032Y558290D01*
G01X-1029531Y555609D02*
X-1031499Y554939D01*
G01Y557620D02*
X-1029531Y558290D01*
G01X-1019688Y555609D02*
X-1021000Y554939D01*
G01D02*
X-1021657Y554269D01*
G01X-1022969Y555609D02*
X-1021000Y557620D01*
G01X-1031499Y554939D02*
X-1032811Y553599D01*
G01Y556280D02*
X-1031499Y557620D01*
G01X-1062995Y550248D02*
X-1051840Y562981D01*
G01X-1067588Y550248D02*
X-1051840Y568342D01*
G01X-1072838Y548238D02*
X-1074150Y546228D01*
G01X-1021657Y554269D02*
X-1022313Y552929D01*
G01X-1011814D02*
Y536846D01*
G01X-1015095D02*
Y552929D01*
G01X-1022313D02*
Y536846D01*
G01X-1025594D02*
Y552929D01*
G01X-1032811Y553599D02*
Y536846D01*
G01Y558290D02*
Y556280D01*
G01X-1036092Y536846D02*
Y558290D01*
G01X-1041342Y550248D02*
Y546228D01*
G01X-1047903D02*
Y536846D01*
G01Y568342D02*
Y550248D01*
G01X-1051840Y536846D02*
Y546228D01*
G01Y562981D02*
Y550248D01*
G01X-1067588Y546228D02*
Y550248D01*
G01X-1013126Y556280D02*
X-1011814Y552929D01*
G01X-1015095D02*
X-1015751Y554269D01*
G01X-1025594Y552929D02*
X-1026250Y554269D01*
G01X-1074150Y559630D02*
X-1072838Y557620D01*
G01X-1014439D02*
X-1013126Y556280D01*
G01X-1015751Y554269D02*
X-1016407Y554939D01*
G01X-1024937Y557620D02*
X-1022969Y555609D01*
G01X-1026250Y554269D02*
X-1026906Y554939D01*
G01X-1016407D02*
X-1017720Y555609D01*
G01X-1026906Y554939D02*
X-1028218Y555609D01*
G01X-1016407Y558290D02*
X-1014439Y557620D01*
G01X-1026906Y558290D02*
X-1024937Y557620D01*
G01X-1019032Y558290D02*
X-1016407D01*
G01X-1029531D02*
X-1026906D01*
G01X-1036092D02*
X-1032811D01*
G01X-1028218Y555609D02*
X-1029531D01*
G01X-1017720D02*
X-1019688D01*
G01X-1047903Y550248D02*
X-1041342D01*
G01X-1051840D02*
X-1062995D01*
G01X-1051840Y546228D02*
X-1067588D01*
G01X-1041342D02*
X-1047903D01*
G01Y536846D02*
X-1051840D01*
G01X-1032811D02*
X-1036092D01*
G01X-1022313D02*
X-1025594D01*
G01X-1011814D02*
X-1015095D01*
G01X-1076030Y594755D02*
X-1076001Y594391D01*
G01X-1076113Y595105D02*
X-1076030Y594755D01*
G01X-1076246Y595426D02*
X-1076113Y595105D01*
G01X-1076419Y595704D02*
X-1076246Y595426D01*
G01X-1076620Y595932D02*
X-1076419Y595704D01*
G01X-1076838Y596106D02*
X-1076620Y595932D01*
G01X-1068943Y594755D02*
X-1068914Y594391D01*
G01X-1069027Y595105D02*
X-1068943Y594755D01*
G01X-1069159Y595426D02*
X-1069027Y595105D01*
G01X-1069332Y595704D02*
X-1069159Y595426D01*
G01X-1069533Y595932D02*
X-1069332Y595704D01*
G01X-1069752Y596106D02*
X-1069533Y595932D01*
G01X-1061856Y594755D02*
X-1061827Y594391D01*
G01X-1061940Y595105D02*
X-1061856Y594755D01*
G01X-1062072Y595426D02*
X-1061940Y595105D01*
G01X-1062245Y595704D02*
X-1062072Y595426D01*
G01X-1062447Y595932D02*
X-1062245Y595704D01*
G01X-1062665Y596106D02*
X-1062447Y595932D01*
G01X-1054770Y594755D02*
X-1054741Y594391D01*
G01X-1054853Y595105D02*
X-1054770Y594755D01*
G01X-1054986Y595426D02*
X-1054853Y595105D01*
G01X-1055159Y595704D02*
X-1054986Y595426D01*
G01X-1055360Y595932D02*
X-1055159Y595704D01*
G01X-1055578Y596106D02*
X-1055360Y595932D01*
G01X-1047683Y594755D02*
X-1047654Y594391D01*
G01X-1047767Y595105D02*
X-1047683Y594755D01*
G01X-1047899Y595426D02*
X-1047767Y595105D01*
G01X-1048072Y595704D02*
X-1047899Y595426D01*
G01X-1048273Y595932D02*
X-1048072Y595704D01*
G01X-1048492Y596106D02*
X-1048273Y595932D01*
G01X-1040597Y594755D02*
X-1040568Y594391D01*
G01X-1040680Y595105D02*
X-1040597Y594755D01*
G01X-1040813Y595426D02*
X-1040680Y595105D01*
G01X-1040985Y595704D02*
X-1040813Y595426D01*
G01X-1041187Y595932D02*
X-1040985Y595704D01*
G01X-1041405Y596106D02*
X-1041187Y595932D01*
G01X-1076472Y595884D02*
X-1076838Y596106D01*
G01X-1076210Y595603D02*
X-1076472Y595884D01*
G01X-1076053Y595290D02*
X-1076210Y595603D01*
G01X-1076001Y594962D02*
X-1076053Y595290D01*
G01X-1069386Y595884D02*
X-1069752Y596106D01*
G01X-1069123Y595603D02*
X-1069386Y595884D01*
G01X-1068967Y595290D02*
X-1069123Y595603D01*
G01X-1068914Y594962D02*
X-1068967Y595290D01*
G01X-1062299Y595884D02*
X-1062665Y596106D01*
G01X-1062037Y595603D02*
X-1062299Y595884D01*
G01X-1061880Y595290D02*
X-1062037Y595603D01*
G01X-1061827Y594962D02*
X-1061880Y595290D01*
G01X-1055213Y595884D02*
X-1055578Y596106D01*
G01X-1054950Y595603D02*
X-1055213Y595884D01*
G01X-1054794Y595290D02*
X-1054950Y595603D01*
G01X-1054741Y594962D02*
X-1054794Y595290D01*
G01X-1078511Y595932D02*
X-1078293Y596106D01*
G01X-1078713Y595704D02*
X-1078511Y595932D01*
G01X-1078886Y595426D02*
X-1078713Y595704D01*
G01X-1079018Y595105D02*
X-1078886Y595426D01*
G01X-1079102Y594755D02*
X-1079018Y595105D01*
G01X-1079131Y594391D02*
X-1079102Y594755D01*
G01X-1071425Y595932D02*
X-1071206Y596106D01*
G01X-1071626Y595704D02*
X-1071425Y595932D01*
G01X-1071799Y595426D02*
X-1071626Y595704D01*
G01X-1071931Y595105D02*
X-1071799Y595426D01*
G01X-1072015Y594755D02*
X-1071931Y595105D01*
G01X-1072044Y594391D02*
X-1072015Y594755D01*
G01X-1048126Y595884D02*
X-1048492Y596106D01*
G01X-1047864Y595603D02*
X-1048126Y595884D01*
G01X-1047707Y595290D02*
X-1047864Y595603D01*
G01X-1047654Y594962D02*
X-1047707Y595290D01*
G01X-1041039Y595884D02*
X-1041405Y596106D01*
G01X-1040777Y595603D02*
X-1041039Y595884D01*
G01X-1040620Y595290D02*
X-1040777Y595603D01*
G01X-1040568Y594962D02*
X-1040620Y595290D01*
G01X-1064338Y595932D02*
X-1064120Y596106D01*
G01X-1064539Y595704D02*
X-1064338Y595932D01*
G01X-1064712Y595426D02*
X-1064539Y595704D01*
G01X-1064845Y595105D02*
X-1064712Y595426D01*
G01X-1064928Y594755D02*
X-1064845Y595105D01*
G01X-1064957Y594391D02*
X-1064928Y594755D01*
G01X-1057251Y595932D02*
X-1057033Y596106D01*
G01X-1057453Y595704D02*
X-1057251Y595932D01*
G01X-1057626Y595426D02*
X-1057453Y595704D01*
G01X-1057758Y595105D02*
X-1057626Y595426D01*
G01X-1057842Y594755D02*
X-1057758Y595105D01*
G01X-1057871Y594391D02*
X-1057842Y594755D01*
G01X-1050165Y595932D02*
X-1049947Y596106D01*
G01X-1050366Y595704D02*
X-1050165Y595932D01*
G01X-1050539Y595426D02*
X-1050366Y595704D01*
G01X-1050672Y595105D02*
X-1050539Y595426D01*
G01X-1050755Y594755D02*
X-1050672Y595105D01*
G01X-1050784Y594391D02*
X-1050755Y594755D01*
G01X-1043078Y595932D02*
X-1042860Y596106D01*
G01X-1043280Y595704D02*
X-1043078Y595932D01*
G01X-1043452Y595426D02*
X-1043280Y595704D01*
G01X-1043585Y595105D02*
X-1043452Y595426D01*
G01X-1043669Y594755D02*
X-1043585Y595105D01*
G01X-1043698Y594391D02*
X-1043669Y594755D01*
G01X-1078755Y595798D02*
X-1078293Y596106D01*
G01X-1079036Y595398D02*
X-1078755Y595798D01*
G01X-1079131Y594962D02*
X-1079036Y595398D01*
G01X-1071668Y595798D02*
X-1071206Y596106D01*
G01X-1071950Y595398D02*
X-1071668Y595798D01*
G01X-1072044Y594962D02*
X-1071950Y595398D01*
G01X-1064582Y595798D02*
X-1064120Y596106D01*
G01X-1064863Y595398D02*
X-1064582Y595798D01*
G01X-1064957Y594962D02*
X-1064863Y595398D01*
G01X-1057495Y595798D02*
X-1057033Y596106D01*
G01X-1057777Y595398D02*
X-1057495Y595798D01*
G01X-1057871Y594962D02*
X-1057777Y595398D01*
G01X-1050409Y595798D02*
X-1049947Y596106D01*
G01X-1050690Y595398D02*
X-1050409Y595798D01*
G01X-1050784Y594962D02*
X-1050690Y595398D01*
G01X-1043322Y595798D02*
X-1042860Y596106D01*
G01X-1043603Y595398D02*
X-1043322Y595798D01*
G01X-1043698Y594962D02*
X-1043603Y595398D01*
G01X-1041145Y637543D02*
G03I-708J0D01*
G01Y633212D02*
G03I-708J0D01*
G01X-1043707Y634019D02*
G03X-1042153Y632444I1575J0D01*
G01X-1048231Y637936D02*
G03I-709J0D01*
G01Y632425D02*
G03I-709J0D01*
G01X-1050794Y634019D02*
G03X-1047644I1575J0D01*
G01X-1055318Y637543D02*
G03I-709J0D01*
G01X-1062405Y637936D02*
G03I-708J0D01*
G01Y632425D02*
G03I-708J0D01*
G01X-1055318Y633212D02*
G03I-709J0D01*
G01X-1057881Y634019D02*
G03X-1054731I1575J0D01*
G01X-1069491Y637543D02*
G03I-709J0D01*
G01Y633212D02*
G03I-709J0D01*
G01X-1064967Y634019D02*
G03X-1061818I1575J0D01*
G01X-1072054D02*
G03X-1068904I1575J0D01*
G01X-1076578Y637936D02*
G03I-708J0D01*
G01Y632425D02*
G03I-708J0D01*
G01X-1079140Y634019D02*
G03X-1075991I1574J0D01*
G01X-1055318Y627700D02*
G03I-709J0D01*
G01Y623369D02*
G03I-709J0D01*
G01X-1041145Y627700D02*
G03I-708J0D01*
G01X-1048231Y628094D02*
G03I-709J0D01*
G01X-1041145Y623369D02*
G03I-708J0D01*
G01X-1048231Y623763D02*
G03I-709J0D01*
G01X-1040755Y629511D02*
G03X-1039770Y630495I0J985D01*
G01X-1044495D02*
G03X-1043510Y629511I984J0D01*
G01X-1039136Y630870D02*
G03X-1040711Y632444I-1574J0D01*
G01X-1055318Y619039D02*
G03I-709J0D01*
G01Y613527D02*
G03I-709J0D01*
G01X-1041145Y619039D02*
G03I-708J0D01*
G01X-1048231Y618251D02*
G03I-709J0D01*
G01Y613921D02*
G03I-709J0D01*
G01X-1041145Y613527D02*
G03I-708J0D01*
G01X-1040164Y614334D02*
G03I-1969J0D01*
G01X-1047251D02*
G03I-1968J0D01*
G01X-1054337D02*
G03I-1969J0D01*
G01X-1069491Y627700D02*
G03I-709J0D01*
G01X-1076578Y628094D02*
G03I-708J0D01*
G01X-1069491Y623369D02*
G03I-709J0D01*
G01X-1076578Y623763D02*
G03I-708J0D01*
G01X-1062405Y628094D02*
G03I-708J0D01*
G01Y623763D02*
G03I-708J0D01*
G01X-1069491Y619039D02*
G03I-709J0D01*
G01X-1062405Y618251D02*
G03I-708J0D01*
G01X-1069491Y613527D02*
G03I-709J0D01*
G01X-1062405Y613921D02*
G03I-708J0D01*
G01X-1061424Y614334D02*
G03I-1968J0D01*
G01X-1068510D02*
G03I-1969J0D01*
G01X-1076578Y618251D02*
G03I-708J0D01*
G01Y613921D02*
G03I-708J0D01*
G01X-1075597Y614334D02*
G03I-1969J0D01*
G01X-1055318Y609196D02*
G03I-709J0D01*
G01X-1062405Y609590D02*
G03I-708J0D01*
G01X-1055318Y604865D02*
G03I-709J0D01*
G01X-1062405Y604078D02*
G03I-708J0D01*
G01X-1041145Y609196D02*
G03I-708J0D01*
G01X-1048231Y609590D02*
G03I-709J0D01*
G01X-1041145Y604865D02*
G03I-708J0D01*
G01X-1048231Y604078D02*
G03I-709J0D01*
G01X-1062405Y599747D02*
G03I-708J0D01*
G01X-1055318Y599354D02*
G03I-709J0D01*
G01Y595023D02*
G03I-709J0D01*
G01X-1048231Y599747D02*
G03I-709J0D01*
G01X-1041145Y599354D02*
G03I-708J0D01*
G01Y595023D02*
G03I-708J0D01*
G01X-1055574Y596114D02*
G03X-1057038I-732J-1394D01*
G01X-1048487D02*
G03X-1049951I-732J-1394D01*
G01X-1041401D02*
G03X-1042865I-732J-1394D01*
G01X-1069491Y609196D02*
G03I-709J0D01*
G01X-1076578Y609590D02*
G03I-708J0D01*
G01X-1069491Y604865D02*
G03I-709J0D01*
G01X-1076578Y604078D02*
G03I-708J0D01*
G01Y599747D02*
G03I-708J0D01*
G01X-1069491Y599354D02*
G03I-709J0D01*
G01Y595023D02*
G03I-709J0D01*
G01X-1076834Y596114D02*
G03X-1078298I-732J-1394D01*
G01X-1069747D02*
G03X-1071211I-732J-1394D01*
G01X-1062660D02*
G03X-1064124I-732J-1394D01*
G01X-1040597Y588625D02*
X-1041778Y587444D01*
G01X-1040597Y636976D02*
X-1041385Y635612D01*
G01X-1039136Y586460D02*
Y663527D01*
G01X-1039157Y589806D02*
Y586460D01*
G01Y593862D02*
Y591381D01*
G01X-1039770Y653921D02*
Y630495D01*
G01X-1040568Y594962D02*
Y589019D01*
G01X-1040597Y591381D02*
Y588625D01*
G01Y639211D02*
Y636976D01*
G01X-1043668Y591381D02*
Y588625D01*
G01Y639211D02*
Y636976D01*
G01X-1043698Y594962D02*
Y589019D01*
G01X-1043707Y639271D02*
Y634019D01*
G01X-1044495Y653921D02*
Y630495D01*
G01X-1047644Y634019D02*
Y650530D01*
G01X-1047654Y594962D02*
Y589019D01*
G01X-1050784Y594962D02*
Y589019D01*
G01X-1050794Y650530D02*
Y634019D01*
G01X-1054731D02*
Y650530D01*
G01X-1054741Y594962D02*
Y589019D01*
G01X-1057871Y594962D02*
Y589019D01*
G01X-1057881Y650530D02*
Y634019D01*
G01X-1061818D02*
Y650530D01*
G01X-1061827Y594962D02*
Y589019D01*
G01X-1064957Y594962D02*
Y589019D01*
G01X-1064967Y650530D02*
Y634019D01*
G01X-1068904D02*
Y650530D01*
G01X-1068914Y594962D02*
Y589019D01*
G01X-1072044Y594962D02*
Y589019D01*
G01X-1072054Y650530D02*
Y634019D01*
G01X-1075991D02*
Y650530D01*
G01X-1076001Y594962D02*
Y589019D01*
G01X-1079131Y594962D02*
Y589019D01*
G01X-1079140Y650530D02*
Y634019D01*
G01X-1043668Y636976D02*
X-1042881Y635612D01*
G01X-1043668Y588625D02*
X-1042487Y587444D01*
G01X-1041385Y635612D02*
X-1042881D01*
G01X-1042153Y632444D02*
X-1040711D01*
G01X-1039770Y632034D02*
X-1044495D01*
G01X-1040755Y629511D02*
X-1043510D01*
G01X-1071206Y596106D02*
X-1076838D01*
G01X-1064120D02*
X-1069752D01*
G01X-1057033D02*
X-1062665D01*
G01X-1049947D02*
X-1055578D01*
G01X-1042860D02*
X-1048492D01*
G01X-1039136D02*
X-1041405D01*
G01X-1040597Y588625D02*
X-1043668D01*
G01X-1041778Y587444D02*
X-1042487D01*
G01X-1051840Y568342D02*
X-1047903D01*
G01X-1040813Y664118D02*
X-1040829Y664117D01*
G01X-1040797Y664120D02*
X-1040813Y664118D01*
G01X-1040781Y664124D02*
X-1040797Y664120D01*
G01X-1041630Y675833D02*
X-1041610Y675895D01*
G01X-1041669Y675774D02*
X-1041630Y675833D01*
G01X-1041722Y675722D02*
X-1041669Y675774D01*
G01X-1041789Y675678D02*
X-1041722Y675722D01*
G01X-1041866Y675644D02*
X-1041789Y675678D01*
G01X-1041950Y675623D02*
X-1041866Y675644D01*
G01X-1055803Y675833D02*
X-1055783Y675895D01*
G01X-1055842Y675774D02*
X-1055803Y675833D01*
G01X-1055896Y675722D02*
X-1055842Y675774D01*
G01X-1055963Y675678D02*
X-1055896Y675722D01*
G01X-1056040Y675644D02*
X-1055963Y675678D01*
G01X-1056123Y675623D02*
X-1056040Y675644D01*
G01X-1069977Y675833D02*
X-1069957Y675895D01*
G01X-1070015Y675774D02*
X-1069977Y675833D01*
G01X-1070069Y675722D02*
X-1070015Y675774D01*
G01X-1070136Y675678D02*
X-1070069Y675722D01*
G01X-1070213Y675644D02*
X-1070136Y675678D01*
G01X-1070296Y675623D02*
X-1070213Y675644D01*
G01X-1054820Y674116D02*
X-1054805Y674190D01*
G01X-1054862Y674051D02*
X-1054820Y674116D01*
G01X-1054925Y674009D02*
X-1054862Y674051D01*
G01X-1055002Y673993D02*
X-1054925Y674009D01*
G01X-1068993Y674116D02*
X-1068978Y674190D01*
G01X-1069035Y674051D02*
X-1068993Y674116D01*
G01X-1069098Y674009D02*
X-1069035Y674051D01*
G01X-1069175Y673993D02*
X-1069098Y674009D01*
G01X-1041447Y674807D02*
X-1041429Y674865D01*
G01X-1041481Y674753D02*
X-1041447Y674807D01*
G01X-1041530Y674702D02*
X-1041481Y674753D01*
G01X-1041590Y674659D02*
X-1041530Y674702D01*
G01X-1041660Y674624D02*
X-1041590Y674659D01*
G01X-1041736Y674600D02*
X-1041660Y674624D01*
G01X-1041816Y674587D02*
X-1041736Y674600D01*
G01X-1040049Y701961D02*
X-1040077Y701902D01*
G01X-1040011Y702011D02*
X-1040049Y701961D01*
G01X-1039962Y702053D02*
X-1040011Y702011D01*
G01X-1039907Y702084D02*
X-1039962Y702053D01*
G01X-1039848Y702103D02*
X-1039907Y702084D01*
G01X-1039785Y702110D02*
X-1039848Y702103D01*
G01X-1041619Y701961D02*
X-1041647Y701902D01*
G01X-1041581Y702011D02*
X-1041619Y701961D01*
G01X-1041532Y702053D02*
X-1041581Y702011D01*
G01X-1041477Y702084D02*
X-1041532Y702053D01*
G01X-1041418Y702103D02*
X-1041477Y702084D01*
G01X-1041355Y702110D02*
X-1041418Y702103D01*
G01X-1054222Y701961D02*
X-1054250Y701902D01*
G01X-1054184Y702011D02*
X-1054222Y701961D01*
G01X-1054135Y702053D02*
X-1054184Y702011D01*
G01X-1054081Y702084D02*
X-1054135Y702053D01*
G01X-1054021Y702103D02*
X-1054081Y702084D01*
G01X-1053958Y702110D02*
X-1054021Y702103D01*
G01X-1055792Y701961D02*
X-1055820Y701902D01*
G01X-1055754Y702011D02*
X-1055792Y701961D01*
G01X-1055705Y702053D02*
X-1055754Y702011D01*
G01X-1055651Y702084D02*
X-1055705Y702053D01*
G01X-1055591Y702103D02*
X-1055651Y702084D01*
G01X-1055528Y702110D02*
X-1055591Y702103D01*
G01X-1068395Y701961D02*
X-1068423Y701902D01*
G01X-1068357Y702011D02*
X-1068395Y701961D01*
G01X-1068309Y702053D02*
X-1068357Y702011D01*
G01X-1068254Y702084D02*
X-1068309Y702053D01*
G01X-1068194Y702103D02*
X-1068254Y702084D01*
G01X-1068132Y702110D02*
X-1068194Y702103D01*
G01X-1069965Y701961D02*
X-1069993Y701902D01*
G01X-1069927Y702011D02*
X-1069965Y701961D01*
G01X-1069879Y702053D02*
X-1069927Y702011D01*
G01X-1069824Y702084D02*
X-1069879Y702053D01*
G01X-1069764Y702103D02*
X-1069824Y702084D01*
G01X-1069702Y702110D02*
X-1069764Y702103D01*
G01X-1041958Y675621D02*
X-1041950Y675623D01*
G01X-1041966Y675620D02*
X-1041958Y675621D01*
G01X-1041975Y675619D02*
X-1041966Y675620D01*
G01X-1041983Y675618D02*
X-1041975Y675619D01*
G01X-1041991Y675617D02*
X-1041983Y675618D01*
G01X-1041998Y675616D02*
X-1041991Y675617D01*
G01X-1056132Y675621D02*
X-1056123Y675623D01*
G01X-1056140Y675620D02*
X-1056132Y675621D01*
G01X-1056148Y675619D02*
X-1056140Y675620D01*
G01X-1056156Y675618D02*
X-1056148Y675619D01*
G01X-1056164Y675617D02*
X-1056156Y675618D01*
G01X-1056171Y675616D02*
X-1056164Y675617D01*
G01X-1070305Y675621D02*
X-1070296Y675623D01*
G01X-1070313Y675620D02*
X-1070305Y675621D01*
G01X-1070321Y675619D02*
X-1070313Y675620D01*
G01X-1070329Y675618D02*
X-1070321Y675619D01*
G01X-1070337Y675617D02*
X-1070329Y675618D01*
G01X-1070344Y675616D02*
X-1070337Y675617D01*
G01X-1066617Y664205D02*
X-1066645Y664251D01*
G01X-1066584Y664167D02*
X-1066617Y664205D01*
G01X-1066543Y664139D02*
X-1066584Y664167D01*
G01X-1066498Y664123D02*
X-1066543Y664139D01*
G01X-1066453Y664117D02*
X-1066498Y664123D01*
G01X-1052444Y664205D02*
X-1052472Y664251D01*
G01X-1052411Y664167D02*
X-1052444Y664205D01*
G01X-1052370Y664139D02*
X-1052411Y664167D01*
G01X-1052325Y664123D02*
X-1052370Y664139D01*
G01X-1052280Y664117D02*
X-1052325Y664123D01*
G01X-1072552Y674132D02*
X-1072561Y674190D01*
G01X-1072530Y674083D02*
X-1072552Y674132D01*
G01X-1072497Y674044D02*
X-1072530Y674083D01*
G01X-1072456Y674015D02*
X-1072497Y674044D01*
G01X-1072410Y673998D02*
X-1072456Y674015D01*
G01X-1072364Y673993D02*
X-1072410Y673998D01*
G01X-1058379Y674132D02*
X-1058388Y674190D01*
G01X-1058356Y674083D02*
X-1058379Y674132D01*
G01X-1058323Y674044D02*
X-1058356Y674083D01*
G01X-1058283Y674015D02*
X-1058323Y674044D01*
G01X-1058237Y673998D02*
X-1058283Y674015D01*
G01X-1058191Y673993D02*
X-1058237Y673998D01*
G01X-1044206Y674132D02*
X-1044214Y674190D01*
G01X-1044183Y674083D02*
X-1044206Y674132D01*
G01X-1044150Y674044D02*
X-1044183Y674083D01*
G01X-1044109Y674015D02*
X-1044150Y674044D01*
G01X-1044064Y673998D02*
X-1044109Y674015D01*
G01X-1044018Y673993D02*
X-1044064Y673998D01*
G01X-1074306Y674807D02*
X-1074325Y674865D01*
G01X-1074272Y674753D02*
X-1074306Y674807D01*
G01X-1074224Y674702D02*
X-1074272Y674753D01*
G01X-1074163Y674659D02*
X-1074224Y674702D01*
G01X-1074093Y674624D02*
X-1074163Y674659D01*
G01X-1074017Y674600D02*
X-1074093Y674624D01*
G01X-1073937Y674587D02*
X-1074017Y674600D01*
G01X-1060133Y674807D02*
X-1060151Y674865D01*
G01X-1060099Y674753D02*
X-1060133Y674807D01*
G01X-1060050Y674702D02*
X-1060099Y674753D01*
G01X-1059990Y674659D02*
X-1060050Y674702D01*
G01X-1059920Y674624D02*
X-1059990Y674659D01*
G01X-1059844Y674600D02*
X-1059920Y674624D01*
G01X-1059764Y674587D02*
X-1059844Y674600D01*
G01X-1045960Y674807D02*
X-1045978Y674865D01*
G01X-1045926Y674753D02*
X-1045960Y674807D01*
G01X-1045877Y674702D02*
X-1045926Y674753D01*
G01X-1045817Y674659D02*
X-1045877Y674702D01*
G01X-1045747Y674624D02*
X-1045817Y674659D01*
G01X-1045670Y674600D02*
X-1045747Y674624D01*
G01X-1045590Y674587D02*
X-1045670Y674600D01*
G01X-1073764Y675617D02*
X-1073755Y675616D01*
G01X-1073772Y675618D02*
X-1073764Y675617D01*
G01X-1073780Y675619D02*
X-1073772Y675618D01*
G01X-1073788Y675620D02*
X-1073780Y675619D01*
G01X-1073797Y675621D02*
X-1073788Y675620D01*
G01X-1073803Y675623D02*
X-1073797Y675621D01*
G01X-1059591Y675617D02*
X-1059582Y675616D01*
G01X-1059599Y675618D02*
X-1059591Y675617D01*
G01X-1059607Y675619D02*
X-1059599Y675618D01*
G01X-1059615Y675620D02*
X-1059607Y675619D01*
G01X-1059623Y675621D02*
X-1059615Y675620D01*
G01X-1059630Y675623D02*
X-1059623Y675621D01*
G01X-1045418Y675617D02*
X-1045409Y675616D01*
G01X-1045426Y675618D02*
X-1045418Y675617D01*
G01X-1045434Y675619D02*
X-1045426Y675618D01*
G01X-1045442Y675620D02*
X-1045434Y675619D01*
G01X-1045450Y675621D02*
X-1045442Y675620D01*
G01X-1045457Y675623D02*
X-1045450Y675621D01*
G01X-1074071Y669533D02*
X-1074129Y669826D01*
G01X-1073900Y669274D02*
X-1074071Y669533D01*
G01X-1073636Y669099D02*
X-1073900Y669274D01*
G01X-1073329Y669039D02*
X-1073636Y669099D01*
G01X-1059898Y669533D02*
X-1059956Y669826D01*
G01X-1059727Y669274D02*
X-1059898Y669533D01*
G01X-1059463Y669099D02*
X-1059727Y669274D01*
G01X-1059156Y669039D02*
X-1059463Y669099D01*
G01X-1045725Y669533D02*
X-1045782Y669826D01*
G01X-1045553Y669274D02*
X-1045725Y669533D01*
G01X-1045290Y669099D02*
X-1045553Y669274D01*
G01X-1044983Y669039D02*
X-1045290Y669099D01*
G01X-1073688Y669633D02*
X-1073741Y669826D01*
G01X-1073538Y669487D02*
X-1073688Y669633D01*
G01X-1073329Y669432D02*
X-1073538Y669487D01*
G01X-1059515Y669633D02*
X-1059568Y669826D01*
G01X-1059365Y669487D02*
X-1059515Y669633D01*
G01X-1059156Y669432D02*
X-1059365Y669487D01*
G01X-1044033Y664118D02*
X-1044018Y664117D01*
G01X-1044049Y664120D02*
X-1044033Y664118D01*
G01X-1044065Y664124D02*
X-1044049Y664120D01*
G01X-1070390Y700366D02*
X-1070359Y700381D01*
G01X-1070438Y700360D02*
X-1070390Y700366D01*
G01X-1070499Y700361D02*
X-1070438Y700360D01*
G01X-1056217Y700366D02*
X-1056186Y700381D01*
G01X-1056265Y700360D02*
X-1056217Y700366D01*
G01X-1056326Y700361D02*
X-1056265Y700360D01*
G01X-1042044Y700366D02*
X-1042013Y700381D01*
G01X-1042092Y700360D02*
X-1042044Y700366D01*
G01X-1042153Y700361D02*
X-1042092Y700360D01*
G01X-1075390Y701883D02*
X-1075013Y701795D01*
G01X-1075466Y701902D02*
X-1075390Y701883D01*
G01X-1061217D02*
X-1060839Y701795D01*
G01X-1061293Y701902D02*
X-1061217Y701883D01*
G01X-1047043D02*
X-1046666Y701795D01*
G01X-1047120Y701902D02*
X-1047043Y701883D01*
G01X-1045341Y669633D02*
X-1045395Y669826D01*
G01X-1045191Y669487D02*
X-1045341Y669633D01*
G01X-1044983Y669432D02*
X-1045191Y669487D01*
G01X-1073622Y700360D02*
X-1073561Y700361D01*
G01X-1073670Y700366D02*
X-1073622Y700360D01*
G01X-1073701Y700381D02*
X-1073670Y700366D01*
G01X-1059449Y700360D02*
X-1059388Y700361D01*
G01X-1059497Y700366D02*
X-1059449Y700360D01*
G01X-1059528Y700381D02*
X-1059497Y700366D01*
G01X-1045276Y700360D02*
X-1045214Y700361D01*
G01X-1045324Y700366D02*
X-1045276Y700360D01*
G01X-1045355Y700381D02*
X-1045324Y700366D01*
G01X-1070433Y701322D02*
X-1070597Y700764D01*
G01X-1070353Y701747D02*
X-1070433Y701322D01*
G01X-1070361Y702016D02*
X-1070353Y701747D01*
G01X-1070456Y702110D02*
X-1070361Y702016D01*
G01X-1056260Y701322D02*
X-1056424Y700764D01*
G01X-1056180Y701747D02*
X-1056260Y701322D01*
G01X-1056188Y702016D02*
X-1056180Y701747D01*
G01X-1056282Y702110D02*
X-1056188Y702016D01*
G01X-1042087Y701322D02*
X-1042251Y700764D01*
G01X-1042007Y701747D02*
X-1042087Y701322D01*
G01X-1042015Y702016D02*
X-1042007Y701747D01*
G01X-1042109Y702110D02*
X-1042015Y702016D01*
G01X-1044105Y664130D02*
X-1044065Y664124D01*
G01X-1044146Y664145D02*
X-1044105Y664130D01*
G01X-1044183Y664170D02*
X-1044146Y664145D01*
G01X-1044214Y664203D02*
X-1044183Y664170D01*
G01X-1070229Y702078D02*
X-1070456Y702110D01*
G01X-1070082Y702008D02*
X-1070229Y702078D01*
G01X-1069993Y701902D02*
X-1070082Y702008D01*
G01X-1056056Y702078D02*
X-1056282Y702110D01*
G01X-1055909Y702008D02*
X-1056056Y702078D01*
G01X-1055820Y701902D02*
X-1055909Y702008D01*
G01X-1041882Y702078D02*
X-1042109Y702110D01*
G01X-1041735Y702008D02*
X-1041882Y702078D01*
G01X-1041647Y701902D02*
X-1041735Y702008D01*
G01X-1073309Y699951D02*
X-1073212Y699747D01*
G01X-1073426Y700155D02*
X-1073309Y699951D01*
G01X-1073649Y700496D02*
X-1073426Y700155D01*
G01X-1059136Y699951D02*
X-1059038Y699747D01*
G01X-1059253Y700155D02*
X-1059136Y699951D01*
G01X-1059476Y700496D02*
X-1059253Y700155D01*
G01X-1044962Y699951D02*
X-1044865Y699747D01*
G01X-1045080Y700155D02*
X-1044962Y699951D01*
G01X-1045303Y700496D02*
X-1045080Y700155D01*
G01X-1073728Y700631D02*
X-1073649Y700496D01*
G01X-1073796Y700764D02*
X-1073728Y700631D01*
G01X-1059555D02*
X-1059476Y700496D01*
G01X-1059623Y700764D02*
X-1059555Y700631D01*
G01X-1073366Y669639D02*
X-1073286Y669629D01*
G01X-1073441Y669657D02*
X-1073366Y669639D01*
G01X-1073511Y669682D02*
X-1073441Y669657D01*
G01X-1073571Y669712D02*
X-1073511Y669682D01*
G01X-1073619Y669748D02*
X-1073571Y669712D01*
G01X-1073654Y669786D02*
X-1073619Y669748D01*
G01X-1073674Y669826D02*
X-1073654Y669786D01*
G01X-1073291Y670374D02*
X-1073211Y670364D01*
G01X-1073367Y670392D02*
X-1073291Y670374D01*
G01X-1073436Y670417D02*
X-1073367Y670392D01*
G01X-1073496Y670447D02*
X-1073436Y670417D01*
G01X-1073544Y670482D02*
X-1073496Y670447D01*
G01X-1073579Y670521D02*
X-1073544Y670482D01*
G01X-1073599Y670561D02*
X-1073579Y670521D01*
G01X-1059193Y669639D02*
X-1059113Y669629D01*
G01X-1059268Y669657D02*
X-1059193Y669639D01*
G01X-1059337Y669682D02*
X-1059268Y669657D01*
G01X-1059398Y669712D02*
X-1059337Y669682D01*
G01X-1059446Y669748D02*
X-1059398Y669712D01*
G01X-1059481Y669786D02*
X-1059446Y669748D01*
G01X-1059501Y669826D02*
X-1059481Y669786D01*
G01X-1059118Y670374D02*
X-1059038Y670364D01*
G01X-1059193Y670392D02*
X-1059118Y670374D01*
G01X-1059263Y670417D02*
X-1059193Y670392D01*
G01X-1059323Y670447D02*
X-1059263Y670417D01*
G01X-1059371Y670482D02*
X-1059323Y670447D01*
G01X-1059406Y670521D02*
X-1059371Y670482D01*
G01X-1059426Y670561D02*
X-1059406Y670521D01*
G01X-1045019Y669639D02*
X-1044940Y669629D01*
G01X-1045095Y669657D02*
X-1045019Y669639D01*
G01X-1045164Y669682D02*
X-1045095Y669657D01*
G01X-1045224Y669712D02*
X-1045164Y669682D01*
G01X-1045273Y669748D02*
X-1045224Y669712D01*
G01X-1045308Y669786D02*
X-1045273Y669748D01*
G01X-1045327Y669826D02*
X-1045308Y669786D01*
G01X-1044945Y670374D02*
X-1044865Y670364D01*
G01X-1045020Y670392D02*
X-1044945Y670374D01*
G01X-1045089Y670417D02*
X-1045020Y670392D01*
G01X-1045150Y670447D02*
X-1045089Y670417D01*
G01X-1045198Y670482D02*
X-1045150Y670447D01*
G01X-1045233Y670521D02*
X-1045198Y670482D01*
G01X-1045253Y670561D02*
X-1045233Y670521D01*
G01X-1075905Y702103D02*
X-1075968Y702110D01*
G01X-1075845Y702084D02*
X-1075905Y702103D01*
G01X-1075789Y702052D02*
X-1075845Y702084D01*
G01X-1075742Y702010D02*
X-1075789Y702052D01*
G01X-1075704Y701960D02*
X-1075742Y702010D01*
G01X-1075677Y701902D02*
X-1075704Y701960D01*
G01X-1075695Y702103D02*
X-1075758Y702110D01*
G01X-1075635Y702084D02*
X-1075695Y702103D01*
G01X-1075579Y702052D02*
X-1075635Y702084D01*
G01X-1075532Y702010D02*
X-1075579Y702052D01*
G01X-1075494Y701960D02*
X-1075532Y702010D01*
G01X-1075467Y701902D02*
X-1075494Y701960D01*
G01X-1074651Y702103D02*
X-1074715Y702110D01*
G01X-1074592Y702084D02*
X-1074651Y702103D01*
G01X-1074537Y702053D02*
X-1074592Y702084D01*
G01X-1074489Y702010D02*
X-1074537Y702053D01*
G01X-1074451Y701960D02*
X-1074489Y702010D01*
G01X-1074423Y701902D02*
X-1074451Y701960D01*
G01X-1074295Y702103D02*
X-1074359Y702110D01*
G01X-1074235Y702084D02*
X-1074295Y702103D01*
G01X-1074181Y702053D02*
X-1074235Y702084D01*
G01X-1074133Y702010D02*
X-1074181Y702053D01*
G01X-1074094Y701960D02*
X-1074133Y702010D01*
G01X-1074067Y701902D02*
X-1074094Y701960D01*
G01X-1061731Y702103D02*
X-1061795Y702110D01*
G01X-1061672Y702084D02*
X-1061731Y702103D01*
G01X-1061616Y702052D02*
X-1061672Y702084D01*
G01X-1061569Y702010D02*
X-1061616Y702052D01*
G01X-1061531Y701960D02*
X-1061569Y702010D01*
G01X-1061503Y701902D02*
X-1061531Y701960D01*
G01X-1061521Y702103D02*
X-1061585Y702110D01*
G01X-1061462Y702084D02*
X-1061521Y702103D01*
G01X-1061406Y702052D02*
X-1061462Y702084D01*
G01X-1061359Y702010D02*
X-1061406Y702052D01*
G01X-1061321Y701960D02*
X-1061359Y702010D01*
G01X-1061293Y701902D02*
X-1061321Y701960D01*
G01X-1060478Y702103D02*
X-1060542Y702110D01*
G01X-1060418Y702084D02*
X-1060478Y702103D01*
G01X-1060364Y702053D02*
X-1060418Y702084D01*
G01X-1060315Y702010D02*
X-1060364Y702053D01*
G01X-1060277Y701960D02*
X-1060315Y702010D01*
G01X-1060250Y701902D02*
X-1060277Y701960D01*
G01X-1060122Y702103D02*
X-1060185Y702110D01*
G01X-1060062Y702084D02*
X-1060122Y702103D01*
G01X-1060008Y702053D02*
X-1060062Y702084D01*
G01X-1059959Y702010D02*
X-1060008Y702053D01*
G01X-1059921Y701960D02*
X-1059959Y702010D01*
G01X-1059894Y701902D02*
X-1059921Y701960D01*
G01X-1073887Y675644D02*
X-1073803Y675623D01*
G01X-1073966Y675679D02*
X-1073887Y675644D01*
G01X-1074032Y675723D02*
X-1073966Y675679D01*
G01X-1074086Y675775D02*
X-1074032Y675723D01*
G01X-1074123Y675834D02*
X-1074086Y675775D01*
G01X-1074143Y675895D02*
X-1074123Y675834D01*
G01X-1045382Y700631D02*
X-1045303Y700496D01*
G01X-1045450Y700764D02*
X-1045382Y700631D01*
G01X-1047558Y702103D02*
X-1047622Y702110D01*
G01X-1047498Y702084D02*
X-1047558Y702103D01*
G01X-1047443Y702052D02*
X-1047498Y702084D01*
G01X-1047395Y702010D02*
X-1047443Y702052D01*
G01X-1047357Y701960D02*
X-1047395Y702010D01*
G01X-1047330Y701902D02*
X-1047357Y701960D01*
G01X-1047348Y702103D02*
X-1047412Y702110D01*
G01X-1047288Y702084D02*
X-1047348Y702103D01*
G01X-1047233Y702052D02*
X-1047288Y702084D01*
G01X-1047185Y702010D02*
X-1047233Y702052D01*
G01X-1047147Y701960D02*
X-1047185Y702010D01*
G01X-1047120Y701902D02*
X-1047147Y701960D01*
G01X-1046305Y702103D02*
X-1046368Y702110D01*
G01X-1046245Y702084D02*
X-1046305Y702103D01*
G01X-1046190Y702053D02*
X-1046245Y702084D01*
G01X-1046142Y702010D02*
X-1046190Y702053D01*
G01X-1046104Y701960D02*
X-1046142Y702010D01*
G01X-1046077Y701902D02*
X-1046104Y701960D01*
G01X-1045949Y702103D02*
X-1046012Y702110D01*
G01X-1045889Y702084D02*
X-1045949Y702103D01*
G01X-1045834Y702053D02*
X-1045889Y702084D01*
G01X-1045786Y702010D02*
X-1045834Y702053D01*
G01X-1045748Y701960D02*
X-1045786Y702010D01*
G01X-1045721Y701902D02*
X-1045748Y701960D01*
G01X-1059714Y675644D02*
X-1059630Y675623D01*
G01X-1059792Y675679D02*
X-1059714Y675644D01*
G01X-1059859Y675723D02*
X-1059792Y675679D01*
G01X-1059913Y675775D02*
X-1059859Y675723D01*
G01X-1059950Y675834D02*
X-1059913Y675775D01*
G01X-1059970Y675895D02*
X-1059950Y675834D01*
G01X-1045541Y675644D02*
X-1045457Y675623D01*
G01X-1045619Y675679D02*
X-1045541Y675644D01*
G01X-1045686Y675723D02*
X-1045619Y675679D01*
G01X-1045739Y675775D02*
X-1045686Y675723D01*
G01X-1045777Y675834D02*
X-1045739Y675775D01*
G01X-1045797Y675895D02*
X-1045777Y675834D01*
G01X-1073698Y702019D02*
X-1073605Y702110D01*
G01X-1073708Y701752D02*
X-1073698Y702019D01*
G01X-1073628Y701326D02*
X-1073708Y701752D01*
G01X-1073463Y700764D02*
X-1073628Y701326D01*
G01X-1059525Y702019D02*
X-1059431Y702110D01*
G01X-1059534Y701752D02*
X-1059525Y702019D01*
G01X-1059455Y701326D02*
X-1059534Y701752D01*
G01X-1059290Y700764D02*
X-1059455Y701326D01*
G01X-1045352Y702019D02*
X-1045258Y702110D01*
G01X-1045361Y701752D02*
X-1045352Y702019D01*
G01X-1045282Y701326D02*
X-1045361Y701752D01*
G01X-1045117Y700764D02*
X-1045282Y701326D01*
G01X-1070127Y674410D02*
X-1070122Y674309D01*
G01X-1070141Y674505D02*
X-1070127Y674410D01*
G01X-1070163Y674587D02*
X-1070141Y674505D01*
G01X-1055954Y674410D02*
X-1055949Y674309D01*
G01X-1055967Y674505D02*
X-1055954Y674410D01*
G01X-1055990Y674587D02*
X-1055967Y674505D01*
G01X-1073613Y699954D02*
X-1073599Y699741D01*
G01X-1073647Y700169D02*
X-1073613Y699954D01*
G01X-1073701Y700381D02*
X-1073647Y700169D01*
G01X-1059439Y699954D02*
X-1059426Y699741D01*
G01X-1059473Y700169D02*
X-1059439Y699954D01*
G01X-1059528Y700381D02*
X-1059473Y700169D01*
G01X-1079526Y664133D02*
X-1079451Y664117D01*
G01X-1079590Y664175D02*
X-1079526Y664133D01*
G01X-1079632Y664240D02*
X-1079590Y664175D01*
G01X-1079648Y664314D02*
X-1079632Y664240D01*
G01X-1072439Y664133D02*
X-1072364Y664117D01*
G01X-1072503Y664175D02*
X-1072439Y664133D01*
G01X-1072546Y664240D02*
X-1072503Y664175D01*
G01X-1072561Y664314D02*
X-1072546Y664240D01*
G01X-1065352Y664133D02*
X-1065277Y664117D01*
G01X-1065417Y664175D02*
X-1065352Y664133D01*
G01X-1065459Y664240D02*
X-1065417Y664175D01*
G01X-1065474Y664314D02*
X-1065459Y664240D01*
G01X-1058266Y664133D02*
X-1058191Y664117D01*
G01X-1058330Y664175D02*
X-1058266Y664133D01*
G01X-1058372Y664240D02*
X-1058330Y664175D01*
G01X-1058388Y664314D02*
X-1058372Y664240D01*
G01X-1051179Y664133D02*
X-1051104Y664117D01*
G01X-1051244Y664175D02*
X-1051179Y664133D01*
G01X-1051286Y664240D02*
X-1051244Y664175D01*
G01X-1051301Y664314D02*
X-1051286Y664240D01*
G01X-1073883Y700999D02*
X-1073701Y700381D01*
G01X-1073998Y701482D02*
X-1073883Y700999D01*
G01X-1074067Y701902D02*
X-1073998Y701482D01*
G01X-1073373Y669442D02*
X-1073286Y669432D01*
G01X-1073455Y669472D02*
X-1073373Y669442D01*
G01X-1073528Y669518D02*
X-1073455Y669472D01*
G01X-1073590Y669582D02*
X-1073528Y669518D01*
G01X-1073636Y669656D02*
X-1073590Y669582D01*
G01X-1073664Y669739D02*
X-1073636Y669656D01*
G01X-1073674Y669826D02*
X-1073664Y669739D01*
G01X-1069763Y674788D02*
X-1069775Y674865D01*
G01X-1069753Y674703D02*
X-1069763Y674788D01*
G01X-1069745Y674610D02*
X-1069753Y674703D01*
G01X-1055590Y674788D02*
X-1055602Y674865D01*
G01X-1055580Y674703D02*
X-1055590Y674788D01*
G01X-1055572Y674610D02*
X-1055580Y674703D01*
G01X-1041417Y674788D02*
X-1041429Y674865D01*
G01X-1041407Y674703D02*
X-1041417Y674788D01*
G01X-1041399Y674610D02*
X-1041407Y674703D01*
G01X-1074197Y698430D02*
X-1074264Y698650D01*
G01X-1074157Y698205D02*
X-1074197Y698430D01*
G01X-1074143Y697977D02*
X-1074157Y698205D01*
G01X-1060024Y698430D02*
X-1060091Y698650D01*
G01X-1059984Y698205D02*
X-1060024Y698430D01*
G01X-1059970Y697977D02*
X-1059984Y698205D01*
G01X-1045851Y698430D02*
X-1045918Y698650D01*
G01X-1045810Y698205D02*
X-1045851Y698430D01*
G01X-1045797Y697977D02*
X-1045810Y698205D01*
G01X-1073820Y698521D02*
X-1073900Y698784D01*
G01X-1073772Y698251D02*
X-1073820Y698521D01*
G01X-1073755Y697977D02*
X-1073772Y698251D01*
G01X-1059647Y698521D02*
X-1059727Y698784D01*
G01X-1059598Y698251D02*
X-1059647Y698521D01*
G01X-1059582Y697977D02*
X-1059598Y698251D01*
G01X-1045474Y698521D02*
X-1045554Y698784D01*
G01X-1045425Y698251D02*
X-1045474Y698521D01*
G01X-1045409Y697977D02*
X-1045425Y698251D01*
G01X-1074408Y698431D02*
X-1074475Y698650D01*
G01X-1074368Y698205D02*
X-1074408Y698431D01*
G01X-1074355Y697977D02*
X-1074368Y698205D01*
G01X-1060235Y698431D02*
X-1060301Y698650D01*
G01X-1060195Y698205D02*
X-1060235Y698431D01*
G01X-1060181Y697977D02*
X-1060195Y698205D01*
G01X-1046062Y698431D02*
X-1046128Y698650D01*
G01X-1046022Y698205D02*
X-1046062Y698431D01*
G01X-1046008Y697977D02*
X-1046022Y698205D01*
G01X-1073795Y700161D02*
X-1073861Y700381D01*
G01X-1073755Y699936D02*
X-1073795Y700161D01*
G01X-1073741Y699707D02*
X-1073755Y699936D01*
G01X-1059621Y700161D02*
X-1059688Y700381D01*
G01X-1059581Y699936D02*
X-1059621Y700161D01*
G01X-1059568Y699707D02*
X-1059581Y699936D01*
G01X-1045448Y700161D02*
X-1045514Y700381D01*
G01X-1045408Y699936D02*
X-1045448Y700161D01*
G01X-1045395Y699707D02*
X-1045408Y699936D01*
G01X-1041794Y674505D02*
X-1041816Y674587D01*
G01X-1041780Y674410D02*
X-1041794Y674505D01*
G01X-1041776Y674309D02*
X-1041780Y674410D01*
G01X-1074741Y674406D02*
X-1074740Y674309D01*
G01X-1074741Y674507D02*
Y674406D01*
G01X-1074742Y674610D02*
X-1074741Y674507D01*
G01X-1069743Y674510D02*
X-1069745Y674610D01*
G01X-1069741Y674409D02*
X-1069743Y674510D01*
G01X-1060568Y674406D02*
X-1060567Y674309D01*
G01X-1060568Y674507D02*
Y674406D01*
G01X-1060569Y674610D02*
X-1060568Y674507D01*
G01X-1055569Y674510D02*
X-1055572Y674610D01*
G01X-1055568Y674409D02*
X-1055569Y674510D01*
G01X-1074358Y674412D02*
X-1074359Y669826D01*
G01X-1074357Y674513D02*
X-1074358Y674412D01*
G01X-1074355Y674610D02*
X-1074357Y674513D01*
G01X-1060185Y674412D02*
X-1060186Y669826D01*
G01X-1060184Y674513D02*
X-1060185Y674412D01*
G01X-1060181Y674610D02*
X-1060184Y674513D01*
G01X-1073959Y674505D02*
X-1073937Y674587D01*
G01X-1073973Y674410D02*
X-1073959Y674505D01*
G01X-1073978Y674309D02*
X-1073973Y674410D01*
G01X-1059786Y674505D02*
X-1059764Y674587D01*
G01X-1059800Y674410D02*
X-1059786Y674505D01*
G01X-1059804Y674309D02*
X-1059800Y674410D01*
G01X-1069691Y698430D02*
X-1069625Y698650D01*
G01X-1069732Y698205D02*
X-1069691Y698430D01*
G01X-1069745Y697977D02*
X-1069732Y698205D01*
G01X-1070414Y700169D02*
X-1070359Y700381D01*
G01X-1070448Y699954D02*
X-1070414Y700169D01*
G01X-1070461Y699741D02*
X-1070448Y699954D01*
G01X-1045266D02*
X-1045253Y699741D01*
G01X-1045300Y700169D02*
X-1045266Y699954D01*
G01X-1045355Y700381D02*
X-1045300Y700169D01*
G01X-1059710Y700999D02*
X-1059528Y700381D01*
G01X-1059825Y701482D02*
X-1059710Y700999D01*
G01X-1059894Y701902D02*
X-1059825Y701482D01*
G01X-1045537Y700999D02*
X-1045355Y700381D01*
G01X-1045652Y701482D02*
X-1045537Y700999D01*
G01X-1045721Y701902D02*
X-1045652Y701482D01*
G01X-1044113Y673348D02*
X-1044069Y673330D01*
G01X-1044152Y673377D02*
X-1044113Y673348D01*
G01X-1044184Y673416D02*
X-1044152Y673377D01*
G01X-1044206Y673464D02*
X-1044184Y673416D01*
G01X-1044214Y673520D02*
X-1044206Y673464D01*
G01X-1059200Y669442D02*
X-1059113Y669432D01*
G01X-1059282Y669472D02*
X-1059200Y669442D01*
G01X-1059355Y669518D02*
X-1059282Y669472D01*
G01X-1059417Y669582D02*
X-1059355Y669518D01*
G01X-1059462Y669656D02*
X-1059417Y669582D01*
G01X-1059491Y669739D02*
X-1059462Y669656D01*
G01X-1059501Y669826D02*
X-1059491Y669739D01*
G01X-1045027Y669442D02*
X-1044940Y669432D01*
G01X-1045108Y669472D02*
X-1045027Y669442D01*
G01X-1045181Y669518D02*
X-1045108Y669472D01*
G01X-1045243Y669582D02*
X-1045181Y669518D01*
G01X-1045289Y669656D02*
X-1045243Y669582D01*
G01X-1045318Y669739D02*
X-1045289Y669656D01*
G01X-1045327Y669826D02*
X-1045318Y669739D01*
G01X-1046395Y674406D02*
X-1046394Y674309D01*
G01X-1046395Y674507D02*
Y674406D01*
G01X-1046396Y674610D02*
X-1046395Y674507D01*
G01X-1041396Y674510D02*
X-1041399Y674610D01*
G01X-1041395Y674409D02*
X-1041396Y674510D01*
G01X-1046012Y674412D02*
Y669826D01*
G01X-1046011Y674513D02*
X-1046012Y674412D01*
G01X-1046008Y674610D02*
X-1046011Y674513D01*
G01X-1045613Y674505D02*
X-1045590Y674587D01*
G01X-1045626Y674410D02*
X-1045613Y674505D01*
G01X-1045631Y674309D02*
X-1045626Y674410D01*
G01X-1055518Y698430D02*
X-1055452Y698650D01*
G01X-1055558Y698205D02*
X-1055518Y698430D01*
G01X-1055572Y697977D02*
X-1055558Y698205D01*
G01X-1041345Y698430D02*
X-1041279Y698650D01*
G01X-1041385Y698205D02*
X-1041345Y698430D01*
G01X-1041399Y697977D02*
X-1041385Y698205D01*
G01X-1056241Y700169D02*
X-1056186Y700381D01*
G01X-1056274Y699954D02*
X-1056241Y700169D01*
G01X-1056288Y699741D02*
X-1056274Y699954D01*
G01X-1042067Y700169D02*
X-1042013Y700381D01*
G01X-1042101Y699954D02*
X-1042067Y700169D01*
G01X-1042115Y699741D02*
X-1042101Y699954D01*
G01X-1074347Y674702D02*
X-1074355Y674610D01*
G01X-1074337Y674788D02*
X-1074347Y674702D01*
G01X-1074325Y674865D02*
X-1074337Y674788D01*
G01X-1060173Y674702D02*
X-1060181Y674610D01*
G01X-1060163Y674788D02*
X-1060173Y674702D01*
G01X-1060151Y674865D02*
X-1060163Y674788D01*
G01X-1046000Y674702D02*
X-1046008Y674610D01*
G01X-1045990Y674788D02*
X-1046000Y674702D01*
G01X-1045978Y674865D02*
X-1045990Y674788D01*
G01X-1070178Y700996D02*
X-1070359Y700381D01*
G01X-1070063Y701478D02*
X-1070178Y700996D01*
G01X-1069993Y701902D02*
X-1070063Y701478D01*
G01X-1056005Y700996D02*
X-1056186Y700381D01*
G01X-1055889Y701478D02*
X-1056005Y700996D01*
G01X-1055820Y701902D02*
X-1055889Y701478D01*
G01X-1041832Y700996D02*
X-1042013Y700381D01*
G01X-1041716Y701478D02*
X-1041832Y700996D01*
G01X-1041647Y701902D02*
X-1041716Y701478D01*
G01X-1076186Y664133D02*
X-1076262Y664117D01*
G01X-1076122Y664176D02*
X-1076186Y664133D01*
G01X-1076079Y664240D02*
X-1076122Y664176D01*
G01X-1076065Y664314D02*
X-1076079Y664240D01*
G01X-1069099Y664133D02*
X-1069175Y664117D01*
G01X-1069035Y664176D02*
X-1069099Y664133D01*
G01X-1068993Y664240D02*
X-1069035Y664176D01*
G01X-1068978Y664314D02*
X-1068993Y664240D01*
G01X-1062013Y664133D02*
X-1062088Y664117D01*
G01X-1061949Y664176D02*
X-1062013Y664133D01*
G01X-1061906Y664240D02*
X-1061949Y664176D01*
G01X-1061892Y664314D02*
X-1061906Y664240D01*
G01X-1054926Y664133D02*
X-1055002Y664117D01*
G01X-1054862Y664176D02*
X-1054926Y664133D01*
G01X-1054820Y664240D02*
X-1054862Y664176D01*
G01X-1054805Y664314D02*
X-1054820Y664240D01*
G01X-1047840Y664133D02*
X-1047915Y664117D01*
G01X-1047776Y664176D02*
X-1047840Y664133D01*
G01X-1047733Y664240D02*
X-1047776Y664176D01*
G01X-1047718Y664314D02*
X-1047733Y664240D01*
G01X-1070306Y699936D02*
X-1070319Y699707D01*
G01X-1070266Y700161D02*
X-1070306Y699936D01*
G01X-1070199Y700381D02*
X-1070266Y700161D01*
G01X-1056133Y699936D02*
X-1056146Y699707D01*
G01X-1056093Y700161D02*
X-1056133Y699936D01*
G01X-1056026Y700381D02*
X-1056093Y700161D01*
G01X-1070328Y698251D02*
X-1070344Y697977D01*
G01X-1070280Y698521D02*
X-1070328Y698251D01*
G01X-1070200Y698784D02*
X-1070280Y698521D01*
G01X-1056155Y698251D02*
X-1056171Y697977D01*
G01X-1056106Y698521D02*
X-1056155Y698251D01*
G01X-1056026Y698784D02*
X-1056106Y698521D01*
G01X-1069943Y698205D02*
X-1069957Y697977D01*
G01X-1069902Y698430D02*
X-1069943Y698205D01*
G01X-1069835Y698650D02*
X-1069902Y698430D01*
G01X-1055770Y698205D02*
X-1055783Y697977D01*
G01X-1055729Y698430D02*
X-1055770Y698205D01*
G01X-1055662Y698650D02*
X-1055729Y698430D01*
G01X-1070082Y674600D02*
X-1070163Y674587D01*
G01X-1070005Y674625D02*
X-1070082Y674600D01*
G01X-1069935Y674660D02*
X-1070005Y674625D01*
G01X-1069875Y674703D02*
X-1069935Y674660D01*
G01X-1069827Y674753D02*
X-1069875Y674703D01*
G01X-1069793Y674808D02*
X-1069827Y674753D01*
G01X-1069775Y674865D02*
X-1069793Y674808D01*
G01X-1069409Y702103D02*
X-1069346Y702110D01*
G01X-1069469Y702084D02*
X-1069409Y702103D01*
G01X-1069524Y702052D02*
X-1069469Y702084D01*
G01X-1069572Y702010D02*
X-1069524Y702052D01*
G01X-1069610Y701960D02*
X-1069572Y702010D01*
G01X-1069637Y701902D02*
X-1069610Y701960D01*
G01X-1068405Y702103D02*
X-1068342Y702110D01*
G01X-1068465Y702084D02*
X-1068405Y702103D01*
G01X-1068521Y702052D02*
X-1068465Y702084D01*
G01X-1068568Y702010D02*
X-1068521Y702052D01*
G01X-1068606Y701960D02*
X-1068568Y702010D01*
G01X-1068633Y701902D02*
X-1068606Y701960D01*
G01X-1070752Y699951D02*
X-1070634Y700155D01*
G01X-1070849Y699747D02*
X-1070752Y699951D01*
G01X-1040754Y674008D02*
X-1040829Y673993D01*
G01X-1040689Y674051D02*
X-1040754Y674008D01*
G01X-1040647Y674116D02*
X-1040689Y674051D01*
G01X-1040632Y674190D02*
X-1040647Y674116D01*
G01X-1041959Y699936D02*
X-1041973Y699707D01*
G01X-1041919Y700161D02*
X-1041959Y699936D01*
G01X-1041853Y700381D02*
X-1041919Y700161D01*
G01X-1041982Y698251D02*
X-1041998Y697977D01*
G01X-1041933Y698521D02*
X-1041982Y698251D01*
G01X-1041853Y698784D02*
X-1041933Y698521D01*
G01X-1041597Y698205D02*
X-1041610Y697977D01*
G01X-1041556Y698430D02*
X-1041597Y698205D01*
G01X-1041489Y698650D02*
X-1041556Y698430D01*
G01X-1055909Y674600D02*
X-1055990Y674587D01*
G01X-1055832Y674625D02*
X-1055909Y674600D01*
G01X-1055761Y674660D02*
X-1055832Y674625D01*
G01X-1055701Y674703D02*
X-1055761Y674660D01*
G01X-1055653Y674753D02*
X-1055701Y674703D01*
G01X-1055620Y674808D02*
X-1055653Y674753D01*
G01X-1055602Y674865D02*
X-1055620Y674808D01*
G01X-1055236Y702103D02*
X-1055172Y702110D01*
G01X-1055296Y702084D02*
X-1055236Y702103D01*
G01X-1055351Y702052D02*
X-1055296Y702084D01*
G01X-1055398Y702010D02*
X-1055351Y702052D01*
G01X-1055437Y701960D02*
X-1055398Y702010D01*
G01X-1055464Y701902D02*
X-1055437Y701960D01*
G01X-1054232Y702103D02*
X-1054169Y702110D01*
G01X-1054292Y702084D02*
X-1054232Y702103D01*
G01X-1054347Y702052D02*
X-1054292Y702084D01*
G01X-1054395Y702010D02*
X-1054347Y702052D01*
G01X-1054433Y701960D02*
X-1054395Y702010D01*
G01X-1054460Y701902D02*
X-1054433Y701960D01*
G01X-1041063Y702103D02*
X-1040999Y702110D01*
G01X-1041122Y702084D02*
X-1041063Y702103D01*
G01X-1041178Y702052D02*
X-1041122Y702084D01*
G01X-1041225Y702010D02*
X-1041178Y702052D01*
G01X-1041263Y701960D02*
X-1041225Y702010D01*
G01X-1041291Y701902D02*
X-1041263Y701960D01*
G01X-1040059Y702103D02*
X-1039995Y702110D01*
G01X-1040118Y702084D02*
X-1040059Y702103D01*
G01X-1040174Y702052D02*
X-1040118Y702084D01*
G01X-1040221Y702010D02*
X-1040174Y702052D01*
G01X-1040259Y701960D02*
X-1040221Y702010D01*
G01X-1040287Y701902D02*
X-1040259Y701960D01*
G01X-1056578Y699951D02*
X-1056461Y700155D01*
G01X-1056676Y699747D02*
X-1056578Y699951D01*
G01X-1042405D02*
X-1042288Y700155D01*
G01X-1042502Y699747D02*
X-1042405Y699951D01*
G01X-1070332Y700631D02*
X-1070264Y700764D01*
G01X-1070411Y700496D02*
X-1070332Y700631D01*
G01X-1070634Y700155D02*
X-1070411Y700496D01*
G01X-1056159Y700631D02*
X-1056091Y700764D01*
G01X-1056238Y700496D02*
X-1056159Y700631D01*
G01X-1056461Y700155D02*
X-1056238Y700496D01*
G01X-1041986Y700631D02*
X-1041918Y700764D01*
G01X-1042065Y700496D02*
X-1041986Y700631D01*
G01X-1042288Y700155D02*
X-1042065Y700496D01*
G01X-1076177Y664136D02*
X-1076262Y664117D01*
G01X-1076114Y664184D02*
X-1076177Y664136D01*
G01X-1076070Y664251D02*
X-1076114Y664184D01*
G01X-1062004Y664136D02*
X-1062088Y664117D01*
G01X-1061940Y664184D02*
X-1062004Y664136D01*
G01X-1061897Y664251D02*
X-1061940Y664184D01*
G01X-1073828Y702079D02*
X-1073605Y702110D01*
G01X-1073986Y702002D02*
X-1073828Y702079D01*
G01X-1074067Y701902D02*
X-1073986Y702002D01*
G01X-1059655Y702079D02*
X-1059431Y702110D01*
G01X-1059813Y702002D02*
X-1059655Y702079D01*
G01X-1059894Y701902D02*
X-1059813Y702002D01*
G01X-1045481Y702079D02*
X-1045258Y702110D01*
G01X-1045639Y702002D02*
X-1045481Y702079D01*
G01X-1045721Y701902D02*
X-1045639Y702002D01*
G01X-1047830Y664136D02*
X-1047915Y664117D01*
G01X-1047767Y664184D02*
X-1047830Y664136D01*
G01X-1047723Y664251D02*
X-1047767Y664184D01*
G01X-1040741Y664130D02*
X-1040782Y664124D01*
G01X-1040700Y664145D02*
X-1040741Y664130D01*
G01X-1040663Y664170D02*
X-1040700Y664145D01*
G01X-1040632Y664203D02*
X-1040663Y664170D01*
G01X-1040640Y673464D02*
X-1040632Y673520D01*
G01X-1040662Y673415D02*
X-1040640Y673464D01*
G01X-1040694Y673377D02*
X-1040662Y673415D01*
G01X-1040734Y673348D02*
X-1040694Y673377D01*
G01X-1040777Y673330D02*
X-1040734Y673348D01*
G01X-1046025Y669826D02*
G03X-1045631Y669432I394J0D01*
G01X-1050396D02*
G03X-1050789Y669039I0J-393D01*
G01X-1048230D02*
G03X-1048624Y669432I-393J0D01*
G01X-1043309D02*
G03X-1043703Y669039I0J-394D01*
G01X-1041144D02*
G03X-1041537Y669432I-393J0D01*
G01X-1046379Y669826D02*
G03X-1045631Y669078I748J0D01*
G01X-1041472Y700240D02*
G03X-1041567Y699707I1440J-532D01*
G01X-1046414Y697977D02*
G03X-1046509Y698509I-1535J0D01*
G01X-1045801Y699707D02*
G03X-1045896Y700240I-1535J1D01*
G01X-1040897Y698509D02*
G03X-1040993Y697977I1440J-534D01*
G01X-1033979Y662346D02*
G03X-1030042I1969J0D01*
G01X-1033979D02*
G03X-1030042I1969J0D01*
G01X-1048231Y656440D02*
G03I-709J0D01*
G01Y652110D02*
G03I-709J0D01*
G01X-1041145Y647385D02*
G03I-708J0D01*
G01X-1040377D02*
G03I-1476J0D01*
G01X-1043668Y648313D02*
G03Y646533I1299J-890D01*
G01X-1040597D02*
G03Y648313I-1299J890D01*
G01X-1041145Y641873D02*
G03I-708J0D01*
G01X-1043668Y640990D02*
G03Y639211I1299J-889D01*
G01X-1040597D02*
G03Y640990I-1299J890D01*
G01X-1048231Y646598D02*
G03I-709J0D01*
G01Y642267D02*
G03I-709J0D01*
G01X-1060198Y669826D02*
G03X-1059804Y669432I394J0D01*
G01X-1064569D02*
G03X-1064962Y669039I0J-393D01*
G01X-1062403D02*
G03X-1062797Y669432I-393J0D01*
G01X-1071655D02*
G03X-1072049Y669039I0J-394D01*
G01X-1069490D02*
G03X-1069884Y669432I-393J0D01*
G01X-1057482D02*
G03X-1057876Y669039I0J-394D01*
G01X-1055317D02*
G03X-1055710Y669432I-393J0D01*
G01X-1060552Y669826D02*
G03X-1059804Y669078I748J0D01*
G01X-1055645Y700240D02*
G03X-1055741Y699707I1440J-534D01*
G01X-1069818Y700240D02*
G03X-1069914Y699707I1440J-534D01*
G01X-1060587Y697977D02*
G03X-1060682Y698509I-1536J0D01*
G01X-1059974Y699707D02*
G03X-1060069Y700240I-1535J1D01*
G01X-1069244Y698509D02*
G03X-1069339Y697977I1440J-532D01*
G01X-1055070Y698509D02*
G03X-1055166Y697977I1440J-534D01*
G01X-1062405Y656440D02*
G03I-708J0D01*
G01Y652110D02*
G03I-708J0D01*
G01Y646598D02*
G03I-708J0D01*
G01X-1055318Y647385D02*
G03I-709J0D01*
G01Y641873D02*
G03I-709J0D01*
G01X-1062405Y642267D02*
G03I-708J0D01*
G01X-1069491Y647385D02*
G03I-709J0D01*
G01Y641873D02*
G03I-709J0D01*
G01X-1074760Y697977D02*
G03X-1074856Y698509I-1536J-2D01*
G01X-1074147Y699707D02*
G03X-1074242Y700240I-1535J1D01*
G01X-1074371Y669826D02*
G03X-1073978Y669432I394J0D01*
G01X-1078742D02*
G03X-1079136Y669039I0J-394D01*
G01X-1076577D02*
G03X-1076970Y669432I-393J0D01*
G01X-1074726Y669826D02*
G03X-1073978Y669078I748J0D01*
G01X-1076578Y656440D02*
G03I-708J0D01*
G01Y652110D02*
G03I-708J0D01*
G01Y646598D02*
G03I-708J0D01*
G01Y642267D02*
G03I-708J0D01*
G01X-1040461Y649699D02*
X-1040535Y649674D01*
G01X-1040658Y649749D02*
X-1040559Y649824D01*
G01X-1040535Y649674D02*
X-1040584Y649623D01*
G01X-1046077Y701902D02*
X-1046451Y701795D01*
G01X-1047704D02*
X-1047330Y701902D01*
G01X-1045554Y698784D02*
X-1045918Y698650D01*
G01X-1046128D02*
X-1046492Y698515D01*
G01X-1045514Y700381D02*
X-1045879Y700246D01*
G01X-1059727Y698784D02*
X-1060091Y698650D01*
G01X-1060301D02*
X-1060666Y698515D01*
G01X-1059688Y700381D02*
X-1060052Y700246D01*
G01X-1039879Y702110D02*
X-1041224Y700764D01*
G01X-1046375Y702110D02*
X-1047720Y700764D01*
G01X-1044841Y649372D02*
X-1044988Y649196D01*
G01Y649397D02*
X-1044841Y649573D01*
G01X-1040731Y649649D02*
X-1040658Y649749D01*
G01X-1047644Y650530D02*
X-1046266Y652917D01*
G01X-1054731Y650530D02*
X-1053353Y652917D01*
G01X-1060250Y701902D02*
X-1060624Y701795D01*
G01X-1061878D02*
X-1061503Y701902D01*
G01X-1074423D02*
X-1074798Y701795D01*
G01X-1076051D02*
X-1075677Y701902D01*
G01X-1073900Y698784D02*
X-1074264Y698650D01*
G01X-1074475D02*
X-1074839Y698515D01*
G01X-1073861Y700381D02*
X-1074225Y700246D01*
G01X-1053461Y702110D02*
X-1054806Y700764D01*
G01X-1060548Y702110D02*
X-1061893Y700764D01*
G01X-1067635Y702110D02*
X-1068980Y700764D01*
G01X-1074721Y702110D02*
X-1076066Y700764D01*
G01X-1061818Y650530D02*
X-1060440Y652917D01*
G01X-1068904Y650530D02*
X-1067526Y652917D01*
G01X-1075991Y650530D02*
X-1074613Y652917D01*
G01X-1039702Y701795D02*
X-1040914Y698515D01*
G01X-1041279Y698650D02*
X-1040077Y701902D01*
G01X-1040287D02*
X-1041489Y698650D01*
G01X-1041853Y698785D02*
X-1040741Y701795D01*
G01X-1041489Y700246D02*
X-1040928Y701763D01*
G01X-1041291Y701902D02*
X-1041853Y700381D01*
G01X-1053876Y701795D02*
X-1055088Y698515D01*
G01X-1055452Y698650D02*
X-1054250Y701902D01*
G01X-1054460D02*
X-1055662Y698650D01*
G01X-1056026Y698785D02*
X-1054914Y701795D01*
G01X-1055662Y700246D02*
X-1055101Y701763D01*
G01X-1055464Y701902D02*
X-1056026Y700381D01*
G01X-1043660Y650377D02*
X-1044053Y649196D01*
G01X-1040584Y649623D02*
X-1040608Y649548D01*
G01X-1040756Y649573D02*
X-1040731Y649649D01*
G01X-1043930Y649975D02*
X-1044152Y649297D01*
G01X-1043906Y650076D02*
X-1043807Y650377D01*
G01X-1068049Y701795D02*
X-1069261Y698515D01*
G01X-1069625Y698650D02*
X-1068423Y701902D01*
G01X-1068633D02*
X-1069835Y698650D01*
G01X-1070200Y698785D02*
X-1069087Y701795D01*
G01X-1069835Y700246D02*
X-1069274Y701763D01*
G01X-1069637Y701902D02*
X-1070199Y700381D01*
G01X-1045409Y675616D02*
X-1045590Y674587D01*
G01X-1045978Y674865D02*
X-1045797Y675895D01*
G01X-1059582Y675616D02*
X-1059764Y674587D01*
G01X-1060151Y674865D02*
X-1059970Y675895D01*
G01X-1073755Y675616D02*
X-1073937Y674587D01*
G01X-1074325Y674865D02*
X-1074143Y675895D01*
G01X-1044940Y669629D02*
X-1044865Y670364D01*
G01X-1045253Y670561D02*
X-1045327Y669826D01*
G01X-1059113Y669629D02*
X-1059038Y670364D01*
G01X-1059426Y670561D02*
X-1059501Y669826D01*
G01X-1040782Y664124D02*
X-1040789Y663527D01*
G01X-1042115Y699741D02*
Y699707D01*
G01X-1042503D02*
X-1042502Y699747D01*
G01X-1041013Y674309D02*
X-1041011Y674610D01*
G01X-1041138Y669013D02*
X-1041137Y669432D01*
G01X-1040777Y673330D02*
X-1040781Y664124D01*
G01X-1030042Y1062991D02*
Y662346D01*
G01Y1062991D02*
Y662346D01*
G01X-1039157Y675174D02*
Y662739D01*
G01X-1039485Y663527D02*
Y702110D01*
G01X-1039702Y701795D02*
Y702110D01*
G01X-1039846Y650377D02*
Y649196D01*
G01X-1039993Y649322D02*
Y649699D01*
G01Y649850D02*
Y650377D01*
G01X-1040597Y646533D02*
Y640990D01*
G01Y653921D02*
Y648313D01*
G01X-1040608Y649548D02*
Y649473D01*
G01X-1040632Y664203D02*
Y663527D01*
G01Y674412D02*
Y673520D01*
G01X-1040741Y701795D02*
Y702110D01*
G01X-1040756Y649473D02*
Y649573D01*
G01X-1040829Y664117D02*
Y673993D01*
G01X-1040928Y702110D02*
Y694236D01*
G01X-1040953Y650377D02*
Y649196D01*
G01X-1041011Y674610D02*
Y697977D01*
G01X-1041013Y669432D02*
Y674309D01*
G01X-1041100Y649196D02*
Y650377D01*
G01X-1041144Y669039D02*
Y665102D01*
G01X-1041242Y669275D02*
Y665338D01*
G01X-1041297Y650377D02*
Y649196D01*
G01X-1041394Y669406D02*
X-1041395Y674409D01*
G01X-1041399Y697977D02*
Y674610D01*
G01X-1041445Y649347D02*
Y650377D01*
G01X-1041585Y699707D02*
Y669432D01*
G01X-1041610Y697977D02*
Y675895D01*
G01X-1041776Y669432D02*
Y674309D01*
G01X-1041973Y699707D02*
Y669432D01*
G01X-1041998Y675616D02*
Y697977D01*
G01X-1042115Y699707D02*
Y669432D01*
G01X-1042134Y650201D02*
Y649196D01*
G01X-1042282D02*
Y650377D01*
G01X-1042503Y669432D02*
Y699707D01*
G01X-1043604Y669275D02*
Y665338D01*
G01X-1043668Y646533D02*
Y640990D01*
G01Y653921D02*
Y648313D01*
G01X-1043703Y670561D02*
Y665102D01*
G01X-1043707Y646594D02*
Y640930D01*
G01Y650530D02*
Y648253D01*
G01X-1044018Y673993D02*
Y664117D01*
G01X-1044214Y664203D02*
Y663527D01*
G01Y674412D02*
Y673520D01*
G01X-1044841Y649573D02*
Y649372D01*
G01X-1044865Y670364D02*
Y699707D01*
G01X-1044940Y669629D02*
Y669432D01*
G01X-1044983D02*
Y669039D01*
G01X-1044988Y650377D02*
Y649397D01*
G01X-1045136Y649196D02*
Y650377D01*
G01X-1045253Y699707D02*
Y670561D01*
G01X-1045395Y669826D02*
Y699707D01*
G01X-1045409Y675616D02*
Y697977D01*
G01X-1045631Y669064D02*
Y674309D01*
G01X-1045782Y669826D02*
Y699707D01*
G01X-1045797Y675895D02*
Y697977D01*
G01X-1046008D02*
Y674610D01*
G01X-1046394Y674309D02*
Y669826D01*
G01X-1046396Y697977D02*
Y674610D01*
G01X-1046451Y702110D02*
Y701795D01*
G01X-1046666D02*
Y702110D01*
G01X-1047704D02*
Y701795D01*
G01X-1047718Y663527D02*
Y675174D01*
G01X-1047730D02*
X-1047728Y664251D01*
G01X-1047851Y702110D02*
Y694236D01*
G01X-1047915Y675174D02*
Y664117D01*
G01X-1048230Y669039D02*
Y665102D01*
G01X-1048540Y699157D02*
Y675174D01*
G01X-1044069Y673330D02*
X-1044065Y664124D01*
G01X-1045253Y699741D02*
Y699707D01*
G01X-1044865Y699747D02*
Y699707D01*
G01X-1044057Y663527D02*
X-1044065Y664124D01*
G01X-1041610Y675895D02*
X-1041429Y674865D01*
G01X-1041816Y674587D02*
X-1041998Y675616D01*
G01X-1055783Y675895D02*
X-1055602Y674865D01*
G01X-1055990Y674587D02*
X-1056171Y675616D01*
G01X-1073286Y669629D02*
X-1073211Y670364D01*
G01X-1073599Y670561D02*
X-1073674Y669826D01*
G01X-1056288Y699741D02*
Y699707D01*
G01X-1056676D02*
Y699747D01*
G01X-1070461Y699741D02*
Y699707D01*
G01X-1070849D02*
Y699747D01*
G01X-1055186Y674309D02*
X-1055184Y674610D01*
G01X-1069360Y674309D02*
X-1069358Y674610D01*
G01X-1055311Y669013D02*
X-1055310Y669432D01*
G01X-1069484Y669013D02*
X-1069483Y669432D01*
G01X-1050789Y669039D02*
Y665102D01*
G01X-1051104Y675174D02*
Y664117D01*
G01X-1051301Y675174D02*
Y663527D01*
G01X-1052280Y664117D02*
Y699157D01*
G01X-1052379Y694236D02*
Y702110D01*
G01X-1052466Y699157D02*
Y664251D01*
G01X-1052477D02*
Y663527D01*
G01X-1052739Y702110D02*
Y694236D01*
G01X-1053876Y701795D02*
Y702110D01*
G01X-1054805Y663527D02*
Y674412D01*
G01X-1054914Y701795D02*
Y702110D01*
G01X-1055002Y664117D02*
Y673993D01*
G01X-1055101Y702110D02*
Y694236D01*
G01X-1055184Y674610D02*
Y697977D01*
G01X-1055187Y669432D02*
Y674309D01*
G01X-1055317Y669039D02*
Y665102D01*
G01X-1055568Y674409D02*
Y669406D01*
G01X-1055572Y674610D02*
Y697977D01*
G01X-1055758Y699707D02*
Y669432D01*
G01X-1055783Y697977D02*
Y675895D01*
G01X-1055949Y669432D02*
Y674309D01*
G01X-1056146Y699707D02*
Y669432D01*
G01X-1056171Y675616D02*
Y697977D01*
G01X-1056288Y699707D02*
Y669432D01*
G01X-1056676D02*
Y699707D01*
G01X-1057876Y670561D02*
Y665102D01*
G01X-1058191Y673993D02*
Y664117D01*
G01X-1058388Y674412D02*
Y663527D01*
G01X-1059038Y670364D02*
Y699707D01*
G01X-1059113Y669629D02*
Y669432D01*
G01X-1059156D02*
Y669039D01*
G01X-1059426Y699707D02*
Y670561D01*
G01X-1059568Y669826D02*
Y699707D01*
G01X-1059582Y675616D02*
Y697977D01*
G01X-1059804Y669064D02*
Y674309D01*
G01X-1059956Y669826D02*
Y699707D01*
G01X-1059970Y675895D02*
Y697977D01*
G01X-1060181D02*
Y674610D01*
G01X-1060567Y674309D02*
Y669826D01*
G01X-1060569Y697977D02*
Y674610D01*
G01X-1060624Y702110D02*
Y701795D01*
G01X-1060839D02*
Y702110D01*
G01X-1061878D02*
Y701795D01*
G01X-1061892Y663527D02*
Y675174D01*
G01X-1061903D02*
X-1061901Y664251D01*
G01X-1062024Y702110D02*
Y694236D01*
G01X-1062088Y675174D02*
Y664117D01*
G01X-1062403Y669039D02*
Y665102D01*
G01X-1062713Y699157D02*
Y675174D01*
G01X-1064962Y669039D02*
Y665102D01*
G01X-1065277Y675174D02*
Y664117D01*
G01X-1065474Y675174D02*
Y663527D01*
G01X-1066453Y664117D02*
Y699157D01*
G01X-1066552Y694236D02*
Y702110D01*
G01X-1066640Y699157D02*
Y664251D01*
G01X-1066650D02*
Y663527D01*
G01X-1066912Y702110D02*
Y694236D01*
G01X-1068049Y701795D02*
Y702110D01*
G01X-1068978Y663527D02*
Y674412D01*
G01X-1069087Y701795D02*
Y702110D01*
G01X-1069175Y664117D02*
Y673993D01*
G01X-1069274Y702110D02*
Y694236D01*
G01X-1069357Y674610D02*
Y697977D01*
G01X-1069360Y669432D02*
Y674309D01*
G01X-1069490Y669039D02*
Y665102D01*
G01X-1069741Y674409D02*
Y669406D01*
G01X-1069745Y674610D02*
Y697977D01*
G01X-1069932Y699707D02*
Y669432D01*
G01X-1069957Y697977D02*
Y675895D01*
G01X-1070122Y669432D02*
Y674309D01*
G01X-1070319Y699707D02*
Y669432D01*
G01X-1070344Y675616D02*
Y697977D01*
G01X-1070461Y699707D02*
Y669432D01*
G01X-1070849D02*
Y699707D01*
G01X-1072049Y670561D02*
Y665102D01*
G01X-1072364Y673993D02*
Y664117D01*
G01X-1072561Y674412D02*
Y663527D01*
G01X-1073211Y670364D02*
Y699707D01*
G01X-1073286Y669629D02*
Y669432D01*
G01X-1073329D02*
Y669039D01*
G01X-1073599Y699707D02*
Y670561D01*
G01X-1073741Y669826D02*
Y699707D01*
G01X-1073755Y675616D02*
Y697977D01*
G01X-1073978Y669064D02*
Y674309D01*
G01X-1074129Y669826D02*
Y699707D01*
G01X-1074143Y675895D02*
Y697977D01*
G01X-1074355D02*
Y674610D01*
G01X-1074740Y674309D02*
Y669826D01*
G01X-1074742Y697977D02*
Y674610D01*
G01X-1074798Y702110D02*
Y701795D01*
G01X-1075013D02*
Y702110D01*
G01X-1076051D02*
Y701795D01*
G01X-1076065Y663527D02*
Y675174D01*
G01X-1076076D02*
X-1076075Y664251D01*
G01X-1076198Y702110D02*
Y694236D01*
G01X-1076262Y675174D02*
Y664117D01*
G01X-1076577Y669039D02*
Y665102D01*
G01X-1076886Y699157D02*
Y675174D01*
G01X-1079136Y669039D02*
Y665102D01*
G01X-1079451Y675174D02*
Y664117D01*
G01X-1079648Y675174D02*
Y663527D01*
G01X-1059426Y699741D02*
Y699707D01*
G01X-1073599Y699741D02*
Y699707D01*
G01X-1059038Y699747D02*
Y699707D01*
G01X-1073212Y699747D02*
X-1073211Y699707D01*
G01X-1069957Y675895D02*
X-1069775Y674865D01*
G01X-1070163Y674587D02*
X-1070344Y675616D01*
G01X-1040608Y649473D02*
X-1040584Y649397D01*
G01X-1040731D02*
X-1040756Y649473D01*
G01X-1044496Y650377D02*
X-1044398Y650076D01*
G01X-1044152Y649297D02*
X-1044373Y649975D01*
G01X-1044250Y649196D02*
X-1044644Y650377D01*
G01X-1045514Y700381D02*
X-1046077Y701902D01*
G01X-1046451Y701795D02*
X-1045879Y700246D01*
G01X-1046666Y701795D02*
X-1045554Y698784D01*
G01X-1045918Y698650D02*
X-1047120Y701902D01*
G01X-1047330D02*
X-1046128Y698650D01*
G01X-1046492Y698515D02*
X-1047704Y701795D01*
G01X-1059688Y700381D02*
X-1060250Y701902D01*
G01X-1060624Y701795D02*
X-1060052Y700246D01*
G01X-1060839Y701795D02*
X-1059727Y698784D01*
G01X-1060091Y698650D02*
X-1061293Y701902D01*
G01X-1061503D02*
X-1060301Y698650D01*
G01X-1060666Y698515D02*
X-1061878Y701795D01*
G01X-1073861Y700381D02*
X-1074423Y701902D01*
G01X-1074798Y701795D02*
X-1074225Y700246D01*
G01X-1075013Y701795D02*
X-1073900Y698784D01*
G01X-1074264Y698650D02*
X-1075467Y701902D01*
G01X-1075677D02*
X-1074475Y698650D01*
G01X-1074839Y698515D02*
X-1076051Y701795D01*
G01X-1045085Y652917D02*
X-1043707Y650530D01*
G01X-1052172Y652917D02*
X-1050794Y650530D01*
G01X-1059259Y652917D02*
X-1057881Y650530D01*
G01X-1042060Y650377D02*
X-1041445Y649347D01*
G01X-1041519Y649196D02*
X-1042134Y650201D01*
G01X-1066345Y652917D02*
X-1064967Y650530D01*
G01X-1073432Y652917D02*
X-1072054Y650530D01*
G01X-1040658Y649297D02*
X-1040731Y649397D01*
G01X-1040584D02*
X-1040535Y649347D01*
G01X-1045194Y702110D02*
X-1043848Y700764D01*
G01X-1052280Y702110D02*
X-1050935Y700764D01*
G01X-1058022D02*
X-1059367Y702110D01*
G01X-1065108Y700764D02*
X-1066453Y702110D01*
G01X-1072195Y700764D02*
X-1073540Y702110D01*
G01X-1040559Y649221D02*
X-1040658Y649297D01*
G01X-1041853Y700381D02*
X-1041489Y700246D01*
G01X-1040914Y698515D02*
X-1041279Y698650D01*
G01X-1041489D02*
X-1041853Y698784D01*
G01X-1056026Y700381D02*
X-1055662Y700246D01*
G01X-1055088Y698515D02*
X-1055452Y698650D01*
G01X-1055662D02*
X-1056026Y698784D01*
G01X-1070199Y700381D02*
X-1069835Y700246D01*
G01X-1069261Y698515D02*
X-1069625Y698650D01*
G01X-1069835D02*
X-1070200Y698784D01*
G01X-1039702Y701795D02*
X-1040077Y701902D01*
G01X-1041291D02*
X-1040928Y701798D01*
G01X-1054250Y701902D02*
X-1053876Y701795D01*
G01X-1055464Y701902D02*
X-1055101Y701798D01*
G01X-1068423Y701902D02*
X-1068049Y701795D01*
G01X-1069637Y701902D02*
X-1069274Y701798D01*
G01X-1042502Y699747D02*
X-1042115Y699741D01*
G01X-1056676Y699747D02*
X-1056288Y699741D01*
G01X-1070849Y699747D02*
X-1070461Y699741D01*
G01X-1041647Y701902D02*
X-1041291D01*
G01X-1055820D02*
X-1055464D01*
G01X-1069993D02*
X-1069637D01*
G01X-1075467D02*
X-1075677D01*
G01X-1068423D02*
X-1068633D01*
G01X-1061293D02*
X-1061503D01*
G01X-1054250D02*
X-1054460D01*
G01X-1047120D02*
X-1047330D01*
G01X-1040077D02*
X-1040287D01*
G01X-1046077D02*
X-1045721D01*
G01X-1060250D02*
X-1059894D01*
G01X-1074423D02*
X-1074067D01*
G01X-1054914Y701795D02*
X-1068049D01*
G01X-1040741D02*
X-1053876D01*
G01X-1039485D02*
X-1039702D01*
G01X-1066912Y701622D02*
X-1069274D01*
G01X-1062024D02*
X-1066552D01*
G01X-1052739D02*
X-1055101D01*
G01X-1047851D02*
X-1052379D01*
G01X-1039485D02*
X-1040928D01*
G01X-1076066Y700764D02*
X-1079282D01*
G01X-1068980D02*
X-1073796D01*
G01X-1061893D02*
X-1065108D01*
G01X-1054806D02*
X-1059623D01*
G01X-1047720D02*
X-1050935D01*
G01X-1041224D02*
X-1045450D01*
G01X-1042013Y700381D02*
X-1041853D01*
G01X-1056186D02*
X-1056026D01*
G01X-1070359D02*
X-1070199D01*
G01X-1073701D02*
X-1073861D01*
G01X-1059528D02*
X-1059688D01*
G01X-1045355D02*
X-1045514D01*
G01X-1045782Y699707D02*
X-1044865D01*
G01X-1059956D02*
X-1059038D01*
G01X-1074129D02*
X-1073211D01*
G01X-1042503D02*
X-1041585D01*
G01X-1056676D02*
X-1055758D01*
G01X-1070849D02*
X-1069932D01*
G01X-1062713Y699157D02*
X-1066639D01*
G01X-1048540D02*
X-1052466D01*
G01X-1055452Y698650D02*
X-1055662D01*
G01X-1041279D02*
X-1041489D01*
G01X-1069625D02*
X-1069835D01*
G01X-1074264D02*
X-1074475D01*
G01X-1060091D02*
X-1060301D01*
G01X-1045918D02*
X-1046128D01*
G01X-1046396Y697977D02*
X-1045409D01*
G01X-1056171D02*
X-1055184D01*
G01X-1060569D02*
X-1059582D01*
G01X-1070344D02*
X-1069357D01*
G01X-1074742D02*
X-1073755D01*
G01X-1041011D02*
X-1041998D01*
G01X-1073212Y699747D02*
X-1073599Y699741D01*
G01X-1059038Y699747D02*
X-1059426Y699741D01*
G01X-1044865Y699747D02*
X-1045253Y699741D01*
G01X-1040535Y649347D02*
X-1040461Y649322D01*
G01X-1040436Y649196D02*
X-1040559Y649221D01*
G01X-1039485Y694235D02*
X-1040928D01*
G01X-1066912Y694236D02*
X-1069274D01*
G01X-1062024D02*
X-1066552D01*
G01X-1052739D02*
X-1055101D01*
G01X-1047851D02*
X-1052379D01*
G01X-1045797Y675895D02*
X-1041610D01*
G01X-1059970D02*
X-1055783D01*
G01X-1074143D02*
X-1069957D01*
G01X-1070344Y675616D02*
X-1073755D01*
G01X-1056171D02*
X-1059582D01*
G01X-1041998D02*
X-1045409D01*
G01X-1076065Y675174D02*
X-1079648D01*
G01X-1061892D02*
X-1065474D01*
G01X-1047718D02*
X-1051301D01*
G01X-1039157D02*
X-1039485D01*
G01X-1055572Y674610D02*
X-1055184D01*
G01X-1069745D02*
X-1069357D01*
G01X-1074355D02*
X-1074742D01*
G01X-1060181D02*
X-1060569D01*
G01X-1046008D02*
X-1046396D01*
G01X-1041011D02*
X-1041399D01*
G01X-1045590Y674587D02*
X-1041816D01*
G01X-1059764D02*
X-1055990D01*
G01X-1073937D02*
X-1070163D01*
G01X-1068978Y674412D02*
X-1072561D01*
G01X-1054805D02*
X-1058388D01*
G01X-1040632D02*
X-1044214D01*
G01X-1060567Y674309D02*
X-1055187D01*
G01X-1074740D02*
X-1069360D01*
G01X-1041013D02*
X-1046394D01*
G01X-1069175Y673993D02*
X-1072364D01*
G01X-1055002D02*
X-1058191D01*
G01X-1040829D02*
X-1044018D01*
G01X-1044214Y673743D02*
X-1040632D01*
G01X-1044069Y673330D02*
X-1040777D01*
G01X-1045253Y670561D02*
X-1043703D01*
G01X-1059426D02*
X-1057876D01*
G01X-1073599D02*
X-1072049D01*
G01X-1044865Y670364D02*
X-1043703D01*
G01X-1059038D02*
X-1057876D01*
G01X-1073211D02*
X-1072049D01*
G01Y669826D02*
X-1074740D01*
G01X-1057876D02*
X-1060567D01*
G01X-1043703D02*
X-1046394D01*
G01X-1044940Y669629D02*
X-1043703D01*
G01X-1059113D02*
X-1057876D01*
G01X-1073286D02*
X-1072049D01*
G01X-1045631Y669445D02*
X-1043703D01*
G01X-1059804D02*
X-1057876D01*
G01X-1073978D02*
X-1072049D01*
G01X-1043309Y669432D02*
X-1041537D01*
G01X-1076970D02*
X-1078742D01*
G01X-1072049D02*
X-1073329D01*
G01X-1069884D02*
X-1071655D01*
G01X-1069360D02*
X-1069490D01*
G01X-1062797D02*
X-1064569D01*
G01X-1055710D02*
X-1057482D01*
G01X-1057876D02*
X-1059156D01*
G01X-1055186D02*
X-1055317D01*
G01X-1048624D02*
X-1050396D01*
G01X-1043703D02*
X-1044983D01*
G01X-1041013D02*
X-1041144D01*
G01X-1041242Y669275D02*
X-1043604D01*
G01X-1045631Y669064D02*
X-1043703D01*
G01X-1059804D02*
X-1057876D01*
G01X-1073978D02*
X-1072049D01*
G01Y669039D02*
X-1073329D01*
G01X-1057876D02*
X-1059156D01*
G01X-1043703D02*
X-1044983D01*
G01X-1043604Y668417D02*
X-1041242D01*
G01X-1041144Y666936D02*
X-1039485D01*
G01X-1072049D02*
X-1076577D01*
G01X-1064962D02*
X-1069490D01*
G01X-1057876D02*
X-1062403D01*
G01X-1050789D02*
X-1055317D01*
G01X-1043703D02*
X-1048230D01*
G01X-1041242Y666913D02*
X-1043604D01*
G01X-1041144Y666739D02*
X-1039485D01*
G01X-1048230D02*
X-1043703D01*
G01X-1055317D02*
X-1050789D01*
G01X-1062403D02*
X-1057876D01*
G01X-1069490D02*
X-1064962D01*
G01X-1076577D02*
X-1072049D01*
G01X-1041242Y665338D02*
X-1043604D01*
G01X-1076577Y665102D02*
X-1079136D01*
G01X-1069490D02*
X-1072049D01*
G01X-1062403D02*
X-1064962D01*
G01X-1055317D02*
X-1057876D01*
G01X-1048230D02*
X-1050789D01*
G01X-1041144D02*
X-1043703D01*
G01X-1044214Y663606D02*
X-1040632D01*
G01X-1072561D02*
X-1068978D01*
G01X-1054805D02*
X-1058388D01*
G01X-1069087Y701795D02*
X-1068710Y701883D01*
G01X-1054914Y701795D02*
X-1054537Y701883D01*
G01X-1040741Y701795D02*
X-1040363Y701883D01*
G01X-1068710D02*
X-1068633Y701902D01*
G01X-1054537Y701883D02*
X-1054460Y701902D01*
G01X-1040363Y701883D02*
X-1040287Y701902D01*
G01X-1039157Y653921D02*
X-1040597D01*
G01X-1073432Y652917D02*
X-1074613D01*
G01X-1066345D02*
X-1067526D01*
G01X-1059259D02*
X-1060440D01*
G01X-1052172D02*
X-1053353D01*
G01X-1045085D02*
X-1046266D01*
G01X-1041445Y650377D02*
X-1041297D01*
G01X-1042282D02*
X-1042060D01*
G01X-1041100D02*
X-1040953D01*
G01X-1039993D02*
X-1039846D01*
G01X-1045136D02*
X-1044988D01*
G01X-1044644D02*
X-1044496D01*
G01X-1043807D02*
X-1043660D01*
G01X-1044398Y650076D02*
X-1043906D01*
G01X-1044373Y649975D02*
X-1043930D01*
G01X-1040436Y649850D02*
X-1039993D01*
G01Y649699D02*
X-1040461D01*
G01Y649322D02*
X-1039993D01*
G01X-1044988Y649196D02*
X-1045136D01*
G01X-1044053D02*
X-1044250D01*
G01X-1041297D02*
X-1041519D01*
G01X-1042134D02*
X-1042282D01*
G01X-1040953D02*
X-1041100D01*
G01X-1039846D02*
X-1040436D01*
G01X-1040559Y649824D02*
X-1040436Y649850D01*
G01X-1003468Y780456D02*
G03I-6889J0D01*
G01X-991657D02*
G03I-18700J0D01*
G01X-1010357Y784393D02*
Y807484D01*
G01X-1011538Y945810D02*
X-1043653D01*
G01X-1000712D02*
G03I-6889J0D01*
G01X-988901D02*
G03I-18700J0D01*
G01X-1030042Y1066928D02*
Y1272188D01*
G01X-1029627Y1064752D02*
G03X-1030042Y1062991I3522J-1759D01*
G01X-1029627Y1064752D02*
G03X-1030042Y1062991I3522J-1759D01*
G01X-1003218Y1023139D02*
X-1009452Y1026490D01*
G01X-1014045Y1034196D02*
X-1012077D01*
G01X-1025200D02*
X-1023231D01*
G01Y1027830D02*
X-1014045D01*
G01Y1025820D02*
X-1023231D01*
G01Y1018448D02*
X-1025200D01*
G01X-1012077D02*
X-1014045D01*
G01X-951381Y1003330D02*
X-1030042D01*
G01X-1012077Y1034196D02*
Y1018448D01*
G01X-1014045Y1027830D02*
Y1034196D01*
G01Y1018448D02*
Y1025820D01*
G01X-1023231D02*
Y1018448D01*
G01Y1034196D02*
Y1027830D01*
G01X-1025200Y1018448D02*
Y1034196D01*
G01X-1011446Y1101114D02*
X-1029627Y1064752D01*
G01X-1011446Y1101114D02*
X-1029627Y1064752D01*
G01X-1009452Y1026490D02*
X-1003218Y1029840D01*
G01X-989885Y1079669D02*
X-1076550D01*
G01X-1007924Y1103291D02*
G03X-1011445Y1101115I0J-3937D01*
G01X-1007924Y1103291D02*
G03X-1011445Y1101115I0J-3937D01*
G01X-1010357Y1103291D02*
X-755633D01*
G01X-1018653Y1463291D02*
Y1444354D01*
G01X-995261Y-643706D02*
X-662374D01*
G01X-998410D02*
X-995261D01*
G01X-969127Y76964D02*
G03I-18701J0D01*
G01X-980938D02*
G03I-6890J0D01*
G01X-990160Y555609D02*
X-991473Y554939D01*
G01Y557620D02*
X-989504Y558290D01*
G01X-1000003Y555609D02*
X-1001972Y554939D01*
G01Y557620D02*
X-1000003Y558290D01*
G01X-991473Y554939D02*
X-992129Y554269D01*
G01X-993441Y555609D02*
X-991473Y557620D01*
G01X-1001972Y554939D02*
X-1003284Y553599D01*
G01Y556280D02*
X-1001972Y557620D01*
G01X-992129Y554269D02*
X-992785Y552929D01*
G01X-939098Y557031D02*
Y978291D01*
G01X-982286Y552929D02*
Y536846D01*
G01X-985567D02*
Y552929D01*
G01X-992785D02*
Y536846D01*
G01X-996066D02*
Y552929D01*
G01X-1003284Y553599D02*
Y536846D01*
G01Y558290D02*
Y556280D01*
G01X-1006565Y536846D02*
Y558290D01*
G01X-983599Y556280D02*
X-982286Y552929D01*
G01X-985567D02*
X-986223Y554269D01*
G01X-996066Y552929D02*
X-996722Y554269D01*
G01X-984911Y557620D02*
X-983599Y556280D01*
G01X-986223Y554269D02*
X-986880Y554939D01*
G01X-995410Y557620D02*
X-993441Y555609D01*
G01X-996722Y554269D02*
X-997378Y554939D01*
G01X-986880D02*
X-988192Y555609D01*
G01X-997378Y554939D02*
X-998691Y555609D01*
G01X-986880Y558290D02*
X-984911Y557620D01*
G01X-997378Y558290D02*
X-995410Y557620D01*
G01X-989504Y558290D02*
X-986880D01*
G01X-1000003D02*
X-997378D01*
G01X-1006565D02*
X-1003284D01*
G01X-939098Y557031D02*
X-915478D01*
G01X-998691Y555609D02*
X-1000003D01*
G01X-988192D02*
X-990160D01*
G01X-1003284Y536846D02*
X-1006565D01*
G01X-992785D02*
X-996066D01*
G01X-982286D02*
X-985567D01*
G01X-835141Y659743D02*
G03I-53481J0D01*
G01X-1006420Y780456D02*
X-986932D01*
G01X-928347Y726266D02*
X-940158D01*
G01X-1007601Y941873D02*
Y915645D01*
G01X-939098Y978291D02*
X-746184D01*
G01X-967247Y1079669D02*
G03I-18701J0D01*
G01X-958599Y1028835D02*
X-957943Y1028165D01*
G01X-959255Y1027160D02*
X-959583Y1027495D01*
G01X-963848Y1028835D02*
X-962864Y1027830D01*
G01X-957943Y1028165D02*
X-957286Y1026490D01*
G01X-972706Y1028165D02*
X-972050Y1026490D01*
G01X-958927D02*
X-959255Y1027160D01*
G01X-964176Y1026490D02*
X-964504Y1027160D01*
G01X-973691Y1026490D02*
X-974019Y1027160D01*
G01X-978940Y1026490D02*
X-979268Y1027160D01*
G01X-1003218Y1029840D02*
X-1002562Y1028835D01*
G01X-964504Y1027160D02*
X-964832Y1027495D01*
G01X-973363Y1028835D02*
X-972706Y1028165D01*
G01X-974019Y1027160D02*
X-974347Y1027495D01*
G01X-978612Y1028835D02*
X-977628Y1027830D01*
G01X-979268Y1027160D02*
X-979596Y1027495D01*
G01X-959583D02*
X-960239Y1027830D01*
G01X-964832Y1027495D02*
X-965489Y1027830D01*
G01X-974347Y1027495D02*
X-975003Y1027830D01*
G01X-979596Y1027495D02*
X-980252Y1027830D01*
G01X-1007155Y1026490D02*
X-1002562Y1024144D01*
G01X-959583Y1029170D02*
X-958599Y1028835D01*
G01X-964832Y1029170D02*
X-963848Y1028835D01*
G01X-974347Y1029170D02*
X-973363Y1028835D01*
G01X-979596Y1029170D02*
X-978612Y1028835D01*
G01X-992063Y1034196D02*
X-990095D01*
G01X-960895Y1029170D02*
X-959583D01*
G01X-966145D02*
X-964832D01*
G01X-969426D02*
X-967785D01*
G01X-975659D02*
X-974347D01*
G01X-980909D02*
X-979596D01*
G01X-984189D02*
X-982549D01*
G01X-980252Y1027830D02*
X-980909D01*
G01X-975003D02*
X-975987D01*
G01X-965489D02*
X-966145D01*
G01X-960239D02*
X-961223D01*
G01X-990095Y1025149D02*
X-986814D01*
G01X-992063D02*
X-997641D01*
G01X-992063Y1023139D02*
X-999937D01*
G01X-986814D02*
X-990095D01*
G01Y1018448D02*
X-992063D01*
G01X-982549D02*
X-984189D01*
G01X-977300D02*
X-978940D01*
G01X-972050D02*
X-973691D01*
G01X-967785D02*
X-969426D01*
G01X-962536D02*
X-964176D01*
G01X-957286D02*
X-958927D01*
G01X-951381Y1103291D02*
Y1003330D01*
G01X-957286Y1026490D02*
Y1018448D01*
G01X-958927D02*
Y1026490D01*
G01X-962536D02*
Y1018448D01*
G01X-964176D02*
Y1026490D01*
G01X-967785Y1026825D02*
Y1018448D01*
G01Y1029170D02*
Y1028165D01*
G01X-969426Y1018448D02*
Y1029170D01*
G01X-972050Y1026490D02*
Y1018448D01*
G01X-973691D02*
Y1026490D01*
G01X-977300D02*
Y1018448D01*
G01X-978940D02*
Y1026490D01*
G01X-982549Y1026825D02*
Y1018448D01*
G01Y1029170D02*
Y1028165D01*
G01X-984189Y1018448D02*
Y1029170D01*
G01X-986814Y1025149D02*
Y1023139D01*
G01X-990095D02*
Y1018448D01*
G01Y1034196D02*
Y1025149D01*
G01X-992063Y1018448D02*
Y1023139D01*
G01Y1031516D02*
Y1025149D01*
G01X-999937Y1023139D02*
Y1025149D01*
G01X-962208Y1027160D02*
X-962536Y1026490D01*
G01X-976972Y1027160D02*
X-977300Y1026490D01*
G01X-1002562Y1024144D02*
X-1003218Y1023139D01*
G01X-961880Y1027495D02*
X-962208Y1027160D01*
G01X-962864Y1027830D02*
X-961880Y1028835D01*
G01X-967129Y1027495D02*
X-967785Y1026825D01*
G01Y1028165D02*
X-967129Y1028835D01*
G01X-976643Y1027495D02*
X-976972Y1027160D01*
G01X-977628Y1027830D02*
X-976643Y1028835D01*
G01X-981893Y1027495D02*
X-982549Y1026825D01*
G01Y1028165D02*
X-981893Y1028835D01*
G01X-997641Y1025149D02*
X-992063Y1031516D01*
G01X-999937Y1025149D02*
X-992063Y1034196D01*
G01X-961880Y1028835D02*
X-960895Y1029170D01*
G01X-966145Y1027830D02*
X-967129Y1027495D01*
G01Y1028835D02*
X-966145Y1029170D01*
G01X-961223Y1027830D02*
X-961880Y1027495D01*
G01X-975987Y1027830D02*
X-976643Y1027495D01*
G01X-1002562Y1028835D02*
X-1007155Y1026490D01*
G01X-976643Y1028835D02*
X-975659Y1029170D01*
G01X-980909Y1027830D02*
X-981893Y1027495D01*
G01Y1028835D02*
X-980909Y1029170D01*
G01X-985948Y1083606D02*
Y1272188D01*
G01X-979058Y1079669D02*
G03I-6890J0D01*
G01X-1007924Y1103291D02*
X-755633D01*
G01X-887434Y-442524D02*
G03X-900032I-6299J0D01*
G01Y-448824D02*
G03X-887434I6299J0D01*
G01X-875032Y-445674D02*
G03I-18701J0D01*
G01X-887434Y-442524D02*
Y-448824D01*
G01X-900032Y-442524D02*
Y-448824D01*
G01X-887434Y-324414D02*
G03X-900032I-6299J0D01*
G01Y-330713D02*
G03X-887434I6299J0D01*
G01X-875032Y-327564D02*
G03I-18701J0D01*
G01X-887434Y-324414D02*
Y-330713D01*
G01X-900032Y-324414D02*
Y-330713D01*
G01X-885554Y560180D02*
G03X-898153I-6299J0D01*
G01Y553881D02*
G03X-885554I6300J0D01*
G01X-868234Y557031D02*
G03X-915478I-23622J0D01*
G01X-868231D02*
G03X-915475I-23622J0D01*
G01X-867442Y555000D02*
G03I-27504J0D01*
G01X-878113Y521131D02*
X-878441Y520964D01*
G01X-885495Y521131D02*
X-885823Y520964D01*
G01X-892877Y516608D02*
X-892057Y517110D01*
G01X-893041Y517445D02*
X-892549Y517781D01*
G01X-894681Y523309D02*
X-895174Y522974D01*
G01X-878441Y520964D02*
X-878605Y520796D01*
G01X-878933Y521131D02*
X-878441Y521634D01*
G01X-881066Y520964D02*
X-881394Y520629D01*
G01Y521299D02*
X-881066Y521634D01*
G01X-885823Y520964D02*
X-885987Y520796D01*
G01X-886315Y521131D02*
X-885823Y521634D01*
G01X-892057Y517110D02*
X-891565Y517613D01*
G01X-888448Y520964D02*
X-888776Y520629D01*
G01Y521299D02*
X-888448Y521634D01*
G01X-878441D02*
X-877949Y521801D01*
G01X-880574Y521131D02*
X-881066Y520964D01*
G01Y521634D02*
X-880574Y521801D01*
G01X-885823Y521634D02*
X-885331Y521801D01*
G01X-887956Y521131D02*
X-888448Y520964D01*
G01Y521634D02*
X-887956Y521801D01*
G01X-894846Y524147D02*
X-895666Y523644D01*
G01D02*
X-896158Y523142D01*
G01X-892549Y517781D02*
X-891893Y518786D01*
G01X-895174Y522974D02*
X-895830Y521969D01*
G01X-878605Y520796D02*
X-878769Y520461D01*
G01X-885987Y520796D02*
X-886151Y520461D01*
G01X-891565Y517613D02*
X-891237Y518283D01*
G01X-896158Y523142D02*
X-896486Y522471D01*
G01X-891237Y518283D02*
X-891073Y518786D01*
G01X-896486Y522471D02*
X-896650Y521969D01*
G01X-891073Y518786D02*
X-890909Y519623D01*
G01X-896650Y521969D02*
X-896814Y521131D01*
G01X-891893Y518786D02*
X-891729Y519791D01*
G01X-895830Y521969D02*
X-895994Y520964D01*
G01X-868231Y557031D02*
Y513724D01*
G01X-876145Y520461D02*
Y516440D01*
G01X-876965D02*
Y520461D01*
G01X-878769D02*
Y516440D01*
G01X-879590D02*
Y520461D01*
G01X-881394Y520629D02*
Y516440D01*
G01Y521801D02*
Y521299D01*
G01X-882214Y516440D02*
Y521801D01*
G01X-883527Y520461D02*
Y516440D01*
G01X-884347D02*
Y520461D01*
G01X-885554Y560180D02*
Y553881D01*
G01X-886151Y520461D02*
Y516440D01*
G01X-886972D02*
Y520461D01*
G01X-888776Y520629D02*
Y516440D01*
G01Y521801D02*
Y521299D01*
G01X-889596Y516440D02*
Y521801D01*
G01X-890909Y519623D02*
Y521131D01*
G01X-891729Y519791D02*
Y520964D01*
G01X-895994D02*
Y519791D01*
G01X-896814Y521131D02*
Y519623D01*
G01X-898126Y519791D02*
Y519121D01*
G01Y521801D02*
Y521131D01*
G01X-898153Y560180D02*
Y553881D01*
G01X-900751Y519121D02*
Y519791D01*
G01Y521131D02*
Y521801D01*
G01X-902063Y524314D02*
Y516440D01*
G01X-903048Y521131D02*
Y524314D01*
G01Y516440D02*
Y520126D01*
G01X-907641D02*
Y516440D01*
G01Y524314D02*
Y521131D01*
G01X-908625Y516440D02*
Y524314D01*
G01X-915475Y513724D02*
Y557031D01*
G01X-891729Y520964D02*
X-891893Y521969D01*
G01X-895994Y519791D02*
X-895830Y518786D01*
G01X-890909Y521131D02*
X-891073Y521969D01*
G01X-896814Y519623D02*
X-896650Y518786D01*
G01X-891073Y521969D02*
X-891237Y522471D01*
G01X-896650Y518786D02*
X-896486Y518283D01*
G01X-876473Y521299D02*
X-876145Y520461D01*
G01X-883855Y521299D02*
X-883527Y520461D01*
G01X-876965D02*
X-877129Y520796D01*
G01X-879590Y520461D02*
X-879754Y520796D01*
G01X-884347Y520461D02*
X-884511Y520796D01*
G01X-886972Y520461D02*
X-887136Y520796D01*
G01X-891237Y522471D02*
X-891565Y523142D01*
G01X-896486Y518283D02*
X-896158Y517613D01*
G01X-891893Y521969D02*
X-892549Y522974D01*
G01X-895830Y518786D02*
X-895174Y517781D01*
G01X-876801Y521634D02*
X-876473Y521299D01*
G01X-877129Y520796D02*
X-877293Y520964D01*
G01X-879426Y521634D02*
X-878933Y521131D01*
G01X-879754Y520796D02*
X-879918Y520964D01*
G01X-884183Y521634D02*
X-883855Y521299D01*
G01X-884511Y520796D02*
X-884675Y520964D01*
G01X-886807Y521634D02*
X-886315Y521131D01*
G01X-887136Y520796D02*
X-887300Y520964D01*
G01X-891565Y523142D02*
X-892057Y523644D01*
G01X-896158Y517613D02*
X-895666Y517110D01*
G01X-892549Y522974D02*
X-893041Y523309D01*
G01X-895174Y517781D02*
X-894681Y517445D01*
G01X-892057Y523644D02*
X-892877Y524147D01*
G01X-895666Y517110D02*
X-894846Y516608D01*
G01X-877293Y520964D02*
X-877621Y521131D01*
G01X-879918Y520964D02*
X-880246Y521131D01*
G01X-884675Y520964D02*
X-885003Y521131D01*
G01X-887300Y520964D02*
X-887628Y521131D01*
G01X-877293Y521801D02*
X-876801Y521634D01*
G01X-879918Y521801D02*
X-879426Y521634D01*
G01X-884675Y521801D02*
X-884183Y521634D01*
G01X-887300Y521801D02*
X-886807Y521634D01*
G01X-893041Y523309D02*
X-893861Y523477D01*
G01X-894681Y517445D02*
X-893861Y517278D01*
G01X-892877Y524147D02*
X-893861Y524314D01*
G01X-894846Y516608D02*
X-893861Y516440D01*
G01X-868234Y557031D02*
X-817053D01*
G01X-903048Y524314D02*
X-902063D01*
G01X-908625D02*
X-907641D01*
G01X-877949Y521801D02*
X-877293D01*
G01X-880574D02*
X-879918D01*
G01X-882214D02*
X-881394D01*
G01X-885331D02*
X-884675D01*
G01X-887956D02*
X-887300D01*
G01X-889596D02*
X-888776D01*
G01X-900751D02*
X-898126D01*
G01X-907641Y521131D02*
X-903048D01*
G01X-898126D02*
X-900751D01*
G01X-887628D02*
X-887956D01*
G01X-885003D02*
X-885495D01*
G01X-880246D02*
X-880574D01*
G01X-877621D02*
X-878113D01*
G01X-903048Y520126D02*
X-907641D01*
G01X-900751Y519791D02*
X-898126D01*
G01Y519121D02*
X-900751D01*
G01X-907641Y516440D02*
X-908625D01*
G01X-902063D02*
X-903048D01*
G01X-888776D02*
X-889596D01*
G01X-886151D02*
X-886972D01*
G01X-883527D02*
X-884347D01*
G01X-881394D02*
X-882214D01*
G01X-878769D02*
X-879590D01*
G01X-876145D02*
X-876965D01*
G01X-868231Y513724D02*
X-915475D01*
G01X-893861Y524314D02*
X-894846Y524147D01*
G01X-893861Y516440D02*
X-892877Y516608D01*
G01X-893861Y523477D02*
X-894681Y523309D01*
G01X-893861Y517278D02*
X-893041Y517445D01*
G01X-888828Y636717D02*
X-888336Y637219D01*
G01X-889649Y636214D02*
X-888828Y636717D01*
G01X-889813Y637052D02*
X-889321Y637387D01*
G01D02*
X-888664Y638392D01*
G01X-888336Y637219D02*
X-888008Y637889D01*
G01X-868231Y675141D02*
Y631834D01*
G01X-872916Y640067D02*
Y636047D01*
G01X-873737D02*
Y640067D01*
G01X-875541D02*
Y636047D01*
G01X-876361D02*
Y640067D01*
G01X-878166Y640235D02*
Y636047D01*
G01X-878986D02*
Y641408D01*
G01X-880298Y640067D02*
Y636047D01*
G01X-881118D02*
Y640067D01*
G01X-882923D02*
Y636047D01*
G01X-883743D02*
Y640067D01*
G01X-885548Y640235D02*
Y636047D01*
G01X-886368D02*
Y641408D01*
G01X-898835Y643921D02*
Y636047D01*
G01X-899819D02*
Y639732D01*
G01X-904412D02*
Y636047D01*
G01X-905397D02*
Y643921D01*
G01X-915475Y631834D02*
Y675141D01*
G01X-893258Y637889D02*
X-892930Y637219D01*
G01X-892601Y638392D02*
X-891945Y637387D01*
G01X-892930Y637219D02*
X-892437Y636717D01*
G01X-891945Y637387D02*
X-891453Y637052D01*
G01X-892437Y636717D02*
X-891617Y636214D01*
G01X-891453Y637052D02*
X-890633Y636884D01*
G01X-891617Y636214D02*
X-890633Y636047D01*
G01X-904412D02*
X-905397D01*
G01X-898835D02*
X-899819D01*
G01X-885548D02*
X-886368D01*
G01X-882923D02*
X-883743D01*
G01X-880298D02*
X-881118D01*
G01X-878166D02*
X-878986D01*
G01X-875541D02*
X-876361D01*
G01X-872916D02*
X-873737D01*
G01X-868231Y631834D02*
X-915475D01*
G01X-890633Y636047D02*
X-889649Y636214D01*
G01X-890633Y636884D02*
X-889813Y637052D01*
G01X-872698Y571172D02*
X-639037Y616661D01*
G01X-891853Y675928D02*
Y794919D01*
G01X-885554Y678291D02*
G03X-898153I-6299J0D01*
G01Y671991D02*
G03X-885554I6300J0D01*
G01X-868231Y675141D02*
G03X-915475I-23622J0D01*
G01X-875213Y640570D02*
X-875377Y640402D01*
G01X-875705Y640737D02*
X-875213Y641240D01*
G01X-877838Y640570D02*
X-878166Y640235D01*
G01Y640905D02*
X-877838Y641240D01*
G01X-882595Y640570D02*
X-882759Y640402D01*
G01X-883087Y640737D02*
X-882595Y641240D01*
G01X-885220Y640570D02*
X-885548Y640235D01*
G01Y640905D02*
X-885220Y641240D01*
G01X-875377Y640402D02*
X-875541Y640067D01*
G01X-874885Y640737D02*
X-875213Y640570D01*
G01X-882267Y640737D02*
X-882595Y640570D01*
G01X-891617Y643753D02*
X-892437Y643250D01*
G01X-891453Y642915D02*
X-891945Y642580D01*
G01X-892437Y643250D02*
X-892930Y642748D01*
G01X-891945Y642580D02*
X-892601Y641575D01*
G01X-882759Y640402D02*
X-882923Y640067D01*
G01X-892930Y642748D02*
X-893258Y642078D01*
G01X-888008Y637889D02*
X-887844Y638392D01*
G01X-893258Y642078D02*
X-893422Y641575D01*
G01X-875213Y641240D02*
X-874721Y641408D01*
G01X-877346Y640737D02*
X-877838Y640570D01*
G01Y641240D02*
X-877346Y641408D01*
G01X-882595Y641240D02*
X-882103Y641408D01*
G01X-884727Y640737D02*
X-885220Y640570D01*
G01Y641240D02*
X-884727Y641408D01*
G01X-887844Y638392D02*
X-887680Y639230D01*
G01X-893422Y641575D02*
X-893586Y640737D01*
G01X-888664Y638392D02*
X-888500Y639397D01*
G01X-892601Y641575D02*
X-892765Y640570D01*
G01X-878166Y641408D02*
Y640905D01*
G01X-885548Y641408D02*
Y640905D01*
G01X-885554Y678291D02*
Y671991D01*
G01X-887680Y639230D02*
Y640737D01*
G01X-888500Y639397D02*
Y640570D01*
G01D02*
X-888664Y641575D01*
G01X-892765Y640570D02*
Y639397D01*
G01X-893586Y640737D02*
Y639230D01*
G01X-894898Y639397D02*
Y638727D01*
G01Y641408D02*
Y640737D01*
G01X-897523Y638727D02*
Y639397D01*
G01Y640737D02*
Y641408D01*
G01X-898153Y678291D02*
Y671991D01*
G01X-899819Y640737D02*
Y643921D01*
G01X-904412D02*
Y640737D01*
G01X-892765Y639397D02*
X-892601Y638392D01*
G01X-887680Y640737D02*
X-887844Y641575D01*
G01X-893586Y639230D02*
X-893422Y638392D01*
G01X-887844Y641575D02*
X-888008Y642078D01*
G01X-873244Y640905D02*
X-872916Y640067D01*
G01X-893422Y638392D02*
X-893258Y637889D01*
G01X-880626Y640905D02*
X-880298Y640067D01*
G01X-873737D02*
X-873901Y640402D01*
G01X-876361Y640067D02*
X-876525Y640402D01*
G01X-881118Y640067D02*
X-881283Y640402D01*
G01X-883743Y640067D02*
X-883907Y640402D01*
G01X-888008Y642078D02*
X-888336Y642748D01*
G01X-888664Y641575D02*
X-889321Y642580D01*
G01X-873573Y641240D02*
X-873244Y640905D01*
G01X-873901Y640402D02*
X-874065Y640570D01*
G01X-876197Y641240D02*
X-875705Y640737D01*
G01X-876525Y640402D02*
X-876689Y640570D01*
G01X-880954Y641240D02*
X-880626Y640905D01*
G01X-881283Y640402D02*
X-881447Y640570D01*
G01X-883579Y641240D02*
X-883087Y640737D01*
G01X-883907Y640402D02*
X-884071Y640570D01*
G01X-888336Y642748D02*
X-888828Y643250D01*
G01X-889321Y642580D02*
X-889813Y642915D01*
G01X-888828Y643250D02*
X-889649Y643753D01*
G01X-874065Y640570D02*
X-874393Y640737D01*
G01X-876689Y640570D02*
X-877017Y640737D01*
G01X-881447Y640570D02*
X-881775Y640737D01*
G01X-884071Y640570D02*
X-884399Y640737D01*
G01X-874065Y641408D02*
X-873573Y641240D01*
G01X-876689Y641408D02*
X-876197Y641240D01*
G01X-881447Y641408D02*
X-880954Y641240D01*
G01X-884071Y641408D02*
X-883579Y641240D01*
G01X-889813Y642915D02*
X-890633Y643083D01*
G01X-889649Y643753D02*
X-890633Y643921D01*
G01X-899819D02*
X-898835D01*
G01X-905397D02*
X-904412D01*
G01X-874721Y641408D02*
X-874065D01*
G01X-877346D02*
X-876689D01*
G01X-878986D02*
X-878166D01*
G01X-882103D02*
X-881447D01*
G01X-884727D02*
X-884071D01*
G01X-886368D02*
X-885548D01*
G01X-897523D02*
X-894898D01*
G01X-904412Y640737D02*
X-899819D01*
G01X-894898D02*
X-897523D01*
G01X-884399D02*
X-884727D01*
G01X-881775D02*
X-882267D01*
G01X-877017D02*
X-877346D01*
G01X-874393D02*
X-874885D01*
G01X-899819Y639732D02*
X-904412D01*
G01X-897523Y639397D02*
X-894898D01*
G01Y638727D02*
X-897523D01*
G01X-890633Y643921D02*
X-891617Y643753D01*
G01X-890633Y643083D02*
X-891453Y642915D01*
G01X-916042Y705660D02*
X-928347Y726266D01*
G01X-862310Y750253D02*
X-865263Y746735D01*
G01Y750756D02*
X-862310Y754273D01*
G01X-869199Y739197D02*
X-870183Y737689D01*
G01X-865263Y746735D02*
Y750756D01*
G01X-883470Y754273D02*
Y730654D01*
G01X-886422Y744725D02*
Y754273D01*
G01Y730654D02*
Y741710D01*
G01X-869199Y746233D02*
X-876088Y742715D01*
G01X-879533D02*
X-870183Y747740D01*
G01X-900200Y741710D02*
Y730654D01*
G01Y754273D02*
Y744725D01*
G01X-903153Y730654D02*
Y754273D01*
G01X-870183Y747740D02*
X-869199Y746233D01*
G01X-870183Y737689D02*
X-879533Y742715D01*
G01X-876088D02*
X-869199Y739197D01*
G01X-886422Y754273D02*
X-883470D01*
G01X-903153D02*
X-900200D01*
G01Y744725D02*
X-886422D01*
G01Y741710D02*
X-900200D01*
G01Y730654D02*
X-903153D01*
G01X-883470D02*
X-886422D01*
G01X-926936Y986671D02*
X-926932Y986643D01*
G01X-926947Y986697D02*
X-926936Y986671D01*
G01X-926965Y986721D02*
X-926947Y986697D01*
G01X-926990Y986742D02*
X-926965Y986721D01*
G01X-927020Y986760D02*
X-926990Y986742D01*
G01X-927054Y986773D02*
X-927020Y986760D01*
G01X-927091Y986781D02*
X-927054Y986773D01*
G01X-927129Y986783D02*
X-927091Y986781D01*
G01X-924968Y986671D02*
X-924964Y986643D01*
G01X-924979Y986697D02*
X-924968Y986671D01*
G01X-924997Y986721D02*
X-924979Y986697D01*
G01X-925021Y986742D02*
X-924997Y986721D01*
G01X-925052Y986760D02*
X-925021Y986742D01*
G01X-925085Y986773D02*
X-925052Y986760D01*
G01X-925122Y986781D02*
X-925085Y986773D01*
G01X-925160Y986783D02*
X-925122Y986781D01*
G01X-922999Y986671D02*
X-922995Y986643D01*
G01X-923010Y986697D02*
X-922999Y986671D01*
G01X-923028Y986721D02*
X-923010Y986697D01*
G01X-923053Y986742D02*
X-923028Y986721D01*
G01X-923083Y986760D02*
X-923053Y986742D01*
G01X-923117Y986773D02*
X-923083Y986760D01*
G01X-923154Y986781D02*
X-923117Y986773D01*
G01X-923192Y986783D02*
X-923154Y986781D01*
G01X-921031Y986671D02*
X-921027Y986643D01*
G01X-921042Y986697D02*
X-921031Y986671D01*
G01X-921060Y986721D02*
X-921042Y986697D01*
G01X-921084Y986742D02*
X-921060Y986721D01*
G01X-921115Y986760D02*
X-921084Y986742D01*
G01X-921148Y986773D02*
X-921115Y986760D01*
G01X-921185Y986781D02*
X-921148Y986773D01*
G01X-921223Y986783D02*
X-921185Y986781D01*
G01X-919062Y986671D02*
X-919058Y986643D01*
G01X-919073Y986697D02*
X-919062Y986671D01*
G01X-919091Y986721D02*
X-919073Y986697D01*
G01X-919116Y986742D02*
X-919091Y986721D01*
G01X-919146Y986760D02*
X-919116Y986742D01*
G01X-919180Y986773D02*
X-919146Y986760D01*
G01X-919217Y986781D02*
X-919180Y986773D01*
G01X-919255Y986783D02*
X-919217Y986781D01*
G01X-917094Y986671D02*
X-917090Y986643D01*
G01X-917105Y986697D02*
X-917094Y986671D01*
G01X-917123Y986721D02*
X-917105Y986697D01*
G01X-917147Y986742D02*
X-917123Y986721D01*
G01X-917178Y986760D02*
X-917147Y986742D01*
G01X-917211Y986773D02*
X-917178Y986760D01*
G01X-917248Y986781D02*
X-917211Y986773D01*
G01X-917286Y986783D02*
X-917248Y986781D01*
G01X-915125Y986671D02*
X-915121Y986643D01*
G01X-915136Y986697D02*
X-915125Y986671D01*
G01X-915154Y986721D02*
X-915136Y986697D01*
G01X-915179Y986742D02*
X-915154Y986721D01*
G01X-915209Y986760D02*
X-915179Y986742D01*
G01X-915243Y986773D02*
X-915209Y986760D01*
G01X-915280Y986781D02*
X-915243Y986773D01*
G01X-915318Y986783D02*
X-915280Y986781D01*
G01X-913157Y986671D02*
X-913153Y986643D01*
G01X-913168Y986697D02*
X-913157Y986671D01*
G01X-913186Y986721D02*
X-913168Y986697D01*
G01X-913210Y986742D02*
X-913186Y986721D01*
G01X-913241Y986760D02*
X-913210Y986742D01*
G01X-913274Y986773D02*
X-913241Y986760D01*
G01X-913311Y986781D02*
X-913274Y986773D01*
G01X-913349Y986783D02*
X-913311Y986781D01*
G01X-911188Y986671D02*
X-911184Y986643D01*
G01X-911199Y986697D02*
X-911188Y986671D01*
G01X-911217Y986721D02*
X-911199Y986697D01*
G01X-911242Y986742D02*
X-911217Y986721D01*
G01X-911272Y986760D02*
X-911242Y986742D01*
G01X-911306Y986773D02*
X-911272Y986760D01*
G01X-911343Y986781D02*
X-911306Y986773D01*
G01X-911381Y986783D02*
X-911343Y986781D01*
G01X-909219Y986671D02*
X-909216Y986643D01*
G01X-909231Y986697D02*
X-909219Y986671D01*
G01X-909249Y986721D02*
X-909231Y986697D01*
G01X-909273Y986742D02*
X-909249Y986721D01*
G01X-909304Y986760D02*
X-909273Y986742D01*
G01X-909337Y986773D02*
X-909304Y986760D01*
G01X-909374Y986781D02*
X-909337Y986773D01*
G01X-909412Y986783D02*
X-909374Y986781D01*
G01X-907251Y986671D02*
X-907247Y986643D01*
G01X-907262Y986697D02*
X-907251Y986671D01*
G01X-907280Y986721D02*
X-907262Y986697D01*
G01X-907305Y986742D02*
X-907280Y986721D01*
G01X-907335Y986760D02*
X-907305Y986742D01*
G01X-907369Y986773D02*
X-907335Y986760D01*
G01X-907406Y986781D02*
X-907369Y986773D01*
G01X-907444Y986783D02*
X-907406Y986781D01*
G01X-905282Y986671D02*
X-905279Y986643D01*
G01X-905294Y986697D02*
X-905282Y986671D01*
G01X-905312Y986721D02*
X-905294Y986697D01*
G01X-905336Y986742D02*
X-905312Y986721D01*
G01X-905367Y986760D02*
X-905336Y986742D01*
G01X-905400Y986773D02*
X-905367Y986760D01*
G01X-905437Y986781D02*
X-905400Y986773D01*
G01X-905475Y986783D02*
X-905437Y986781D01*
G01X-903314Y986671D02*
X-903310Y986643D01*
G01X-903325Y986697D02*
X-903314Y986671D01*
G01X-903343Y986721D02*
X-903325Y986697D01*
G01X-903368Y986742D02*
X-903343Y986721D01*
G01X-903398Y986760D02*
X-903368Y986742D01*
G01X-903432Y986773D02*
X-903398Y986760D01*
G01X-903469Y986781D02*
X-903432Y986773D01*
G01X-903507Y986783D02*
X-903469Y986781D01*
G01X-901345Y986671D02*
X-901342Y986643D01*
G01X-901357Y986697D02*
X-901345Y986671D01*
G01X-901375Y986721D02*
X-901357Y986697D01*
G01X-901399Y986742D02*
X-901375Y986721D01*
G01X-901430Y986760D02*
X-901399Y986742D01*
G01X-901463Y986773D02*
X-901430Y986760D01*
G01X-901500Y986781D02*
X-901463Y986773D01*
G01X-901538Y986783D02*
X-901500Y986781D01*
G01X-899377Y986671D02*
X-899373Y986643D01*
G01X-899388Y986697D02*
X-899377Y986671D01*
G01X-899406Y986721D02*
X-899388Y986697D01*
G01X-899431Y986742D02*
X-899406Y986721D01*
G01X-899461Y986760D02*
X-899431Y986742D01*
G01X-899495Y986773D02*
X-899461Y986760D01*
G01X-899532Y986781D02*
X-899495Y986773D01*
G01X-899570Y986783D02*
X-899532Y986781D01*
G01X-897408Y986671D02*
X-897405Y986643D01*
G01X-897420Y986697D02*
X-897408Y986671D01*
G01X-897438Y986721D02*
X-897420Y986697D01*
G01X-897462Y986742D02*
X-897438Y986721D01*
G01X-897493Y986760D02*
X-897462Y986742D01*
G01X-897526Y986773D02*
X-897493Y986760D01*
G01X-897563Y986781D02*
X-897526Y986773D01*
G01X-897601Y986783D02*
X-897563Y986781D01*
G01X-895440Y986671D02*
X-895436Y986643D01*
G01X-895451Y986697D02*
X-895440Y986671D01*
G01X-895469Y986721D02*
X-895451Y986697D01*
G01X-895494Y986742D02*
X-895469Y986721D01*
G01X-895524Y986760D02*
X-895494Y986742D01*
G01X-895558Y986773D02*
X-895524Y986760D01*
G01X-895595Y986781D02*
X-895558Y986773D01*
G01X-895633Y986783D02*
X-895595Y986781D01*
G01X-893471Y986671D02*
X-893468Y986643D01*
G01X-893483Y986697D02*
X-893471Y986671D01*
G01X-893501Y986721D02*
X-893483Y986697D01*
G01X-893525Y986742D02*
X-893501Y986721D01*
G01X-893555Y986760D02*
X-893525Y986742D01*
G01X-893589Y986773D02*
X-893555Y986760D01*
G01X-893626Y986781D02*
X-893589Y986773D01*
G01X-893664Y986783D02*
X-893626Y986781D01*
G01X-891503Y986671D02*
X-891499Y986643D01*
G01X-891514Y986697D02*
X-891503Y986671D01*
G01X-891532Y986721D02*
X-891514Y986697D01*
G01X-891557Y986742D02*
X-891532Y986721D01*
G01X-891587Y986760D02*
X-891557Y986742D01*
G01X-891621Y986773D02*
X-891587Y986760D01*
G01X-891658Y986781D02*
X-891621Y986773D01*
G01X-891696Y986783D02*
X-891658Y986781D01*
G01X-889534Y986671D02*
X-889531Y986643D01*
G01X-889546Y986697D02*
X-889534Y986671D01*
G01X-889564Y986721D02*
X-889546Y986697D01*
G01X-889588Y986742D02*
X-889564Y986721D01*
G01X-889618Y986760D02*
X-889588Y986742D01*
G01X-889652Y986773D02*
X-889618Y986760D01*
G01X-889689Y986781D02*
X-889652Y986773D01*
G01X-889727Y986783D02*
X-889689Y986781D01*
G01X-887566Y986671D02*
X-887562Y986643D01*
G01X-887577Y986697D02*
X-887566Y986671D01*
G01X-887595Y986721D02*
X-887577Y986697D01*
G01X-887620Y986742D02*
X-887595Y986721D01*
G01X-887650Y986760D02*
X-887620Y986742D01*
G01X-887684Y986773D02*
X-887650Y986760D01*
G01X-887721Y986781D02*
X-887684Y986773D01*
G01X-887759Y986783D02*
X-887721Y986781D01*
G01X-885597Y986671D02*
X-885594Y986643D01*
G01X-885609Y986697D02*
X-885597Y986671D01*
G01X-885627Y986721D02*
X-885609Y986697D01*
G01X-885651Y986742D02*
X-885627Y986721D01*
G01X-885681Y986760D02*
X-885651Y986742D01*
G01X-885715Y986773D02*
X-885681Y986760D01*
G01X-885752Y986781D02*
X-885715Y986773D01*
G01X-885790Y986783D02*
X-885752Y986781D01*
G01X-883629Y986671D02*
X-883625Y986643D01*
G01X-883640Y986697D02*
X-883629Y986671D01*
G01X-883658Y986721D02*
X-883640Y986697D01*
G01X-883683Y986742D02*
X-883658Y986721D01*
G01X-883713Y986760D02*
X-883683Y986742D01*
G01X-883747Y986773D02*
X-883713Y986760D01*
G01X-883784Y986781D02*
X-883747Y986773D01*
G01X-883822Y986783D02*
X-883784Y986781D01*
G01X-881660Y986671D02*
X-881657Y986643D01*
G01X-881672Y986697D02*
X-881660Y986671D01*
G01X-881690Y986721D02*
X-881672Y986697D01*
G01X-881714Y986742D02*
X-881690Y986721D01*
G01X-881744Y986760D02*
X-881714Y986742D01*
G01X-881778Y986773D02*
X-881744Y986760D01*
G01X-881815Y986781D02*
X-881778Y986773D01*
G01X-881853Y986783D02*
X-881815Y986781D01*
G01X-879692Y986671D02*
X-879688Y986643D01*
G01X-879703Y986697D02*
X-879692Y986671D01*
G01X-879721Y986721D02*
X-879703Y986697D01*
G01X-879746Y986742D02*
X-879721Y986721D01*
G01X-879776Y986760D02*
X-879746Y986742D01*
G01X-879810Y986773D02*
X-879776Y986760D01*
G01X-879847Y986781D02*
X-879810Y986773D01*
G01X-879885Y986783D02*
X-879847Y986781D01*
G01X-877723Y986671D02*
X-877720Y986643D01*
G01X-877735Y986697D02*
X-877723Y986671D01*
G01X-877753Y986721D02*
X-877735Y986697D01*
G01X-877777Y986742D02*
X-877753Y986721D01*
G01X-877807Y986760D02*
X-877777Y986742D01*
G01X-877841Y986773D02*
X-877807Y986760D01*
G01X-877878Y986781D02*
X-877841Y986773D01*
G01X-877916Y986783D02*
X-877878Y986781D01*
G01X-875755Y986671D02*
X-875751Y986643D01*
G01X-875766Y986697D02*
X-875755Y986671D01*
G01X-875784Y986721D02*
X-875766Y986697D01*
G01X-875809Y986742D02*
X-875784Y986721D01*
G01X-875839Y986760D02*
X-875809Y986742D01*
G01X-875873Y986773D02*
X-875839Y986760D01*
G01X-875910Y986781D02*
X-875873Y986773D01*
G01X-875948Y986783D02*
X-875910Y986781D01*
G01X-873786Y986671D02*
X-873783Y986643D01*
G01X-873798Y986697D02*
X-873786Y986671D01*
G01X-873816Y986721D02*
X-873798Y986697D01*
G01X-873840Y986742D02*
X-873816Y986721D01*
G01X-873870Y986760D02*
X-873840Y986742D01*
G01X-873904Y986773D02*
X-873870Y986760D01*
G01X-873941Y986781D02*
X-873904Y986773D01*
G01X-873979Y986783D02*
X-873941Y986781D01*
G01X-871818Y986671D02*
X-871814Y986643D01*
G01X-871829Y986697D02*
X-871818Y986671D01*
G01X-871847Y986721D02*
X-871829Y986697D01*
G01X-871872Y986742D02*
X-871847Y986721D01*
G01X-871902Y986760D02*
X-871872Y986742D01*
G01X-871936Y986773D02*
X-871902Y986760D01*
G01X-871973Y986781D02*
X-871936Y986773D01*
G01X-872011Y986783D02*
X-871973Y986781D01*
G01X-926940Y986438D02*
X-926932Y986362D01*
G01X-926959Y986501D02*
X-926940Y986438D01*
G01X-926986Y986552D02*
X-926959Y986501D01*
G01X-927018Y986591D02*
X-926986Y986552D01*
G01X-927054Y986618D02*
X-927018Y986591D01*
G01X-927091Y986634D02*
X-927054Y986618D01*
G01X-927129Y986639D02*
X-927091Y986634D01*
G01X-924971Y986438D02*
X-924964Y986362D01*
G01X-924990Y986501D02*
X-924971Y986438D01*
G01X-925017Y986552D02*
X-924990Y986501D01*
G01X-925050Y986591D02*
X-925017Y986552D01*
G01X-925085Y986618D02*
X-925050Y986591D01*
G01X-925122Y986634D02*
X-925085Y986618D01*
G01X-925160Y986639D02*
X-925122Y986634D01*
G01X-923003Y986438D02*
X-922995Y986362D01*
G01X-923022Y986501D02*
X-923003Y986438D01*
G01X-923049Y986552D02*
X-923022Y986501D01*
G01X-923081Y986591D02*
X-923049Y986552D01*
G01X-923117Y986618D02*
X-923081Y986591D01*
G01X-923154Y986634D02*
X-923117Y986618D01*
G01X-923192Y986639D02*
X-923154Y986634D01*
G01X-921034Y986438D02*
X-921027Y986362D01*
G01X-921053Y986501D02*
X-921034Y986438D01*
G01X-921080Y986552D02*
X-921053Y986501D01*
G01X-921113Y986591D02*
X-921080Y986552D01*
G01X-921148Y986618D02*
X-921113Y986591D01*
G01X-921185Y986634D02*
X-921148Y986618D01*
G01X-921223Y986639D02*
X-921185Y986634D01*
G01X-919066Y986438D02*
X-919058Y986362D01*
G01X-919085Y986501D02*
X-919066Y986438D01*
G01X-919112Y986552D02*
X-919085Y986501D01*
G01X-919144Y986591D02*
X-919112Y986552D01*
G01X-919180Y986618D02*
X-919144Y986591D01*
G01X-919217Y986634D02*
X-919180Y986618D01*
G01X-919255Y986639D02*
X-919217Y986634D01*
G01X-917097Y986438D02*
X-917090Y986362D01*
G01X-917116Y986501D02*
X-917097Y986438D01*
G01X-917143Y986552D02*
X-917116Y986501D01*
G01X-917176Y986591D02*
X-917143Y986552D01*
G01X-917211Y986618D02*
X-917176Y986591D01*
G01X-917248Y986634D02*
X-917211Y986618D01*
G01X-917286Y986639D02*
X-917248Y986634D01*
G01X-915129Y986438D02*
X-915121Y986362D01*
G01X-915148Y986501D02*
X-915129Y986438D01*
G01X-915175Y986552D02*
X-915148Y986501D01*
G01X-915207Y986591D02*
X-915175Y986552D01*
G01X-915243Y986618D02*
X-915207Y986591D01*
G01X-915280Y986634D02*
X-915243Y986618D01*
G01X-915318Y986639D02*
X-915280Y986634D01*
G01X-913160Y986438D02*
X-913153Y986362D01*
G01X-913179Y986501D02*
X-913160Y986438D01*
G01X-913206Y986552D02*
X-913179Y986501D01*
G01X-913239Y986591D02*
X-913206Y986552D01*
G01X-913274Y986618D02*
X-913239Y986591D01*
G01X-913311Y986634D02*
X-913274Y986618D01*
G01X-913349Y986639D02*
X-913311Y986634D01*
G01X-911192Y986438D02*
X-911184Y986362D01*
G01X-911211Y986501D02*
X-911192Y986438D01*
G01X-911238Y986552D02*
X-911211Y986501D01*
G01X-911270Y986591D02*
X-911238Y986552D01*
G01X-911306Y986618D02*
X-911270Y986591D01*
G01X-911343Y986634D02*
X-911306Y986618D01*
G01X-911381Y986639D02*
X-911343Y986634D01*
G01X-909223Y986438D02*
X-909216Y986362D01*
G01X-909242Y986501D02*
X-909223Y986438D01*
G01X-909269Y986552D02*
X-909242Y986501D01*
G01X-909302Y986591D02*
X-909269Y986552D01*
G01X-909337Y986618D02*
X-909302Y986591D01*
G01X-909374Y986634D02*
X-909337Y986618D01*
G01X-909412Y986639D02*
X-909374Y986634D01*
G01X-907255Y986438D02*
X-907247Y986362D01*
G01X-907274Y986501D02*
X-907255Y986438D01*
G01X-907301Y986552D02*
X-907274Y986501D01*
G01X-907333Y986591D02*
X-907301Y986552D01*
G01X-907369Y986618D02*
X-907333Y986591D01*
G01X-907406Y986634D02*
X-907369Y986618D01*
G01X-907444Y986639D02*
X-907406Y986634D01*
G01X-905286Y986438D02*
X-905279Y986362D01*
G01X-905305Y986501D02*
X-905286Y986438D01*
G01X-905332Y986552D02*
X-905305Y986501D01*
G01X-905365Y986591D02*
X-905332Y986552D01*
G01X-905400Y986618D02*
X-905365Y986591D01*
G01X-905437Y986634D02*
X-905400Y986618D01*
G01X-905475Y986639D02*
X-905437Y986634D01*
G01X-903318Y986438D02*
X-903310Y986362D01*
G01X-903337Y986501D02*
X-903318Y986438D01*
G01X-903364Y986552D02*
X-903337Y986501D01*
G01X-903396Y986591D02*
X-903364Y986552D01*
G01X-903432Y986618D02*
X-903396Y986591D01*
G01X-903469Y986634D02*
X-903432Y986618D01*
G01X-903507Y986639D02*
X-903469Y986634D01*
G01X-901349Y986438D02*
X-901342Y986362D01*
G01X-901368Y986501D02*
X-901349Y986438D01*
G01X-901395Y986552D02*
X-901368Y986501D01*
G01X-901428Y986591D02*
X-901395Y986552D01*
G01X-901463Y986618D02*
X-901428Y986591D01*
G01X-901500Y986634D02*
X-901463Y986618D01*
G01X-901538Y986639D02*
X-901500Y986634D01*
G01X-899381Y986438D02*
X-899373Y986362D01*
G01X-899400Y986501D02*
X-899381Y986438D01*
G01X-899427Y986552D02*
X-899400Y986501D01*
G01X-899459Y986591D02*
X-899427Y986552D01*
G01X-899495Y986618D02*
X-899459Y986591D01*
G01X-899532Y986634D02*
X-899495Y986618D01*
G01X-899570Y986639D02*
X-899532Y986634D01*
G01X-897412Y986438D02*
X-897405Y986362D01*
G01X-897431Y986501D02*
X-897412Y986438D01*
G01X-897458Y986552D02*
X-897431Y986501D01*
G01X-897491Y986591D02*
X-897458Y986552D01*
G01X-897526Y986618D02*
X-897491Y986591D01*
G01X-897563Y986634D02*
X-897526Y986618D01*
G01X-897601Y986639D02*
X-897563Y986634D01*
G01X-927482D02*
X-927444Y986639D01*
G01X-927519Y986618D02*
X-927482Y986634D01*
G01X-927555Y986591D02*
X-927519Y986618D01*
G01X-927587Y986552D02*
X-927555Y986591D01*
G01X-927614Y986501D02*
X-927587Y986552D01*
G01X-927633Y986438D02*
X-927614Y986501D01*
G01X-927641Y986362D02*
X-927633Y986438D01*
G01X-925514Y986634D02*
X-925475Y986639D01*
G01X-925551Y986618D02*
X-925514Y986634D01*
G01X-925586Y986591D02*
X-925551Y986618D01*
G01X-925619Y986552D02*
X-925586Y986591D01*
G01X-925646Y986501D02*
X-925619Y986552D01*
G01X-925665Y986438D02*
X-925646Y986501D01*
G01X-925672Y986362D02*
X-925665Y986438D01*
G01X-923545Y986634D02*
X-923507Y986639D01*
G01X-923582Y986618D02*
X-923545Y986634D01*
G01X-923618Y986591D02*
X-923582Y986618D01*
G01X-923650Y986552D02*
X-923618Y986591D01*
G01X-923677Y986501D02*
X-923650Y986552D01*
G01X-923696Y986438D02*
X-923677Y986501D01*
G01X-923704Y986362D02*
X-923696Y986438D01*
G01X-921577Y986634D02*
X-921538Y986639D01*
G01X-921614Y986618D02*
X-921577Y986634D01*
G01X-921649Y986591D02*
X-921614Y986618D01*
G01X-921682Y986552D02*
X-921649Y986591D01*
G01X-921709Y986501D02*
X-921682Y986552D01*
G01X-921728Y986438D02*
X-921709Y986501D01*
G01X-921735Y986362D02*
X-921728Y986438D01*
G01X-919608Y986634D02*
X-919570Y986639D01*
G01X-919645Y986618D02*
X-919608Y986634D01*
G01X-919681Y986591D02*
X-919645Y986618D01*
G01X-919713Y986552D02*
X-919681Y986591D01*
G01X-919740Y986501D02*
X-919713Y986552D01*
G01X-919759Y986438D02*
X-919740Y986501D01*
G01X-919767Y986362D02*
X-919759Y986438D01*
G01X-917640Y986634D02*
X-917601Y986639D01*
G01X-917677Y986618D02*
X-917640Y986634D01*
G01X-917712Y986591D02*
X-917677Y986618D01*
G01X-917745Y986552D02*
X-917712Y986591D01*
G01X-917772Y986501D02*
X-917745Y986552D01*
G01X-917791Y986438D02*
X-917772Y986501D01*
G01X-917798Y986362D02*
X-917791Y986438D01*
G01X-915671Y986634D02*
X-915633Y986639D01*
G01X-915708Y986618D02*
X-915671Y986634D01*
G01X-915744Y986591D02*
X-915708Y986618D01*
G01X-915776Y986552D02*
X-915744Y986591D01*
G01X-915803Y986501D02*
X-915776Y986552D01*
G01X-915822Y986438D02*
X-915803Y986501D01*
G01X-915830Y986362D02*
X-915822Y986438D01*
G01X-927483Y986781D02*
X-927444Y986783D01*
G01X-927520Y986773D02*
X-927483Y986781D01*
G01X-927553Y986760D02*
X-927520Y986773D01*
G01X-927583Y986742D02*
X-927553Y986760D01*
G01X-927608Y986721D02*
X-927583Y986742D01*
G01X-927626Y986697D02*
X-927608Y986721D01*
G01X-927637Y986671D02*
X-927626Y986697D01*
G01X-927641Y986643D02*
X-927637Y986671D01*
G01X-925514Y986781D02*
X-925475Y986783D01*
G01X-925551Y986773D02*
X-925514Y986781D01*
G01X-925585Y986760D02*
X-925551Y986773D01*
G01X-925615Y986742D02*
X-925585Y986760D01*
G01X-925639Y986721D02*
X-925615Y986742D01*
G01X-925657Y986697D02*
X-925639Y986721D01*
G01X-925669Y986671D02*
X-925657Y986697D01*
G01X-925672Y986643D02*
X-925669Y986671D01*
G01X-923546Y986781D02*
X-923507Y986783D01*
G01X-923583Y986773D02*
X-923546Y986781D01*
G01X-923616Y986760D02*
X-923583Y986773D01*
G01X-923646Y986742D02*
X-923616Y986760D01*
G01X-923671Y986721D02*
X-923646Y986742D01*
G01X-923689Y986697D02*
X-923671Y986721D01*
G01X-923700Y986671D02*
X-923689Y986697D01*
G01X-923704Y986643D02*
X-923700Y986671D01*
G01X-921577Y986781D02*
X-921538Y986783D01*
G01X-921614Y986773D02*
X-921577Y986781D01*
G01X-921648Y986760D02*
X-921614Y986773D01*
G01X-921678Y986742D02*
X-921648Y986760D01*
G01X-921702Y986721D02*
X-921678Y986742D01*
G01X-921720Y986697D02*
X-921702Y986721D01*
G01X-921732Y986671D02*
X-921720Y986697D01*
G01X-921735Y986643D02*
X-921732Y986671D01*
G01X-919609Y986781D02*
X-919570Y986783D01*
G01X-919646Y986773D02*
X-919609Y986781D01*
G01X-919679Y986760D02*
X-919646Y986773D01*
G01X-919709Y986742D02*
X-919679Y986760D01*
G01X-919734Y986721D02*
X-919709Y986742D01*
G01X-919752Y986697D02*
X-919734Y986721D01*
G01X-919763Y986671D02*
X-919752Y986697D01*
G01X-919767Y986643D02*
X-919763Y986671D01*
G01X-917640Y986781D02*
X-917601Y986783D01*
G01X-917677Y986773D02*
X-917640Y986781D01*
G01X-917711Y986760D02*
X-917677Y986773D01*
G01X-917741Y986742D02*
X-917711Y986760D01*
G01X-917765Y986721D02*
X-917741Y986742D01*
G01X-917783Y986697D02*
X-917765Y986721D01*
G01X-917795Y986671D02*
X-917783Y986697D01*
G01X-917798Y986643D02*
X-917795Y986671D01*
G01X-915672Y986781D02*
X-915633Y986783D01*
G01X-915709Y986773D02*
X-915672Y986781D01*
G01X-915742Y986760D02*
X-915709Y986773D01*
G01X-915772Y986742D02*
X-915742Y986760D01*
G01X-915797Y986721D02*
X-915772Y986742D01*
G01X-915815Y986697D02*
X-915797Y986721D01*
G01X-915826Y986671D02*
X-915815Y986697D01*
G01X-915830Y986643D02*
X-915826Y986671D01*
G01X-913703Y986781D02*
X-913664Y986783D01*
G01X-913740Y986773D02*
X-913703Y986781D01*
G01X-913774Y986760D02*
X-913740Y986773D01*
G01X-913804Y986742D02*
X-913774Y986760D01*
G01X-913828Y986721D02*
X-913804Y986742D01*
G01X-913846Y986697D02*
X-913828Y986721D01*
G01X-913858Y986671D02*
X-913846Y986697D01*
G01X-913861Y986643D02*
X-913858Y986671D01*
G01X-911735Y986781D02*
X-911696Y986783D01*
G01X-911772Y986773D02*
X-911735Y986781D01*
G01X-911805Y986760D02*
X-911772Y986773D01*
G01X-911835Y986742D02*
X-911805Y986760D01*
G01X-911860Y986721D02*
X-911835Y986742D01*
G01X-911878Y986697D02*
X-911860Y986721D01*
G01X-911889Y986671D02*
X-911878Y986697D01*
G01X-911893Y986643D02*
X-911889Y986671D01*
G01X-909766Y986781D02*
X-909727Y986783D01*
G01X-909803Y986773D02*
X-909766Y986781D01*
G01X-909837Y986760D02*
X-909803Y986773D01*
G01X-909867Y986742D02*
X-909837Y986760D01*
G01X-909891Y986721D02*
X-909867Y986742D01*
G01X-909909Y986697D02*
X-909891Y986721D01*
G01X-909921Y986671D02*
X-909909Y986697D01*
G01X-909924Y986643D02*
X-909921Y986671D01*
G01X-895444Y986438D02*
X-895436Y986362D01*
G01X-895463Y986501D02*
X-895444Y986438D01*
G01X-895490Y986552D02*
X-895463Y986501D01*
G01X-895522Y986591D02*
X-895490Y986552D01*
G01X-895558Y986618D02*
X-895522Y986591D01*
G01X-895595Y986634D02*
X-895558Y986618D01*
G01X-895633Y986639D02*
X-895595Y986634D01*
G01X-893475Y986438D02*
X-893468Y986362D01*
G01X-893494Y986501D02*
X-893475Y986438D01*
G01X-893521Y986552D02*
X-893494Y986501D01*
G01X-893554Y986591D02*
X-893521Y986552D01*
G01X-893589Y986618D02*
X-893554Y986591D01*
G01X-893626Y986634D02*
X-893589Y986618D01*
G01X-893664Y986639D02*
X-893626Y986634D01*
G01X-891507Y986438D02*
X-891499Y986362D01*
G01X-891526Y986501D02*
X-891507Y986438D01*
G01X-891553Y986552D02*
X-891526Y986501D01*
G01X-891585Y986591D02*
X-891553Y986552D01*
G01X-891621Y986618D02*
X-891585Y986591D01*
G01X-891658Y986634D02*
X-891621Y986618D01*
G01X-891696Y986639D02*
X-891658Y986634D01*
G01X-889538Y986438D02*
X-889531Y986362D01*
G01X-889557Y986501D02*
X-889538Y986438D01*
G01X-889584Y986552D02*
X-889557Y986501D01*
G01X-889617Y986591D02*
X-889584Y986552D01*
G01X-889652Y986618D02*
X-889617Y986591D01*
G01X-889689Y986634D02*
X-889652Y986618D01*
G01X-889727Y986639D02*
X-889689Y986634D01*
G01X-887569Y986438D02*
X-887562Y986362D01*
G01X-887589Y986501D02*
X-887569Y986438D01*
G01X-887616Y986552D02*
X-887589Y986501D01*
G01X-887648Y986591D02*
X-887616Y986552D01*
G01X-887684Y986618D02*
X-887648Y986591D01*
G01X-887721Y986634D02*
X-887684Y986618D01*
G01X-887759Y986639D02*
X-887721Y986634D01*
G01X-885601Y986438D02*
X-885594Y986362D01*
G01X-885620Y986501D02*
X-885601Y986438D01*
G01X-885647Y986552D02*
X-885620Y986501D01*
G01X-885680Y986591D02*
X-885647Y986552D01*
G01X-885715Y986618D02*
X-885680Y986591D01*
G01X-885752Y986634D02*
X-885715Y986618D01*
G01X-885790Y986639D02*
X-885752Y986634D01*
G01X-883632Y986438D02*
X-883625Y986362D01*
G01X-883652Y986501D02*
X-883632Y986438D01*
G01X-883679Y986552D02*
X-883652Y986501D01*
G01X-883711Y986591D02*
X-883679Y986552D01*
G01X-883747Y986618D02*
X-883711Y986591D01*
G01X-883784Y986634D02*
X-883747Y986618D01*
G01X-883822Y986639D02*
X-883784Y986634D01*
G01X-881664Y986438D02*
X-881657Y986362D01*
G01X-881683Y986501D02*
X-881664Y986438D01*
G01X-881710Y986552D02*
X-881683Y986501D01*
G01X-881743Y986591D02*
X-881710Y986552D01*
G01X-881778Y986618D02*
X-881743Y986591D01*
G01X-881815Y986634D02*
X-881778Y986618D01*
G01X-881853Y986639D02*
X-881815Y986634D01*
G01X-879695Y986438D02*
X-879688Y986362D01*
G01X-879715Y986501D02*
X-879695Y986438D01*
G01X-879742Y986552D02*
X-879715Y986501D01*
G01X-879774Y986591D02*
X-879742Y986552D01*
G01X-879810Y986618D02*
X-879774Y986591D01*
G01X-879847Y986634D02*
X-879810Y986618D01*
G01X-879885Y986639D02*
X-879847Y986634D01*
G01X-877727Y986438D02*
X-877720Y986362D01*
G01X-877746Y986501D02*
X-877727Y986438D01*
G01X-877773Y986552D02*
X-877746Y986501D01*
G01X-877806Y986591D02*
X-877773Y986552D01*
G01X-877841Y986618D02*
X-877806Y986591D01*
G01X-877878Y986634D02*
X-877841Y986618D01*
G01X-877916Y986639D02*
X-877878Y986634D01*
G01X-875758Y986438D02*
X-875751Y986362D01*
G01X-875778Y986501D02*
X-875758Y986438D01*
G01X-875805Y986552D02*
X-875778Y986501D01*
G01X-875837Y986591D02*
X-875805Y986552D01*
G01X-875873Y986618D02*
X-875837Y986591D01*
G01X-875910Y986634D02*
X-875873Y986618D01*
G01X-875948Y986639D02*
X-875910Y986634D01*
G01X-873790Y986438D02*
X-873783Y986362D01*
G01X-873809Y986501D02*
X-873790Y986438D01*
G01X-873836Y986552D02*
X-873809Y986501D01*
G01X-873869Y986591D02*
X-873836Y986552D01*
G01X-873904Y986618D02*
X-873869Y986591D01*
G01X-873941Y986634D02*
X-873904Y986618D01*
G01X-873979Y986639D02*
X-873941Y986634D01*
G01X-871821Y986438D02*
X-871814Y986362D01*
G01X-871841Y986501D02*
X-871821Y986438D01*
G01X-871868Y986552D02*
X-871841Y986501D01*
G01X-871900Y986591D02*
X-871868Y986552D01*
G01X-871936Y986618D02*
X-871900Y986591D01*
G01X-871973Y986634D02*
X-871936Y986618D01*
G01X-872011Y986639D02*
X-871973Y986634D01*
G01X-913703D02*
X-913664Y986639D01*
G01X-913740Y986618D02*
X-913703Y986634D01*
G01X-913775Y986591D02*
X-913740Y986618D01*
G01X-913808Y986552D02*
X-913775Y986591D01*
G01X-913835Y986501D02*
X-913808Y986552D01*
G01X-913854Y986438D02*
X-913835Y986501D01*
G01X-913861Y986362D02*
X-913854Y986438D01*
G01X-911734Y986634D02*
X-911696Y986639D01*
G01X-911771Y986618D02*
X-911734Y986634D01*
G01X-911806Y986591D02*
X-911771Y986618D01*
G01X-911839Y986552D02*
X-911806Y986591D01*
G01X-911866Y986501D02*
X-911839Y986552D01*
G01X-911885Y986438D02*
X-911866Y986501D01*
G01X-911893Y986362D02*
X-911885Y986438D01*
G01X-909766Y986634D02*
X-909727Y986639D01*
G01X-909803Y986618D02*
X-909766Y986634D01*
G01X-909838Y986591D02*
X-909803Y986618D01*
G01X-909871Y986552D02*
X-909838Y986591D01*
G01X-909898Y986501D02*
X-909871Y986552D01*
G01X-909917Y986438D02*
X-909898Y986501D01*
G01X-909924Y986362D02*
X-909917Y986438D01*
G01X-907797Y986634D02*
X-907759Y986639D01*
G01X-907834Y986618D02*
X-907797Y986634D01*
G01X-907869Y986591D02*
X-907834Y986618D01*
G01X-907902Y986552D02*
X-907869Y986591D01*
G01X-907929Y986501D02*
X-907902Y986552D01*
G01X-907948Y986438D02*
X-907929Y986501D01*
G01X-907956Y986362D02*
X-907948Y986438D01*
G01X-905829Y986634D02*
X-905790Y986639D01*
G01X-905866Y986618D02*
X-905829Y986634D01*
G01X-905901Y986591D02*
X-905866Y986618D01*
G01X-905934Y986552D02*
X-905901Y986591D01*
G01X-905961Y986501D02*
X-905934Y986552D01*
G01X-905980Y986438D02*
X-905961Y986501D01*
G01X-905987Y986362D02*
X-905980Y986438D01*
G01X-903860Y986634D02*
X-903822Y986639D01*
G01X-903897Y986618D02*
X-903860Y986634D01*
G01X-903932Y986591D02*
X-903897Y986618D01*
G01X-903965Y986552D02*
X-903932Y986591D01*
G01X-903992Y986501D02*
X-903965Y986552D01*
G01X-904011Y986438D02*
X-903992Y986501D01*
G01X-904019Y986362D02*
X-904011Y986438D01*
G01X-901892Y986634D02*
X-901853Y986639D01*
G01X-901929Y986618D02*
X-901892Y986634D01*
G01X-901964Y986591D02*
X-901929Y986618D01*
G01X-901997Y986552D02*
X-901964Y986591D01*
G01X-902024Y986501D02*
X-901997Y986552D01*
G01X-902043Y986438D02*
X-902024Y986501D01*
G01X-902050Y986362D02*
X-902043Y986438D01*
G01X-899923Y986634D02*
X-899885Y986639D01*
G01X-899960Y986618D02*
X-899923Y986634D01*
G01X-899995Y986591D02*
X-899960Y986618D01*
G01X-900028Y986552D02*
X-899995Y986591D01*
G01X-900055Y986501D02*
X-900028Y986552D01*
G01X-900074Y986438D02*
X-900055Y986501D01*
G01X-900082Y986362D02*
X-900074Y986438D01*
G01X-897955Y986634D02*
X-897916Y986639D01*
G01X-897992Y986618D02*
X-897955Y986634D01*
G01X-898027Y986591D02*
X-897992Y986618D01*
G01X-898060Y986552D02*
X-898027Y986591D01*
G01X-898087Y986501D02*
X-898060Y986552D01*
G01X-898106Y986438D02*
X-898087Y986501D01*
G01X-898113Y986362D02*
X-898106Y986438D01*
G01X-895986Y986634D02*
X-895948Y986639D01*
G01X-896023Y986618D02*
X-895986Y986634D01*
G01X-896058Y986591D02*
X-896023Y986618D01*
G01X-896091Y986552D02*
X-896058Y986591D01*
G01X-896118Y986501D02*
X-896091Y986552D01*
G01X-896137Y986438D02*
X-896118Y986501D01*
G01X-896145Y986362D02*
X-896137Y986438D01*
G01X-894018Y986634D02*
X-893979Y986639D01*
G01X-894055Y986618D02*
X-894018Y986634D01*
G01X-894090Y986591D02*
X-894055Y986618D01*
G01X-894123Y986552D02*
X-894090Y986591D01*
G01X-894150Y986501D02*
X-894123Y986552D01*
G01X-894169Y986438D02*
X-894150Y986501D01*
G01X-894176Y986362D02*
X-894169Y986438D01*
G01X-892049Y986634D02*
X-892011Y986639D01*
G01X-892086Y986618D02*
X-892049Y986634D01*
G01X-892121Y986591D02*
X-892086Y986618D01*
G01X-892154Y986552D02*
X-892121Y986591D01*
G01X-892181Y986501D02*
X-892154Y986552D01*
G01X-892200Y986438D02*
X-892181Y986501D01*
G01X-892208Y986362D02*
X-892200Y986438D01*
G01X-890081Y986634D02*
X-890042Y986639D01*
G01X-890118Y986618D02*
X-890081Y986634D01*
G01X-890153Y986591D02*
X-890118Y986618D01*
G01X-890186Y986552D02*
X-890153Y986591D01*
G01X-890213Y986501D02*
X-890186Y986552D01*
G01X-890232Y986438D02*
X-890213Y986501D01*
G01X-890239Y986362D02*
X-890232Y986438D01*
G01X-888112Y986634D02*
X-888074Y986639D01*
G01X-888149Y986618D02*
X-888112Y986634D01*
G01X-888184Y986591D02*
X-888149Y986618D01*
G01X-888217Y986552D02*
X-888184Y986591D01*
G01X-888244Y986501D02*
X-888217Y986552D01*
G01X-888263Y986438D02*
X-888244Y986501D01*
G01X-888271Y986362D02*
X-888263Y986438D01*
G01X-886144Y986634D02*
X-886105Y986639D01*
G01X-886181Y986618D02*
X-886144Y986634D01*
G01X-886216Y986591D02*
X-886181Y986618D01*
G01X-886249Y986552D02*
X-886216Y986591D01*
G01X-886276Y986501D02*
X-886249Y986552D01*
G01X-886295Y986438D02*
X-886276Y986501D01*
G01X-886302Y986362D02*
X-886295Y986438D01*
G01X-884175Y986634D02*
X-884137Y986639D01*
G01X-884212Y986618D02*
X-884175Y986634D01*
G01X-884247Y986591D02*
X-884212Y986618D01*
G01X-884280Y986552D02*
X-884247Y986591D01*
G01X-884307Y986501D02*
X-884280Y986552D01*
G01X-884326Y986438D02*
X-884307Y986501D01*
G01X-884334Y986362D02*
X-884326Y986438D01*
G01X-882207Y986634D02*
X-882168Y986639D01*
G01X-882244Y986618D02*
X-882207Y986634D01*
G01X-882279Y986591D02*
X-882244Y986618D01*
G01X-882312Y986552D02*
X-882279Y986591D01*
G01X-882339Y986501D02*
X-882312Y986552D01*
G01X-882358Y986438D02*
X-882339Y986501D01*
G01X-882365Y986362D02*
X-882358Y986438D01*
G01X-880238Y986634D02*
X-880200Y986639D01*
G01X-880275Y986618D02*
X-880238Y986634D01*
G01X-880310Y986591D02*
X-880275Y986618D01*
G01X-880343Y986552D02*
X-880310Y986591D01*
G01X-880370Y986501D02*
X-880343Y986552D01*
G01X-880389Y986438D02*
X-880370Y986501D01*
G01X-880397Y986362D02*
X-880389Y986438D01*
G01X-878270Y986634D02*
X-878231Y986639D01*
G01X-878307Y986618D02*
X-878270Y986634D01*
G01X-878342Y986591D02*
X-878307Y986618D01*
G01X-878375Y986552D02*
X-878342Y986591D01*
G01X-878402Y986501D02*
X-878375Y986552D01*
G01X-878421Y986438D02*
X-878402Y986501D01*
G01X-878428Y986362D02*
X-878421Y986438D01*
G01X-876301Y986634D02*
X-876263Y986639D01*
G01X-876338Y986618D02*
X-876301Y986634D01*
G01X-876373Y986591D02*
X-876338Y986618D01*
G01X-876406Y986552D02*
X-876373Y986591D01*
G01X-876433Y986501D02*
X-876406Y986552D01*
G01X-876452Y986438D02*
X-876433Y986501D01*
G01X-876460Y986362D02*
X-876452Y986438D01*
G01X-907798Y986781D02*
X-907759Y986783D01*
G01X-907835Y986773D02*
X-907798Y986781D01*
G01X-907868Y986760D02*
X-907835Y986773D01*
G01X-907898Y986742D02*
X-907868Y986760D01*
G01X-907923Y986721D02*
X-907898Y986742D01*
G01X-907941Y986697D02*
X-907923Y986721D01*
G01X-907952Y986671D02*
X-907941Y986697D01*
G01X-907956Y986643D02*
X-907952Y986671D01*
G01X-905829Y986781D02*
X-905790Y986783D01*
G01X-905866Y986773D02*
X-905829Y986781D01*
G01X-905900Y986760D02*
X-905866Y986773D01*
G01X-905930Y986742D02*
X-905900Y986760D01*
G01X-905954Y986721D02*
X-905930Y986742D01*
G01X-905972Y986697D02*
X-905954Y986721D01*
G01X-905984Y986671D02*
X-905972Y986697D01*
G01X-905987Y986643D02*
X-905984Y986671D01*
G01X-903861Y986781D02*
X-903822Y986783D01*
G01X-903898Y986773D02*
X-903861Y986781D01*
G01X-903931Y986760D02*
X-903898Y986773D01*
G01X-903961Y986742D02*
X-903931Y986760D01*
G01X-903986Y986721D02*
X-903961Y986742D01*
G01X-904004Y986697D02*
X-903986Y986721D01*
G01X-904015Y986671D02*
X-904004Y986697D01*
G01X-904019Y986643D02*
X-904015Y986671D01*
G01X-901892Y986781D02*
X-901853Y986783D01*
G01X-901929Y986773D02*
X-901892Y986781D01*
G01X-901963Y986760D02*
X-901929Y986773D01*
G01X-901993Y986742D02*
X-901963Y986760D01*
G01X-902017Y986721D02*
X-901993Y986742D01*
G01X-902035Y986697D02*
X-902017Y986721D01*
G01X-902047Y986671D02*
X-902035Y986697D01*
G01X-902050Y986643D02*
X-902047Y986671D01*
G01X-899924Y986781D02*
X-899885Y986783D01*
G01X-899961Y986773D02*
X-899924Y986781D01*
G01X-899994Y986760D02*
X-899961Y986773D01*
G01X-900024Y986742D02*
X-899994Y986760D01*
G01X-900049Y986721D02*
X-900024Y986742D01*
G01X-900067Y986697D02*
X-900049Y986721D01*
G01X-900078Y986671D02*
X-900067Y986697D01*
G01X-900082Y986643D02*
X-900078Y986671D01*
G01X-897955Y986781D02*
X-897916Y986783D01*
G01X-897992Y986773D02*
X-897955Y986781D01*
G01X-898026Y986760D02*
X-897992Y986773D01*
G01X-898056Y986742D02*
X-898026Y986760D01*
G01X-898080Y986721D02*
X-898056Y986742D01*
G01X-898098Y986697D02*
X-898080Y986721D01*
G01X-898110Y986671D02*
X-898098Y986697D01*
G01X-898113Y986643D02*
X-898110Y986671D01*
G01X-895987Y986781D02*
X-895948Y986783D01*
G01X-896024Y986773D02*
X-895987Y986781D01*
G01X-896057Y986760D02*
X-896024Y986773D01*
G01X-896087Y986742D02*
X-896057Y986760D01*
G01X-896112Y986721D02*
X-896087Y986742D01*
G01X-896130Y986697D02*
X-896112Y986721D01*
G01X-896141Y986671D02*
X-896130Y986697D01*
G01X-896145Y986643D02*
X-896141Y986671D01*
G01X-894018Y986781D02*
X-893979Y986783D01*
G01X-894055Y986773D02*
X-894018Y986781D01*
G01X-894089Y986760D02*
X-894055Y986773D01*
G01X-894119Y986742D02*
X-894089Y986760D01*
G01X-894143Y986721D02*
X-894119Y986742D01*
G01X-894161Y986697D02*
X-894143Y986721D01*
G01X-894172Y986671D02*
X-894161Y986697D01*
G01X-894176Y986643D02*
X-894172Y986671D01*
G01X-892050Y986781D02*
X-892011Y986783D01*
G01X-892087Y986773D02*
X-892050Y986781D01*
G01X-892120Y986760D02*
X-892087Y986773D01*
G01X-892150Y986742D02*
X-892120Y986760D01*
G01X-892175Y986721D02*
X-892150Y986742D01*
G01X-892193Y986697D02*
X-892175Y986721D01*
G01X-892204Y986671D02*
X-892193Y986697D01*
G01X-892208Y986643D02*
X-892204Y986671D01*
G01X-890081Y986781D02*
X-890042Y986783D01*
G01X-890118Y986773D02*
X-890081Y986781D01*
G01X-890152Y986760D02*
X-890118Y986773D01*
G01X-890182Y986742D02*
X-890152Y986760D01*
G01X-890206Y986721D02*
X-890182Y986742D01*
G01X-890224Y986697D02*
X-890206Y986721D01*
G01X-890235Y986671D02*
X-890224Y986697D01*
G01X-890239Y986643D02*
X-890235Y986671D01*
G01X-888113Y986781D02*
X-888074Y986783D01*
G01X-888150Y986773D02*
X-888113Y986781D01*
G01X-888183Y986760D02*
X-888150Y986773D01*
G01X-888213Y986742D02*
X-888183Y986760D01*
G01X-888238Y986721D02*
X-888213Y986742D01*
G01X-888256Y986697D02*
X-888238Y986721D01*
G01X-888267Y986671D02*
X-888256Y986697D01*
G01X-888271Y986643D02*
X-888267Y986671D01*
G01X-886144Y986781D02*
X-886105Y986783D01*
G01X-886181Y986773D02*
X-886144Y986781D01*
G01X-886215Y986760D02*
X-886181Y986773D01*
G01X-886245Y986742D02*
X-886215Y986760D01*
G01X-886269Y986721D02*
X-886245Y986742D01*
G01X-886287Y986697D02*
X-886269Y986721D01*
G01X-886298Y986671D02*
X-886287Y986697D01*
G01X-886302Y986643D02*
X-886298Y986671D01*
G01X-884176Y986781D02*
X-884137Y986783D01*
G01X-884213Y986773D02*
X-884176Y986781D01*
G01X-884246Y986760D02*
X-884213Y986773D01*
G01X-884276Y986742D02*
X-884246Y986760D01*
G01X-884301Y986721D02*
X-884276Y986742D01*
G01X-884319Y986697D02*
X-884301Y986721D01*
G01X-884330Y986671D02*
X-884319Y986697D01*
G01X-884334Y986643D02*
X-884330Y986671D01*
G01X-882207Y986781D02*
X-882168Y986783D01*
G01X-882244Y986773D02*
X-882207Y986781D01*
G01X-882278Y986760D02*
X-882244Y986773D01*
G01X-882308Y986742D02*
X-882278Y986760D01*
G01X-882332Y986721D02*
X-882308Y986742D01*
G01X-882350Y986697D02*
X-882332Y986721D01*
G01X-882361Y986671D02*
X-882350Y986697D01*
G01X-882365Y986643D02*
X-882361Y986671D01*
G01X-880239Y986781D02*
X-880200Y986783D01*
G01X-880276Y986773D02*
X-880239Y986781D01*
G01X-880309Y986760D02*
X-880276Y986773D01*
G01X-880339Y986742D02*
X-880309Y986760D01*
G01X-880364Y986721D02*
X-880339Y986742D01*
G01X-880382Y986697D02*
X-880364Y986721D01*
G01X-880393Y986671D02*
X-880382Y986697D01*
G01X-880397Y986643D02*
X-880393Y986671D01*
G01X-878270Y986781D02*
X-878231Y986783D01*
G01X-878307Y986773D02*
X-878270Y986781D01*
G01X-878341Y986760D02*
X-878307Y986773D01*
G01X-878371Y986742D02*
X-878341Y986760D01*
G01X-878395Y986721D02*
X-878371Y986742D01*
G01X-878413Y986697D02*
X-878395Y986721D01*
G01X-878424Y986671D02*
X-878413Y986697D01*
G01X-878428Y986643D02*
X-878424Y986671D01*
G01X-876302Y986781D02*
X-876263Y986783D01*
G01X-876339Y986773D02*
X-876302Y986781D01*
G01X-876372Y986760D02*
X-876339Y986773D01*
G01X-876402Y986742D02*
X-876372Y986760D01*
G01X-876427Y986721D02*
X-876402Y986742D01*
G01X-876445Y986697D02*
X-876427Y986721D01*
G01X-876456Y986671D02*
X-876445Y986697D01*
G01X-876460Y986643D02*
X-876456Y986671D01*
G01X-874333Y986781D02*
X-874294Y986783D01*
G01X-874370Y986773D02*
X-874333Y986781D01*
G01X-874404Y986760D02*
X-874370Y986773D01*
G01X-874434Y986742D02*
X-874404Y986760D01*
G01X-874458Y986721D02*
X-874434Y986742D01*
G01X-874476Y986697D02*
X-874458Y986721D01*
G01X-874487Y986671D02*
X-874476Y986697D01*
G01X-874491Y986643D02*
X-874487Y986671D01*
G01X-872365Y986781D02*
X-872326Y986783D01*
G01X-872401Y986773D02*
X-872365Y986781D01*
G01X-872435Y986760D02*
X-872401Y986773D01*
G01X-872465Y986742D02*
X-872435Y986760D01*
G01X-872490Y986721D02*
X-872465Y986742D01*
G01X-872508Y986697D02*
X-872490Y986721D01*
G01X-872519Y986671D02*
X-872508Y986697D01*
G01X-872523Y986643D02*
X-872519Y986671D01*
G01X-874333Y986634D02*
X-874294Y986639D01*
G01X-874370Y986618D02*
X-874333Y986634D01*
G01X-874405Y986591D02*
X-874370Y986618D01*
G01X-874438Y986552D02*
X-874405Y986591D01*
G01X-874465Y986501D02*
X-874438Y986552D01*
G01X-874484Y986438D02*
X-874465Y986501D01*
G01X-874491Y986362D02*
X-874484Y986438D01*
G01X-872364Y986634D02*
X-872326Y986639D01*
G01X-872401Y986618D02*
X-872364Y986634D01*
G01X-872436Y986591D02*
X-872401Y986618D01*
G01X-872469Y986552D02*
X-872436Y986591D01*
G01X-872496Y986501D02*
X-872469Y986552D01*
G01X-872515Y986438D02*
X-872496Y986501D01*
G01X-872523Y986362D02*
X-872515Y986438D01*
G01X-869905Y981637D02*
G03X-865574I2165J0D01*
G01X-871972Y972582D02*
G03X-871775Y972779I0J197D01*
G01X-872562D02*
G03X-872365Y972582I197J0D01*
G01X-873940D02*
G03X-873743Y972779I0J197D01*
G01X-874531D02*
G03X-874334Y972582I197J0D01*
G01X-875909D02*
G03X-875712Y972779I0J197D01*
G01X-876499D02*
G03X-876302Y972582I197J0D01*
G01X-877877D02*
G03X-877680Y972779I0J197D01*
G01X-878468D02*
G03X-878271Y972582I197J0D01*
G01X-879846D02*
G03X-879649Y972779I0J197D01*
G01X-880436D02*
G03X-880239Y972582I197J0D01*
G01X-881814D02*
G03X-881617Y972779I0J197D01*
G01X-882405D02*
G03X-882208Y972582I197J0D01*
G01X-883783D02*
G03X-883586Y972779I0J197D01*
G01X-884373D02*
G03X-884176Y972582I197J0D01*
G01X-885751D02*
G03X-885554Y972779I0J197D01*
G01X-886342D02*
G03X-886145Y972582I197J0D01*
G01X-887720D02*
G03X-887523Y972779I0J197D01*
G01X-888310D02*
G03X-888113Y972582I197J0D01*
G01X-889688D02*
G03X-889491Y972779I0J197D01*
G01X-890279D02*
G03X-890082Y972582I197J0D01*
G01X-891657D02*
G03X-891460Y972779I0J197D01*
G01X-892247D02*
G03X-892050Y972582I197J0D01*
G01X-910279Y987621D02*
G03X-909491Y988409I0J788D01*
G01X-893625Y972582D02*
G03X-893428Y972779I0J197D01*
G01X-894216D02*
G03X-894019Y972582I197J0D01*
G01X-895594D02*
G03X-895397Y972779I0J197D01*
G01X-896184D02*
G03X-895987Y972582I197J0D01*
G01X-897562D02*
G03X-897365Y972779I0J197D01*
G01X-898153D02*
G03X-897956Y972582I197J0D01*
G01X-899531D02*
G03X-899334Y972779I0J197D01*
G01X-900121D02*
G03X-899924Y972582I197J0D01*
G01X-901499D02*
G03X-901302Y972779I0J197D01*
G01X-902090D02*
G03X-901893Y972582I197J0D01*
G01X-903468D02*
G03X-903271Y972779I0J197D01*
G01X-904058D02*
G03X-903861Y972582I197J0D01*
G01X-905436D02*
G03X-905239Y972779I0J197D01*
G01X-906027D02*
G03X-905830Y972582I197J0D01*
G01X-907405D02*
G03X-907208Y972779I0J197D01*
G01X-907995D02*
G03X-907798Y972582I197J0D01*
G01X-909373D02*
G03X-909176Y972779I0J197D01*
G01X-909964D02*
G03X-909767Y972582I197J0D01*
G01X-911342D02*
G03X-911145Y972779I0J197D01*
G01X-911932D02*
G03X-911735Y972582I197J0D01*
G01X-913310D02*
G03X-913113Y972779I0J197D01*
G01X-913901D02*
G03X-913704Y972582I197J0D01*
G01X-930712Y988409D02*
G03X-929924Y987621I788J0D01*
G01X-930239Y983606D02*
G03I-984J0D01*
G01X-932700Y979472D02*
G03X-931519Y980653I0J1181D01*
G01X-929452Y983606D02*
G03I-1771J0D01*
G01X-929058D02*
G03I-2165J0D01*
G01X-915279Y972582D02*
G03X-915082Y972779I0J197D01*
G01X-915869D02*
G03X-915672Y972582I197J0D01*
G01X-917247D02*
G03X-917050Y972779I0J197D01*
G01X-917838D02*
G03X-917641Y972582I197J0D01*
G01X-919216D02*
G03X-919019Y972779I0J197D01*
G01X-919806D02*
G03X-919609Y972582I197J0D01*
G01X-921184D02*
G03X-920987Y972779I0J197D01*
G01X-921775D02*
G03X-921578Y972582I197J0D01*
G01X-923153D02*
G03X-922956Y972779I0J197D01*
G01X-923743D02*
G03X-923546Y972582I197J0D01*
G01X-925121D02*
G03X-924924Y972779I0J197D01*
G01X-925712D02*
G03X-925515Y972582I197J0D01*
G01X-927090D02*
G03X-926893Y972779I0J197D01*
G01X-927680D02*
G03X-927483Y972582I197J0D01*
G01X-935160Y974747D02*
G03X-934373Y973960I787J0D01*
G01X-911538Y995316D02*
X-911473Y995048D01*
G01X-911867Y995316D02*
X-911801Y995048D01*
G01X-913244Y994780D02*
X-913179Y994512D01*
G01X-916525Y995450D02*
X-916460Y995182D01*
G01X-913573Y994780D02*
X-913441Y994311D01*
G01X-911604Y995517D02*
X-911538Y995316D01*
G01X-914229Y995651D02*
X-914163Y995450D01*
G01X-918231Y994780D02*
X-918166Y994579D01*
G01X-921840Y995316D02*
X-921775Y995115D01*
G01X-921184Y991755D02*
X-920200Y988941D01*
G01X-921381Y991085D02*
X-920462Y988606D01*
G01X-924202Y995785D02*
X-924071Y995450D01*
G01X-918166Y994579D02*
X-918100Y994445D01*
G01X-918494Y994512D02*
X-918363Y994244D01*
G01X-919216Y995651D02*
X-919150Y995517D01*
G01X-921578Y995584D02*
X-921512Y995450D01*
G01X-923218Y994244D02*
X-923153Y994110D01*
G01X-924465Y995584D02*
X-924399Y995450D01*
G01X-925515Y995584D02*
X-925449Y995450D01*
G01X-911735Y995718D02*
X-911604Y995517D01*
G01X-911998D02*
X-911867Y995316D01*
G01X-913179Y994512D02*
X-913048Y994311D01*
G01X-913441D02*
X-913310Y994110D01*
G01X-916919Y995517D02*
X-916788Y995316D01*
G01X-921972Y995517D02*
X-921840Y995316D01*
G01X-923218Y994579D02*
X-923087Y994378D01*
G01X-916722Y995718D02*
X-916525Y995450D01*
G01X-911867Y995852D02*
X-911735Y995718D01*
G01X-912129Y995651D02*
X-911998Y995517D01*
G01X-914360Y995785D02*
X-914229Y995651D01*
G01X-913048Y994311D02*
X-912916Y994177D01*
G01X-914622Y995584D02*
X-914491Y995450D01*
G01X-913310Y994110D02*
X-913179Y993976D01*
G01X-919347Y995785D02*
X-919216Y995651D01*
G01X-918100Y994445D02*
X-917903Y994244D01*
G01X-919609Y995584D02*
X-919478Y995450D01*
G01X-918363Y994244D02*
X-918231Y994110D01*
G01X-921775Y995785D02*
X-921578Y995584D01*
G01X-924334Y995919D02*
X-924202Y995785D01*
G01X-924531Y995651D02*
X-924465Y995584D01*
G01X-923153Y994110D02*
X-923021Y993976D01*
G01X-925384Y995919D02*
X-925187Y995718D01*
G01X-925580Y995651D02*
X-925515Y995584D01*
G01X-872852Y983923D02*
X-872759Y985583D01*
G01X-872767Y985767D02*
X-872812Y984973D01*
G01X-874821Y983923D02*
X-874727Y985583D01*
G01X-874735Y985767D02*
X-874780Y984973D01*
G01X-876789Y983923D02*
X-876696Y985583D01*
G01X-876704Y985767D02*
X-876749Y984973D01*
G01X-878758Y983923D02*
X-878664Y985583D01*
G01X-878672Y985767D02*
X-878717Y984973D01*
G01X-880726Y983923D02*
X-880633Y985583D01*
G01X-880641Y985767D02*
X-880686Y984973D01*
G01X-872767Y985767D02*
X-872759Y985924D01*
G01X-874735Y985767D02*
X-874727Y985924D01*
G01X-876704Y985767D02*
X-876696Y985924D01*
G01X-878672Y985767D02*
X-878664Y985924D01*
G01X-880641Y985767D02*
X-880633Y985924D01*
G01X-872852Y983923D02*
X-872812Y984973D01*
G01X-874821Y983923D02*
X-874780Y984973D01*
G01X-876789Y983923D02*
X-876749Y984973D01*
G01X-878758Y983923D02*
X-878717Y984973D01*
G01X-880726Y983923D02*
X-880686Y984973D01*
G01X-882695Y983923D02*
X-882654Y984973D01*
G01X-865574Y981637D02*
Y990495D01*
G01X-869905D02*
Y981637D01*
G01X-871578Y971598D02*
Y977700D01*
G01X-871775Y975100D02*
Y972779D01*
G01X-871814Y986643D02*
Y982464D01*
G01X-872011Y986783D02*
Y986639D01*
G01X-872326D02*
Y986783D01*
G01X-872523Y986643D02*
Y982464D01*
G01X-872562Y972779D02*
Y975100D01*
G01X-872759Y977700D02*
Y971598D01*
G01Y987940D02*
Y985583D01*
G01X-873546D02*
Y987940D01*
G01Y971598D02*
Y977700D01*
G01X-873743Y975100D02*
Y972779D01*
G01X-873783Y986643D02*
Y982464D01*
G01X-873979Y986783D02*
Y986639D01*
G01X-874294D02*
Y986783D01*
G01X-874491Y986643D02*
Y982464D01*
G01X-874531Y972779D02*
Y975100D01*
G01X-874727Y977700D02*
Y971598D01*
G01Y987940D02*
Y985583D01*
G01X-875515D02*
Y987940D01*
G01Y977700D02*
Y971598D01*
G01X-875712Y975100D02*
Y972779D01*
G01X-875751Y986643D02*
Y982464D01*
G01X-875948Y986783D02*
Y986639D01*
G01X-876263D02*
Y986783D01*
G01X-876460Y986643D02*
Y982464D01*
G01X-876499Y972779D02*
Y975100D01*
G01X-876696Y971598D02*
Y977700D01*
G01Y987940D02*
Y985583D01*
G01X-877483D02*
Y987940D01*
G01Y977700D02*
Y971598D01*
G01X-877680Y975100D02*
Y972779D01*
G01X-877720Y986643D02*
Y982464D01*
G01X-877916Y986783D02*
Y986639D01*
G01X-878231D02*
Y986783D01*
G01X-878428Y986643D02*
Y982464D01*
G01X-878468Y972779D02*
Y975100D01*
G01X-878664Y971598D02*
Y977700D01*
G01Y987940D02*
Y985583D01*
G01X-879452D02*
Y987940D01*
G01Y971598D02*
Y977700D01*
G01X-879649Y975100D02*
Y972779D01*
G01X-879688Y986643D02*
Y982464D01*
G01X-879885Y986783D02*
Y986639D01*
G01X-880200D02*
Y986783D01*
G01X-880397Y986643D02*
Y982464D01*
G01X-880436Y972779D02*
Y975100D01*
G01X-880633Y977700D02*
Y971598D01*
G01Y987940D02*
Y985583D01*
G01X-881420D02*
Y987940D01*
G01Y971598D02*
Y977700D01*
G01X-881617Y975100D02*
Y972779D01*
G01X-881657Y986643D02*
Y982464D01*
G01X-881853Y986783D02*
Y986639D01*
G01X-882168D02*
Y986783D01*
G01X-882365Y986643D02*
Y982464D01*
G01X-882405Y972779D02*
Y975100D01*
G01X-882601Y977700D02*
Y971598D01*
G01Y987940D02*
Y985583D01*
G01X-883389D02*
Y987940D01*
G01Y971598D02*
Y977700D01*
G01X-883586Y975100D02*
Y972779D01*
G01X-883625Y986643D02*
Y982464D01*
G01X-883822Y986783D02*
Y986639D01*
G01X-884137D02*
Y986783D01*
G01X-884334Y986643D02*
Y982464D01*
G01X-884373Y972779D02*
Y975100D01*
G01X-884570Y977700D02*
Y971598D01*
G01Y987940D02*
Y985583D01*
G01X-885357D02*
Y987940D01*
G01Y977700D02*
Y971598D01*
G01X-885554Y975100D02*
Y972779D01*
G01X-885594Y986643D02*
Y982464D01*
G01X-885790Y986783D02*
Y986639D01*
G01X-886105D02*
Y986783D01*
G01X-886302Y986643D02*
Y982464D01*
G01X-886342Y972779D02*
Y975100D01*
G01X-886538Y971598D02*
Y977700D01*
G01Y987940D02*
Y985583D01*
G01X-887326D02*
Y987940D01*
G01Y977700D02*
Y971598D01*
G01X-887523Y975100D02*
Y972779D01*
G01X-887562Y986643D02*
Y982464D01*
G01X-887759Y986783D02*
Y986639D01*
G01X-888074D02*
Y986783D01*
G01X-888271Y986643D02*
Y982464D01*
G01X-888310Y972779D02*
Y975100D01*
G01X-888507Y971598D02*
Y977700D01*
G01Y987940D02*
Y985583D01*
G01X-889294D02*
Y987940D01*
G01Y971598D02*
Y977700D01*
G01X-873453Y983923D02*
X-873494Y984973D01*
G01X-875422Y983923D02*
X-875462Y984973D01*
G01X-877390Y983923D02*
X-877431Y984973D01*
G01X-879359Y983923D02*
X-879399Y984973D01*
G01X-881327Y983923D02*
X-881368Y984973D01*
G01X-883296Y983923D02*
X-883336Y984973D01*
G01X-885264Y983923D02*
X-885305Y984973D01*
G01X-887233Y983923D02*
X-887273Y984973D01*
G01X-889201Y983923D02*
X-889242Y984973D01*
G01X-891170Y983923D02*
X-891210Y984973D01*
G01X-893138Y983923D02*
X-893179Y984973D01*
G01X-873546Y985924D02*
X-873538Y985767D01*
G01X-875515Y985924D02*
X-875507Y985767D01*
G01X-877483Y985924D02*
X-877475Y985767D01*
G01X-879452Y985924D02*
X-879444Y985767D01*
G01X-881420Y985924D02*
X-881412Y985767D01*
G01X-883389Y985924D02*
X-883381Y985767D01*
G01X-885357Y985924D02*
X-885349Y985767D01*
G01X-887326Y985924D02*
X-887318Y985767D01*
G01X-889294Y985924D02*
X-889286Y985767D01*
G01X-891263Y985924D02*
X-891255Y985767D01*
G01X-893231Y985924D02*
X-893223Y985767D01*
G01X-895200Y985924D02*
X-895192Y985767D01*
G01X-873453Y983923D02*
X-873546Y985583D01*
G01X-875422Y983923D02*
X-875515Y985583D01*
G01X-877390Y983923D02*
X-877483Y985583D01*
G01X-879359Y983923D02*
X-879452Y985583D01*
G01X-881327Y983923D02*
X-881420Y985583D01*
G01X-883296Y983923D02*
X-883389Y985583D01*
G01X-885264Y983923D02*
X-885357Y985583D01*
G01X-887233Y983923D02*
X-887326Y985583D01*
G01X-889201Y983923D02*
X-889294Y985583D01*
G01X-891170Y983923D02*
X-891263Y985583D01*
G01X-893138Y983923D02*
X-893231Y985583D01*
G01X-895107Y983923D02*
X-895200Y985583D01*
G01X-873494Y984973D02*
X-873538Y985767D01*
G01X-875462Y984973D02*
X-875507Y985767D01*
G01X-877431Y984973D02*
X-877475Y985767D01*
G01X-879399Y984973D02*
X-879444Y985767D01*
G01X-881368Y984973D02*
X-881412Y985767D01*
G01X-883336Y984973D02*
X-883381Y985767D01*
G01X-885305Y984973D02*
X-885349Y985767D01*
G01X-887273Y984973D02*
X-887318Y985767D01*
G01X-889242Y984973D02*
X-889286Y985767D01*
G01X-891210Y984973D02*
X-891255Y985767D01*
G01X-893179Y984973D02*
X-893223Y985767D01*
G01X-895147Y984973D02*
X-895192Y985767D01*
G01X-918559Y994914D02*
X-918494Y994512D01*
G01X-914163Y995450D02*
X-914098Y995115D01*
G01X-914491Y995450D02*
X-914426Y995115D01*
G01X-919150Y995517D02*
X-919084Y995182D01*
G01X-919478Y995450D02*
X-919412Y995182D01*
G01X-921512Y995450D02*
X-921447Y995182D01*
G01X-928336Y996723D02*
X-927746Y994914D01*
G01X-927680Y994646D02*
X-927418Y993842D01*
G01X-928074Y996991D02*
X-927024Y993842D01*
G01X-914557Y995919D02*
X-914360Y995785D01*
G01X-917116Y995651D02*
X-916919Y995517D01*
G01X-919544Y995919D02*
X-919347Y995785D01*
G01X-918231Y994110D02*
X-918035Y993976D01*
G01X-921972Y995919D02*
X-921775Y995785D01*
G01X-923087Y994378D02*
X-922890Y994244D01*
G01X-916722Y995718D02*
X-917050Y995919D01*
G01X-911867Y995852D02*
X-911998Y995919D01*
G01X-914622Y995584D02*
X-914754Y995651D01*
G01X-913048Y993909D02*
X-913179Y993976D01*
G01X-919609Y995584D02*
X-919741Y995651D01*
G01X-917772Y994177D02*
X-917903Y994244D01*
G01X-921972Y995517D02*
X-922234Y995651D01*
G01X-924531D02*
X-924662Y995718D01*
G01X-925580Y995651D02*
X-925712Y995718D01*
G01X-922890Y993909D02*
X-923021Y993976D01*
G01X-914557Y995919D02*
X-914754Y995986D01*
G01X-882695Y983923D02*
X-882601Y985583D01*
G01X-882609Y985767D02*
X-882654Y984973D01*
G01X-884663Y983923D02*
X-884570Y985583D01*
G01X-884578Y985767D02*
X-884623Y984973D01*
G01X-886632Y983923D02*
X-886538Y985583D01*
G01X-886546Y985767D02*
X-886591Y984973D01*
G01X-888600Y983923D02*
X-888507Y985583D01*
G01X-888515Y985767D02*
X-888560Y984973D01*
G01X-890569Y983923D02*
X-890475Y985583D01*
G01X-890483Y985767D02*
X-890528Y984973D01*
G01X-892537Y983923D02*
X-892444Y985583D01*
G01X-892452Y985767D02*
X-892497Y984973D01*
G01X-894506Y983923D02*
X-894412Y985583D01*
G01X-894420Y985767D02*
X-894465Y984973D01*
G01X-896474Y983923D02*
X-896381Y985583D01*
G01X-896389Y985767D02*
X-896434Y984973D01*
G01X-898443Y983923D02*
X-898349Y985583D01*
G01X-898357Y985767D02*
X-898402Y984973D01*
G01X-900411Y983923D02*
X-900318Y985583D01*
G01X-900326Y985767D02*
X-900371Y984973D01*
G01X-902380Y983923D02*
X-902286Y985583D01*
G01X-902294Y985767D02*
X-902339Y984973D01*
G01X-904348Y983923D02*
X-904255Y985583D01*
G01X-904263Y985767D02*
X-904308Y984973D01*
G01X-906317Y983923D02*
X-906223Y985583D01*
G01X-906231Y985767D02*
X-906276Y984973D01*
G01X-908285Y983923D02*
X-908192Y985583D01*
G01X-908200Y985767D02*
X-908245Y984973D01*
G01X-910254Y983923D02*
X-910160Y985583D01*
G01X-910168Y985767D02*
X-910213Y984973D01*
G01X-912222Y983923D02*
X-912129Y985583D01*
G01X-912137Y985767D02*
X-912182Y984973D01*
G01X-914191Y983923D02*
X-914098Y985583D01*
G01X-914105Y985767D02*
X-914150Y984973D01*
G01X-916159Y983923D02*
X-916066Y985583D01*
G01X-916074Y985767D02*
X-916119Y984973D01*
G01X-918128Y983923D02*
X-918035Y985583D01*
G01X-918042Y985767D02*
X-918087Y984973D01*
G01X-920096Y983923D02*
X-920003Y985583D01*
G01X-920011Y985767D02*
X-920056Y984973D01*
G01X-921972Y985583D02*
X-921979Y985433D01*
G01X-882609Y985767D02*
X-882601Y985924D01*
G01X-884578Y985767D02*
X-884570Y985924D01*
G01X-886546Y985767D02*
X-886538Y985924D01*
G01X-888515Y985767D02*
X-888507Y985924D01*
G01X-890483Y985767D02*
X-890475Y985924D01*
G01X-892452Y985767D02*
X-892444Y985924D01*
G01X-894420Y985767D02*
X-894412Y985924D01*
G01X-896389Y985767D02*
X-896381Y985924D01*
G01X-898357Y985767D02*
X-898349Y985924D01*
G01X-900326Y985767D02*
X-900318Y985924D01*
G01X-902294Y985767D02*
X-902286Y985924D01*
G01X-904263Y985767D02*
X-904255Y985924D01*
G01X-906231Y985767D02*
X-906223Y985924D01*
G01X-908200Y985767D02*
X-908192Y985924D01*
G01X-910168Y985767D02*
X-910160Y985924D01*
G01X-912137Y985767D02*
X-912129Y985924D01*
G01X-914105Y985767D02*
X-914098Y985924D01*
G01X-916074Y985767D02*
X-916066Y985924D01*
G01X-918042Y985767D02*
X-918035Y985924D01*
G01X-920011Y985767D02*
X-920003Y985924D01*
G01X-921979Y985767D02*
X-921972Y985924D01*
G01X-884663Y983923D02*
X-884623Y984973D01*
G01X-886632Y983923D02*
X-886591Y984973D01*
G01X-888600Y983923D02*
X-888560Y984973D01*
G01X-890569Y983923D02*
X-890528Y984973D01*
G01X-892537Y983923D02*
X-892497Y984973D01*
G01X-894506Y983923D02*
X-894465Y984973D01*
G01X-896474Y983923D02*
X-896434Y984973D01*
G01X-898443Y983923D02*
X-898402Y984973D01*
G01X-900411Y983923D02*
X-900371Y984973D01*
G01X-902380Y983923D02*
X-902339Y984973D01*
G01X-904348Y983923D02*
X-904308Y984973D01*
G01X-906317Y983923D02*
X-906276Y984973D01*
G01X-908285Y983923D02*
X-908245Y984973D01*
G01X-910254Y983923D02*
X-910213Y984973D01*
G01X-912222Y983923D02*
X-912182Y984973D01*
G01X-914191Y983923D02*
X-914150Y984973D01*
G01X-916159Y983923D02*
X-916119Y984973D01*
G01X-918128Y983923D02*
X-918087Y984973D01*
G01X-920096Y983923D02*
X-920056Y984973D01*
G01X-922065Y983923D02*
X-922024Y984973D01*
G01X-924033Y983923D02*
X-923993Y984973D01*
G01X-889491Y975100D02*
Y972779D01*
G01X-889531Y986643D02*
Y982464D01*
G01X-889727Y986783D02*
Y986639D01*
G01X-890042D02*
Y986783D01*
G01X-890239Y986643D02*
Y982464D01*
G01X-890279Y972779D02*
Y975100D01*
G01X-890475Y977700D02*
Y971598D01*
G01Y987940D02*
Y985583D01*
G01X-891263D02*
Y987940D01*
G01Y977700D02*
Y971598D01*
G01X-891460Y975100D02*
Y972779D01*
G01X-891499Y986643D02*
Y982464D01*
G01X-891696Y986783D02*
Y986639D01*
G01X-891853Y987543D02*
Y979669D01*
G01X-892011Y986639D02*
Y986783D01*
G01X-892208Y986643D02*
Y982464D01*
G01X-892247Y972779D02*
Y975100D01*
G01X-892444Y971598D02*
Y977700D01*
G01Y987940D02*
Y985583D01*
G01X-893231D02*
Y987940D01*
G01Y977700D02*
Y971598D01*
G01X-893428Y975100D02*
Y972779D01*
G01X-893468Y986643D02*
Y982464D01*
G01X-893664Y986783D02*
Y986639D01*
G01X-893979D02*
Y986783D01*
G01X-894176Y986643D02*
Y982464D01*
G01X-894216Y972779D02*
Y975100D01*
G01X-894412Y971598D02*
Y977700D01*
G01Y987940D02*
Y985583D01*
G01X-895200D02*
Y987940D01*
G01Y977700D02*
Y971598D01*
G01X-895397Y975100D02*
Y972779D01*
G01X-895436Y986643D02*
Y982464D01*
G01X-895633Y986783D02*
Y986639D01*
G01X-895948D02*
Y986783D01*
G01X-896145Y986643D02*
Y982464D01*
G01X-896184Y972779D02*
Y975100D01*
G01X-896381Y971598D02*
Y977700D01*
G01Y987940D02*
Y985583D01*
G01X-897168D02*
Y987940D01*
G01Y971598D02*
Y977700D01*
G01X-897365Y975100D02*
Y972779D01*
G01X-897405Y986643D02*
Y982464D01*
G01X-897601Y986783D02*
Y986639D01*
G01X-897916D02*
Y986783D01*
G01X-898113Y986643D02*
Y982464D01*
G01X-898153Y972779D02*
Y975100D01*
G01X-898349Y977700D02*
Y971598D01*
G01Y987940D02*
Y985583D01*
G01X-899137D02*
Y987940D01*
G01Y971598D02*
Y977700D01*
G01X-899334Y975100D02*
Y972779D01*
G01X-899373Y986643D02*
Y982464D01*
G01X-899570Y986783D02*
Y986639D01*
G01X-899885D02*
Y986783D01*
G01X-900082Y986643D02*
Y982464D01*
G01X-900121Y972779D02*
Y975100D01*
G01X-900318Y977700D02*
Y971598D01*
G01Y987940D02*
Y985583D01*
G01X-901105D02*
Y987940D01*
G01Y977700D02*
Y971598D01*
G01X-901302Y975100D02*
Y972779D01*
G01X-901342Y986643D02*
Y982464D01*
G01X-901538Y986783D02*
Y986639D01*
G01X-901853D02*
Y986783D01*
G01X-902050Y986643D02*
Y982464D01*
G01X-902090Y972779D02*
Y975100D01*
G01X-902286Y971598D02*
Y977700D01*
G01Y987940D02*
Y985583D01*
G01X-903074D02*
Y987940D01*
G01Y971598D02*
Y977700D01*
G01X-903271Y975100D02*
Y972779D01*
G01X-903310Y986643D02*
Y982464D01*
G01X-903507Y986783D02*
Y986639D01*
G01X-903822D02*
Y986783D01*
G01X-904019Y986643D02*
Y982464D01*
G01X-904058Y972779D02*
Y975100D01*
G01X-904255Y977700D02*
Y971598D01*
G01Y987940D02*
Y985583D01*
G01X-905042D02*
Y987940D01*
G01Y971598D02*
Y977700D01*
G01X-905239Y975100D02*
Y972779D01*
G01X-905279Y986643D02*
Y982464D01*
G01X-905475Y986783D02*
Y986639D01*
G01X-905790D02*
Y986783D01*
G01X-905987Y986643D02*
Y982464D01*
G01X-906027Y972779D02*
Y975100D01*
G01X-906223Y977700D02*
Y971598D01*
G01Y987940D02*
Y985583D01*
G01X-907011D02*
Y987940D01*
G01Y977700D02*
Y971598D01*
G01X-907208Y975100D02*
Y972779D01*
G01X-907247Y986643D02*
Y982464D01*
G01X-907444Y986783D02*
Y986639D01*
G01X-907759D02*
Y986783D01*
G01X-907956Y986643D02*
Y982464D01*
G01X-907995Y972779D02*
Y975100D01*
G01X-908192Y971598D02*
Y977700D01*
G01Y987940D02*
Y985583D01*
G01X-908979D02*
Y987940D01*
G01Y977700D02*
Y971598D01*
G01X-909176Y975100D02*
Y972779D01*
G01X-909216Y986643D02*
Y982464D01*
G01X-909412Y986783D02*
Y986639D01*
G01X-909491Y997267D02*
Y988409D01*
G01X-909727Y986639D02*
Y986783D01*
G01X-909924Y986643D02*
Y982464D01*
G01X-909964Y972779D02*
Y975100D01*
G01X-910160Y971598D02*
Y977700D01*
G01Y987940D02*
Y985583D01*
G01X-910620Y996991D02*
Y993842D01*
G01X-910948Y985583D02*
Y987940D01*
G01Y977700D02*
Y971598D01*
G01Y996991D02*
Y993842D01*
G01X-911145Y975100D02*
Y972779D01*
G01X-911184Y986643D02*
Y982464D01*
G01X-911381Y986783D02*
Y986639D01*
G01X-911473Y995048D02*
Y994780D01*
G01X-911696Y986639D02*
Y986783D01*
G01X-911801Y995048D02*
Y994780D01*
G01X-911893Y986643D02*
Y982464D01*
G01X-911932Y972779D02*
Y975100D01*
G01X-912129Y971598D02*
Y977700D01*
G01Y987940D02*
Y985583D01*
G01X-912916D02*
Y987940D01*
G01Y971598D02*
Y977700D01*
G01X-913113Y975100D02*
Y972779D01*
G01X-913153Y986643D02*
Y982464D01*
G01X-913244Y995048D02*
Y994780D01*
G01X-913349Y986783D02*
Y986639D01*
G01X-913573Y995048D02*
Y994780D01*
G01X-913664Y986639D02*
Y986783D01*
G01X-913861Y986643D02*
Y982464D01*
G01X-913901Y972779D02*
Y975100D01*
G01X-914098Y977700D02*
Y971598D01*
G01Y987940D02*
Y985583D01*
G01Y995115D02*
Y993842D01*
G01X-914426Y995115D02*
Y993842D01*
G01X-914885Y985583D02*
Y987940D01*
G01Y971598D02*
Y977700D01*
G01X-915082Y975100D02*
Y972779D01*
G01X-915121Y986643D02*
Y982464D01*
G01X-915318Y986783D02*
Y986639D01*
G01X-915607Y995383D02*
Y993842D01*
G01Y995986D02*
Y995651D01*
G01X-915633Y986639D02*
Y986783D01*
G01X-915830Y986643D02*
Y982464D01*
G01X-915869Y972779D02*
Y975100D01*
G01X-915935Y995986D02*
Y993842D01*
G01X-916066Y977700D02*
Y971598D01*
G01Y987940D02*
Y985583D01*
G01X-916460Y995182D02*
Y994914D01*
G01X-916788Y995316D02*
Y995182D01*
G01X-916853Y985583D02*
Y987940D01*
G01Y977700D02*
Y971598D01*
G01X-917050Y975100D02*
Y972779D01*
G01X-917090Y986643D02*
Y982464D01*
G01X-917286Y986783D02*
Y986639D01*
G01X-917601D02*
Y986783D01*
G01X-917798Y986643D02*
Y982464D01*
G01X-917838Y972779D02*
Y975100D01*
G01X-918035Y971598D02*
Y977700D01*
G01Y987940D02*
Y985583D01*
G01X-918166Y995249D02*
Y995182D01*
G01X-918231Y994914D02*
Y994780D01*
G01X-918625Y991755D02*
Y988606D01*
G01X-918822Y985583D02*
Y987940D01*
G01Y977700D02*
Y971598D01*
G01X-919019Y975100D02*
Y972779D01*
G01Y991085D02*
Y988606D01*
G01X-919058Y986643D02*
Y982464D01*
G01X-919084Y995182D02*
Y993842D01*
G01X-919255Y986783D02*
Y986639D01*
G01X-919412Y995182D02*
Y993842D01*
G01X-919570Y986639D02*
Y986783D01*
G01X-919767Y986643D02*
Y982464D01*
G01X-919806Y972779D02*
Y975100D01*
G01X-920003Y971598D02*
Y977700D01*
G01Y987940D02*
Y985583D01*
G01X-920594Y995383D02*
Y993842D01*
G01Y996991D02*
Y995651D01*
G01X-920790Y985583D02*
Y987940D01*
G01Y971598D02*
Y977700D01*
G01X-920922Y996991D02*
Y993842D01*
G01X-920987Y975100D02*
Y972779D01*
G01X-921027Y986643D02*
Y982464D01*
G01X-921223Y986783D02*
Y986639D01*
G01X-921381Y991085D02*
Y988606D01*
G01X-921447Y995182D02*
Y994646D01*
G01X-921538Y986639D02*
Y986783D01*
G01X-921735Y986643D02*
Y982464D01*
G01X-921775Y972779D02*
Y975100D01*
G01Y991755D02*
Y988606D01*
G01Y995115D02*
Y994713D01*
G01X-921972Y977700D02*
Y971598D01*
G01Y987940D02*
Y985583D01*
G01X-922759D02*
Y987940D01*
G01Y977700D02*
Y971598D01*
G01X-922956Y975100D02*
Y972779D01*
G01X-922995Y986643D02*
Y982464D01*
G01X-923192Y986783D02*
Y986639D01*
G01X-923218Y995249D02*
Y994579D01*
G01Y994244D02*
Y992770D01*
G01Y995986D02*
Y995584D01*
G01X-923507Y986639D02*
Y986783D01*
G01X-923546Y995986D02*
Y992770D01*
G01X-923704Y986643D02*
Y982464D01*
G01X-923743Y972779D02*
Y975100D01*
G01X-923940Y971598D02*
Y977700D01*
G01Y987940D02*
Y985583D01*
G01X-924071Y995450D02*
Y993842D01*
G01X-924399Y995450D02*
Y993842D01*
G01X-924727Y985583D02*
Y987940D01*
G01Y977700D02*
Y971598D01*
G01X-924924Y975100D02*
Y972779D01*
G01X-924964Y986643D02*
Y982464D01*
G01X-925121Y995450D02*
Y993842D01*
G01X-925160Y986783D02*
Y986639D01*
G01X-925318Y996007D02*
Y999944D01*
G01X-925449Y995450D02*
Y993842D01*
G01X-925475Y986639D02*
Y986783D01*
G01X-925672Y986643D02*
Y982464D01*
G01X-925712Y972779D02*
Y975100D01*
G01X-925909Y971598D02*
Y977700D01*
G01Y987940D02*
Y985583D01*
G01X-926171Y995517D02*
Y993842D01*
G01Y995986D02*
Y995785D01*
G01X-926499Y995986D02*
Y993842D01*
G01X-926696Y985583D02*
Y987940D01*
G01Y971598D02*
Y977700D01*
G01X-926893Y975100D02*
Y972779D01*
G01X-926932Y986643D02*
Y982464D01*
G01X-927129Y986783D02*
Y986639D01*
G01X-927286Y999944D02*
Y996007D01*
G01X-927444Y986639D02*
Y986783D01*
G01X-927641Y986643D02*
Y982464D01*
G01X-927680Y972779D02*
Y975100D01*
G01X-927877Y977700D02*
Y971598D01*
G01Y987940D02*
Y985583D01*
G01X-928664D02*
Y987940D01*
G01X-895107Y983923D02*
X-895147Y984973D01*
G01X-897075Y983923D02*
X-897116Y984973D01*
G01X-899044Y983923D02*
X-899084Y984973D01*
G01X-901012Y983923D02*
X-901053Y984973D01*
G01X-902981Y983923D02*
X-903021Y984973D01*
G01X-904949Y983923D02*
X-904990Y984973D01*
G01X-906918Y983923D02*
X-906958Y984973D01*
G01X-908886Y983923D02*
X-908927Y984973D01*
G01X-910855Y983923D02*
X-910895Y984973D01*
G01X-912823Y983923D02*
X-912864Y984973D01*
G01X-914792Y983923D02*
X-914832Y984973D01*
G01X-916760Y983923D02*
X-916801Y984973D01*
G01X-918729Y983923D02*
X-918769Y984973D01*
G01X-920697Y983923D02*
X-920738Y984973D01*
G01X-922666Y983923D02*
X-922706Y984973D01*
G01X-924634Y983923D02*
X-924675Y984973D01*
G01X-926603Y983923D02*
X-926643Y984973D01*
G01X-928571Y983923D02*
X-928612Y984973D01*
G01X-897168Y985924D02*
X-897160Y985767D01*
G01X-899137Y985924D02*
X-899129Y985767D01*
G01X-901105Y985924D02*
X-901098Y985767D01*
G01X-903074Y985924D02*
X-903066Y985767D01*
G01X-905042Y985924D02*
X-905035Y985767D01*
G01X-907011Y985924D02*
X-907003Y985767D01*
G01X-908979Y985924D02*
X-908972Y985767D01*
G01X-910948Y985924D02*
X-910940Y985767D01*
G01X-912916Y985924D02*
X-912909Y985767D01*
G01X-914885Y985924D02*
X-914877Y985767D01*
G01X-916853Y985924D02*
X-916846Y985767D01*
G01X-918822Y985924D02*
X-918814Y985767D01*
G01X-920790Y985924D02*
X-920783Y985767D01*
G01X-922759Y985924D02*
X-922751Y985767D01*
G01X-924727Y985924D02*
X-924720Y985767D01*
G01X-926696Y985924D02*
X-926688Y985767D01*
G01X-928664Y985924D02*
X-928657Y985767D01*
G01X-897075Y983923D02*
X-897168Y985583D01*
G01X-899044Y983923D02*
X-899137Y985583D01*
G01X-901012Y983923D02*
X-901105Y985583D01*
G01X-902981Y983923D02*
X-903074Y985583D01*
G01X-904949Y983923D02*
X-905042Y985583D01*
G01X-906918Y983923D02*
X-907011Y985583D01*
G01X-908886Y983923D02*
X-908979Y985583D01*
G01X-910855Y983923D02*
X-910948Y985583D01*
G01X-912823Y983923D02*
X-912916Y985583D01*
G01X-914792Y983923D02*
X-914885Y985583D01*
G01X-916760Y983923D02*
X-916853Y985583D01*
G01X-918729Y983923D02*
X-918822Y985583D01*
G01X-920697Y983923D02*
X-920790Y985583D01*
G01X-922666Y983923D02*
X-922759Y985583D01*
G01X-924634Y983923D02*
X-924727Y985583D01*
G01X-926603Y983923D02*
X-926696Y985583D01*
G01X-928571Y983923D02*
X-928664Y985583D01*
G01X-897116Y984973D02*
X-897160Y985767D01*
G01X-899084Y984973D02*
X-899129Y985767D01*
G01X-901053Y984973D02*
X-901098Y985767D01*
G01X-903021Y984973D02*
X-903066Y985767D01*
G01X-904990Y984973D02*
X-905035Y985767D01*
G01X-906958Y984973D02*
X-907003Y985767D01*
G01X-908927Y984973D02*
X-908972Y985767D01*
G01X-910895Y984973D02*
X-910940Y985767D01*
G01X-912864Y984973D02*
X-912909Y985767D01*
G01X-914832Y984973D02*
X-914877Y985767D01*
G01X-916801Y984973D02*
X-916846Y985767D01*
G01X-918769Y984973D02*
X-918814Y985767D01*
G01X-920738Y984973D02*
X-920783Y985767D01*
G01X-922706Y984973D02*
X-922751Y985767D01*
G01X-924675Y984973D02*
X-924720Y985767D01*
G01X-926643Y984973D02*
X-926688Y985767D01*
G01X-928612Y984973D02*
X-928657Y985767D01*
G01X-919544Y995919D02*
X-919741Y995986D01*
G01X-917838Y993909D02*
X-918035Y993976D01*
G01X-924334Y995919D02*
X-924531Y995986D01*
G01X-925384Y995919D02*
X-925580Y995986D01*
G01X-911998Y995919D02*
X-912260Y995986D01*
G01X-912129Y995651D02*
X-912391Y995718D01*
G01X-914754Y995651D02*
X-915016Y995718D01*
G01X-912654Y994110D02*
X-912916Y994177D01*
G01X-919741Y995651D02*
X-920003Y995718D01*
G01X-912785Y993842D02*
X-913048Y993909D01*
G01X-921972Y995919D02*
X-922234Y995986D01*
G01X-917510Y994110D02*
X-917772Y994177D01*
G01X-922628D02*
X-922890Y994244D01*
G01X-922628Y993842D02*
X-922890Y993909D01*
G01X-917050Y995919D02*
X-917444Y995986D01*
G01X-917116Y995651D02*
X-917510Y995718D01*
G01X-917444Y993842D02*
X-917838Y993909D01*
G01X-913441Y995517D02*
X-913507Y995316D01*
G01X-911473Y994780D02*
X-911604Y994311D01*
G01X-911801Y994780D02*
X-911867Y994512D01*
G01X-913179Y995316D02*
X-913244Y995048D01*
G01X-913507Y995316D02*
X-913573Y995048D01*
G01X-916460Y994512D02*
X-916525Y994244D01*
G01X-921447Y994646D02*
X-921512Y994378D01*
G01X-918494Y995316D02*
X-918559Y994914D01*
G01X-922065Y983923D02*
X-921979Y985433D01*
G01Y985767D02*
X-922024Y984973D01*
G01X-924033Y983923D02*
X-923940Y985583D01*
G01X-923948Y985767D02*
X-923993Y984973D01*
G01X-926002Y983923D02*
X-925909Y985583D01*
G01X-925916Y985767D02*
X-925961Y984973D01*
G01X-927970Y983923D02*
X-927877Y985583D01*
G01X-927885Y985767D02*
X-927930Y984973D01*
G01X-923948Y985767D02*
X-923940Y985924D01*
G01X-925916Y985767D02*
X-925909Y985924D01*
G01X-927885Y985767D02*
X-927877Y985924D01*
G01X-926002Y983923D02*
X-925961Y984973D01*
G01X-927970Y983923D02*
X-927930Y984973D01*
G01X-930239Y1006736D02*
Y995909D01*
G01X-930436Y982019D02*
Y973960D01*
G01X-930712Y997267D02*
Y988409D01*
G01X-931519Y980653D02*
Y990495D01*
G01X-932700Y979472D02*
Y983409D01*
G01X-934964Y995909D02*
Y1006736D01*
G01X-935160Y1005259D02*
Y973960D01*
G01X-925318Y996007D02*
X-927286D01*
G01X-923218Y995986D02*
X-923546D01*
G01X-926171D02*
X-926499D01*
G01X-925580D02*
X-925843D01*
G01X-924531D02*
X-924793D01*
G01X-922234D02*
X-922628D01*
G01X-919741D02*
X-920003D01*
G01X-915607D02*
X-915935D01*
G01X-914754D02*
X-915016D01*
G01X-912260D02*
X-912785D01*
G01X-930239Y995909D02*
X-934964D01*
G01X-925712Y995718D02*
X-925843D01*
G01X-924662D02*
X-924859D01*
G01X-912391D02*
X-912654D01*
G01X-922234Y995651D02*
X-922628D01*
G01X-916788Y995182D02*
X-918166D01*
G01X-927746Y994914D02*
X-928927D01*
G01X-916460D02*
X-918231D01*
G01X-927680Y994646D02*
X-928993D01*
G01X-916460Y994512D02*
X-916788D01*
G01X-922365Y994177D02*
X-922628D01*
G01X-912391Y994110D02*
X-912654D01*
G01X-929255Y993842D02*
X-929649D01*
G01X-927024D02*
X-927418D01*
G01X-925121D02*
X-925449D01*
G01X-924071D02*
X-924399D01*
G01X-926171D02*
X-926499D01*
G01X-920594D02*
X-920922D01*
G01X-922234D02*
X-922628D01*
G01X-919084D02*
X-919412D01*
G01X-914098D02*
X-914426D01*
G01X-915607D02*
X-915935D01*
G01X-910620D02*
X-910948D01*
G01X-912260D02*
X-912785D01*
G01X-923218Y992770D02*
X-923546D01*
G01X-921184Y991755D02*
X-921775D01*
G01X-918625D02*
X-919216D01*
G01X-869905Y990495D02*
X-931519D01*
G01X-852188D02*
X-865574D01*
G01X-921381Y988606D02*
X-921775D01*
G01X-919937D02*
X-920462D01*
G01X-918625D02*
X-919019D01*
G01X-927877Y987940D02*
X-928664D01*
G01X-925909D02*
X-926696D01*
G01X-923940D02*
X-924727D01*
G01X-921972D02*
X-922759D01*
G01X-920003D02*
X-920790D01*
G01X-918035D02*
X-918822D01*
G01X-916066D02*
X-916853D01*
G01X-914098D02*
X-914885D01*
G01X-912129D02*
X-912916D01*
G01X-910160D02*
X-910948D01*
G01X-908192D02*
X-908979D01*
G01X-906223D02*
X-907011D01*
G01X-904255D02*
X-905042D01*
G01X-902286D02*
X-903074D01*
G01X-900318D02*
X-901105D01*
G01X-898349D02*
X-899137D01*
G01X-896381D02*
X-897168D01*
G01X-894412D02*
X-895200D01*
G01X-892444D02*
X-893231D01*
G01X-890475D02*
X-891263D01*
G01X-888507D02*
X-889294D01*
G01X-886538D02*
X-887326D01*
G01X-884570D02*
X-885357D01*
G01X-882601D02*
X-883389D01*
G01X-880633D02*
X-881420D01*
G01X-878664D02*
X-879452D01*
G01X-876696D02*
X-877483D01*
G01X-874727D02*
X-875515D01*
G01X-872759D02*
X-873546D01*
G01X-910279Y987621D02*
X-929924D01*
G01X-927877Y987257D02*
X-928664D01*
G01X-925909D02*
X-926696D01*
G01X-923940D02*
X-924727D01*
G01X-921972D02*
X-922759D01*
G01X-920003D02*
X-920790D01*
G01X-918035D02*
X-918822D01*
G01X-916066D02*
X-916853D01*
G01X-914098D02*
X-914885D01*
G01X-912129D02*
X-912916D01*
G01X-910160D02*
X-910948D01*
G01X-908192D02*
X-908979D01*
G01X-906223D02*
X-907011D01*
G01X-904255D02*
X-905042D01*
G01X-902286D02*
X-903074D01*
G01X-900318D02*
X-901105D01*
G01X-898349D02*
X-899137D01*
G01X-896381D02*
X-897168D01*
G01X-894412D02*
X-895200D01*
G01X-892444D02*
X-893231D01*
G01X-890475D02*
X-891263D01*
G01X-888507D02*
X-889294D01*
G01X-886538D02*
X-887326D01*
G01X-884570D02*
X-885357D01*
G01X-882601D02*
X-883389D01*
G01X-880633D02*
X-881420D01*
G01X-878664D02*
X-879452D01*
G01X-876696D02*
X-877483D01*
G01X-874727D02*
X-875515D01*
G01X-872759D02*
X-873546D01*
G01X-927877Y987195D02*
X-928664D01*
G01X-925909D02*
X-926696D01*
G01X-923940D02*
X-924727D01*
G01X-921972D02*
X-922759D01*
G01X-920003D02*
X-920790D01*
G01X-918035D02*
X-918822D01*
G01X-916066D02*
X-916853D01*
G01X-914098D02*
X-914885D01*
G01X-912129D02*
X-912916D01*
G01X-910160D02*
X-910948D01*
G01X-908192D02*
X-908979D01*
G01X-906223D02*
X-907011D01*
G01X-904255D02*
X-905042D01*
G01X-902286D02*
X-903074D01*
G01X-900318D02*
X-901105D01*
G01X-898349D02*
X-899137D01*
G01X-896381D02*
X-897168D01*
G01X-894412D02*
X-895200D01*
G01X-892444D02*
X-893231D01*
G01X-890475D02*
X-891263D01*
G01X-888507D02*
X-889294D01*
G01X-886538D02*
X-887326D01*
G01X-884570D02*
X-885357D01*
G01X-882601D02*
X-883389D01*
G01X-880633D02*
X-881420D01*
G01X-878664D02*
X-879452D01*
G01X-876696D02*
X-877483D01*
G01X-874727D02*
X-875515D01*
G01X-872759D02*
X-873546D01*
G01Y986868D02*
X-872759D01*
G01X-875515D02*
X-874727D01*
G01X-879452D02*
X-878664D01*
G01X-877483D02*
X-876696D01*
G01X-883389D02*
X-882601D01*
G01X-881420D02*
X-880633D01*
G01X-885357D02*
X-884570D01*
G01X-889294D02*
X-888507D01*
G01X-887326D02*
X-886538D01*
G01X-893231D02*
X-892444D01*
G01X-891263D02*
X-890475D01*
G01X-895200D02*
X-894412D01*
G01X-899137D02*
X-898349D01*
G01X-897168D02*
X-896381D01*
G01X-903074D02*
X-902286D01*
G01X-901105D02*
X-900318D01*
G01X-905042D02*
X-904255D01*
G01X-908979D02*
X-908192D01*
G01X-907011D02*
X-906223D01*
G01X-912916D02*
X-912129D01*
G01X-910948D02*
X-910160D01*
G01X-916853D02*
X-916066D01*
G01X-914885D02*
X-914098D01*
G01X-918822D02*
X-918035D01*
G01X-922759D02*
X-921972D01*
G01X-920790D02*
X-920003D01*
G01X-926696D02*
X-925909D01*
G01X-924727D02*
X-923940D01*
G01X-928664D02*
X-927877D01*
G01X-872326Y986783D02*
X-872011D01*
G01X-876263D02*
X-875948D01*
G01X-874294D02*
X-873979D01*
G01X-880200D02*
X-879885D01*
G01X-878231D02*
X-877916D01*
G01X-882168D02*
X-881853D01*
G01X-886105D02*
X-885790D01*
G01X-884137D02*
X-883822D01*
G01X-890042D02*
X-889727D01*
G01X-888074D02*
X-887759D01*
G01X-892011D02*
X-891696D01*
G01X-895948D02*
X-895633D01*
G01X-893979D02*
X-893664D01*
G01X-899885D02*
X-899570D01*
G01X-897916D02*
X-897601D01*
G01X-901853D02*
X-901538D01*
G01X-905790D02*
X-905475D01*
G01X-903822D02*
X-903507D01*
G01X-909727D02*
X-909412D01*
G01X-907759D02*
X-907444D01*
G01X-911696D02*
X-911381D01*
G01X-915633D02*
X-915318D01*
G01X-913664D02*
X-913349D01*
G01X-919570D02*
X-919255D01*
G01X-917601D02*
X-917286D01*
G01X-923507D02*
X-923192D01*
G01X-921538D02*
X-921223D01*
G01X-925475D02*
X-925160D01*
G01X-927444D02*
X-927129D01*
G01X-872326Y986639D02*
X-872011D01*
G01X-876263D02*
X-875948D01*
G01X-874294D02*
X-873979D01*
G01X-880200D02*
X-879885D01*
G01X-878231D02*
X-877916D01*
G01X-882168D02*
X-881853D01*
G01X-886105D02*
X-885790D01*
G01X-884137D02*
X-883822D01*
G01X-890042D02*
X-889727D01*
G01X-888074D02*
X-887759D01*
G01X-892011D02*
X-891696D01*
G01X-895948D02*
X-895633D01*
G01X-893979D02*
X-893664D01*
G01X-899885D02*
X-899570D01*
G01X-897916D02*
X-897601D01*
G01X-901853D02*
X-901538D01*
G01X-905790D02*
X-905475D01*
G01X-903822D02*
X-903507D01*
G01X-909727D02*
X-909412D01*
G01X-907759D02*
X-907444D01*
G01X-911696D02*
X-911381D01*
G01X-915633D02*
X-915318D01*
G01X-913664D02*
X-913349D01*
G01X-919570D02*
X-919255D01*
G01X-917601D02*
X-917286D01*
G01X-923507D02*
X-923192D01*
G01X-921538D02*
X-921223D01*
G01X-925475D02*
X-925160D01*
G01X-927444D02*
X-927129D01*
G01X-926932Y986259D02*
X-927641D01*
G01X-924964D02*
X-925672D01*
G01X-922995D02*
X-923704D01*
G01X-921027D02*
X-921735D01*
G01X-919058D02*
X-919767D01*
G01X-917090D02*
X-917798D01*
G01X-915121D02*
X-915830D01*
G01X-913153D02*
X-913861D01*
G01X-911184D02*
X-911893D01*
G01X-909216D02*
X-909924D01*
G01X-907247D02*
X-907956D01*
G01X-905279D02*
X-905987D01*
G01X-903310D02*
X-904019D01*
G01X-901342D02*
X-902050D01*
G01X-899373D02*
X-900082D01*
G01X-897405D02*
X-898113D01*
G01X-895436D02*
X-896145D01*
G01X-893468D02*
X-894176D01*
G01X-891499D02*
X-892208D01*
G01X-889531D02*
X-890239D01*
G01X-887562D02*
X-888271D01*
G01X-885594D02*
X-886302D01*
G01X-883625D02*
X-884334D01*
G01X-881657D02*
X-882365D01*
G01X-879688D02*
X-880397D01*
G01X-877720D02*
X-878428D01*
G01X-875751D02*
X-876460D01*
G01X-873783D02*
X-874491D01*
G01X-871814D02*
X-872523D01*
G01Y986223D02*
X-871814D01*
G01X-876460D02*
X-875751D01*
G01X-874491D02*
X-873783D01*
G01X-880397D02*
X-879688D01*
G01X-878428D02*
X-877720D01*
G01X-882365D02*
X-881657D01*
G01X-886302D02*
X-885594D01*
G01X-884334D02*
X-883625D01*
G01X-890239D02*
X-889531D01*
G01X-888271D02*
X-887562D01*
G01X-892208D02*
X-891499D01*
G01X-896145D02*
X-895436D01*
G01X-894176D02*
X-893468D01*
G01X-900082D02*
X-899373D01*
G01X-898113D02*
X-897405D01*
G01X-902050D02*
X-901342D01*
G01X-905987D02*
X-905279D01*
G01X-904019D02*
X-903310D01*
G01X-909924D02*
X-909216D01*
G01X-907956D02*
X-907247D01*
G01X-911893D02*
X-911184D01*
G01X-915830D02*
X-915121D01*
G01X-913861D02*
X-913153D01*
G01X-919767D02*
X-919058D01*
G01X-917798D02*
X-917090D01*
G01X-921735D02*
X-921027D01*
G01X-925672D02*
X-924964D01*
G01X-923704D02*
X-922995D01*
G01X-927641D02*
X-926932D01*
G01X-865574Y986165D02*
X-852188D01*
G01X-931519D02*
X-869905D01*
G01X-926932Y985891D02*
X-927641D01*
G01X-924964D02*
X-925672D01*
G01X-922995D02*
X-923704D01*
G01X-921027D02*
X-921735D01*
G01X-919058D02*
X-919767D01*
G01X-917090D02*
X-917798D01*
G01X-915121D02*
X-915830D01*
G01X-913153D02*
X-913861D01*
G01X-911184D02*
X-911893D01*
G01X-909216D02*
X-909924D01*
G01X-907247D02*
X-907956D01*
G01X-905279D02*
X-905987D01*
G01X-903310D02*
X-904019D01*
G01X-901342D02*
X-902050D01*
G01X-899373D02*
X-900082D01*
G01X-897405D02*
X-898113D01*
G01X-895436D02*
X-896145D01*
G01X-893468D02*
X-894176D01*
G01X-891499D02*
X-892208D01*
G01X-889531D02*
X-890239D01*
G01X-887562D02*
X-888271D01*
G01X-885594D02*
X-886302D01*
G01X-883625D02*
X-884334D01*
G01X-881657D02*
X-882365D01*
G01X-879688D02*
X-880397D01*
G01X-877720D02*
X-878428D01*
G01X-875751D02*
X-876460D01*
G01X-873783D02*
X-874491D01*
G01X-871814D02*
X-872523D01*
G01X-927885Y985767D02*
X-928657D01*
G01X-925916D02*
X-926688D01*
G01X-923948D02*
X-924720D01*
G01X-921979D02*
X-922751D01*
G01X-920011D02*
X-920783D01*
G01X-918042D02*
X-918814D01*
G01X-916074D02*
X-916846D01*
G01X-914105D02*
X-914877D01*
G01X-912137D02*
X-912909D01*
G01X-910168D02*
X-910940D01*
G01X-908200D02*
X-908972D01*
G01X-906231D02*
X-907003D01*
G01X-904263D02*
X-905035D01*
G01X-902294D02*
X-903066D01*
G01X-900326D02*
X-901098D01*
G01X-898357D02*
X-899129D01*
G01X-896389D02*
X-897160D01*
G01X-894420D02*
X-895192D01*
G01X-892452D02*
X-893223D01*
G01X-890483D02*
X-891255D01*
G01X-888515D02*
X-889286D01*
G01X-886546D02*
X-887318D01*
G01X-884578D02*
X-885349D01*
G01X-882609D02*
X-883381D01*
G01X-880641D02*
X-881412D01*
G01X-878672D02*
X-879444D01*
G01X-876704D02*
X-877475D01*
G01X-874735D02*
X-875507D01*
G01X-872767D02*
X-873538D01*
G01Y985433D02*
X-872767D01*
G01X-875507D02*
X-874735D01*
G01X-879444D02*
X-878672D01*
G01X-877475D02*
X-876704D01*
G01X-883381D02*
X-882609D01*
G01X-881412D02*
X-880641D01*
G01X-885349D02*
X-884578D01*
G01X-889286D02*
X-888515D01*
G01X-887318D02*
X-886546D01*
G01X-893223D02*
X-892452D01*
G01X-891255D02*
X-890483D01*
G01X-895192D02*
X-894420D01*
G01X-899129D02*
X-898357D01*
G01X-897160D02*
X-896389D01*
G01X-903066D02*
X-902294D01*
G01X-901098D02*
X-900326D01*
G01X-905035D02*
X-904263D01*
G01X-908972D02*
X-908200D01*
G01X-907003D02*
X-906231D01*
G01X-912909D02*
X-912137D01*
G01X-910940D02*
X-910168D01*
G01X-916846D02*
X-916074D01*
G01X-914877D02*
X-914105D01*
G01X-918814D02*
X-918042D01*
G01X-922751D02*
X-921979D01*
G01X-920783D02*
X-920011D01*
G01X-926688D02*
X-925916D01*
G01X-924720D02*
X-923948D01*
G01X-928657D02*
X-927885D01*
G01X-872523Y985043D02*
X-871814D01*
G01X-876460D02*
X-875751D01*
G01X-874491D02*
X-873783D01*
G01X-880397D02*
X-879688D01*
G01X-878428D02*
X-877720D01*
G01X-882365D02*
X-881657D01*
G01X-886302D02*
X-885594D01*
G01X-884334D02*
X-883625D01*
G01X-890239D02*
X-889531D01*
G01X-888271D02*
X-887562D01*
G01X-892208D02*
X-891499D01*
G01X-896145D02*
X-895436D01*
G01X-894176D02*
X-893468D01*
G01X-900082D02*
X-899373D01*
G01X-898113D02*
X-897405D01*
G01X-902050D02*
X-901342D01*
G01X-905987D02*
X-905279D01*
G01X-904019D02*
X-903310D01*
G01X-909924D02*
X-909216D01*
G01X-907956D02*
X-907247D01*
G01X-911893D02*
X-911184D01*
G01X-915830D02*
X-915121D01*
G01X-913861D02*
X-913153D01*
G01X-919767D02*
X-919058D01*
G01X-917798D02*
X-917090D01*
G01X-921735D02*
X-921027D01*
G01X-925672D02*
X-924964D01*
G01X-923704D02*
X-922995D01*
G01X-927641D02*
X-926932D01*
G01X-927930Y984973D02*
X-928612D01*
G01X-925961D02*
X-926643D01*
G01X-923993D02*
X-924675D01*
G01X-922024D02*
X-922706D01*
G01X-920056D02*
X-920738D01*
G01X-918087D02*
X-918769D01*
G01X-916119D02*
X-916801D01*
G01X-914150D02*
X-914832D01*
G01X-912182D02*
X-912864D01*
G01X-910213D02*
X-910895D01*
G01X-908245D02*
X-908927D01*
G01X-906276D02*
X-906958D01*
G01X-904308D02*
X-904990D01*
G01X-902339D02*
X-903021D01*
G01X-900371D02*
X-901053D01*
G01X-898402D02*
X-899084D01*
G01X-896434D02*
X-897116D01*
G01X-894465D02*
X-895147D01*
G01X-892497D02*
X-893179D01*
G01X-890528D02*
X-891210D01*
G01X-888560D02*
X-889242D01*
G01X-886591D02*
X-887273D01*
G01X-884623D02*
X-885305D01*
G01X-882654D02*
X-883336D01*
G01X-880686D02*
X-881368D01*
G01X-878717D02*
X-879399D01*
G01X-876749D02*
X-877431D01*
G01X-874780D02*
X-875462D01*
G01X-872812D02*
X-873494D01*
G01X-926932Y984866D02*
X-927641D01*
G01X-924964D02*
X-925672D01*
G01X-922995D02*
X-923704D01*
G01X-921027D02*
X-921735D01*
G01X-919058D02*
X-919767D01*
G01X-917090D02*
X-917798D01*
G01X-915121D02*
X-915830D01*
G01X-913153D02*
X-913861D01*
G01X-911184D02*
X-911893D01*
G01X-909216D02*
X-909924D01*
G01X-907247D02*
X-907956D01*
G01X-905279D02*
X-905987D01*
G01X-903310D02*
X-904019D01*
G01X-901342D02*
X-902050D01*
G01X-899373D02*
X-900082D01*
G01X-897405D02*
X-898113D01*
G01X-895436D02*
X-896145D01*
G01X-893468D02*
X-894176D01*
G01X-891499D02*
X-892208D01*
G01X-889531D02*
X-890239D01*
G01X-887562D02*
X-888271D01*
G01X-885594D02*
X-886302D01*
G01X-883625D02*
X-884334D01*
G01X-881657D02*
X-882365D01*
G01X-879688D02*
X-880397D01*
G01X-877720D02*
X-878428D01*
G01X-875751D02*
X-876460D01*
G01X-873783D02*
X-874491D01*
G01X-871814D02*
X-872523D01*
G01X-927970Y983923D02*
X-928571D01*
G01X-926002D02*
X-926603D01*
G01X-924033D02*
X-924634D01*
G01X-922065D02*
X-922666D01*
G01X-920096D02*
X-920697D01*
G01X-918128D02*
X-918729D01*
G01X-916159D02*
X-916760D01*
G01X-914191D02*
X-914792D01*
G01X-912222D02*
X-912823D01*
G01X-910254D02*
X-910855D01*
G01X-908285D02*
X-908886D01*
G01X-906317D02*
X-906918D01*
G01X-904348D02*
X-904949D01*
G01X-902380D02*
X-902981D01*
G01X-900411D02*
X-901012D01*
G01X-898443D02*
X-899044D01*
G01X-896474D02*
X-897075D01*
G01X-894506D02*
X-895107D01*
G01X-892537D02*
X-893138D01*
G01X-890569D02*
X-891170D01*
G01X-888600D02*
X-889201D01*
G01X-886632D02*
X-887233D01*
G01X-884663D02*
X-885264D01*
G01X-882695D02*
X-883296D01*
G01X-880726D02*
X-881327D01*
G01X-878758D02*
X-879359D01*
G01X-876789D02*
X-877390D01*
G01X-874821D02*
X-875422D01*
G01X-872852D02*
X-873453D01*
G01X-926932Y983724D02*
X-927641D01*
G01X-924964D02*
X-925672D01*
G01X-922995D02*
X-923704D01*
G01X-921027D02*
X-921735D01*
G01X-919058D02*
X-919767D01*
G01X-917090D02*
X-917798D01*
G01X-915121D02*
X-915830D01*
G01X-913153D02*
X-913861D01*
G01X-911184D02*
X-911893D01*
G01X-909216D02*
X-909924D01*
G01X-907247D02*
X-907956D01*
G01X-905279D02*
X-905987D01*
G01X-903310D02*
X-904019D01*
G01X-901342D02*
X-902050D01*
G01X-899373D02*
X-900082D01*
G01X-897405D02*
X-898113D01*
G01X-895436D02*
X-896145D01*
G01X-893468D02*
X-894176D01*
G01X-891499D02*
X-892208D01*
G01X-889531D02*
X-890239D01*
G01X-887562D02*
X-888271D01*
G01X-885594D02*
X-886302D01*
G01X-883625D02*
X-884334D01*
G01X-881657D02*
X-882365D01*
G01X-879688D02*
X-880397D01*
G01X-877720D02*
X-878428D01*
G01X-875751D02*
X-876460D01*
G01X-873783D02*
X-874491D01*
G01X-871814D02*
X-872523D01*
G01X-895790Y983606D02*
X-887916D01*
G01X-932995D02*
X-935160D01*
G01Y983409D02*
X-848546D01*
G01X-926932Y982464D02*
X-927641D01*
G01X-924964D02*
X-925672D01*
G01X-922995D02*
X-923704D01*
G01X-921027D02*
X-921735D01*
G01X-919058D02*
X-919767D01*
G01X-917090D02*
X-917798D01*
G01X-915121D02*
X-915830D01*
G01X-913153D02*
X-913861D01*
G01X-911184D02*
X-911893D01*
G01X-909216D02*
X-909924D01*
G01X-907247D02*
X-907956D01*
G01X-905279D02*
X-905987D01*
G01X-903310D02*
X-904019D01*
G01X-901342D02*
X-902050D01*
G01X-899373D02*
X-900082D01*
G01X-897405D02*
X-898113D01*
G01X-895436D02*
X-896145D01*
G01X-893468D02*
X-894176D01*
G01X-891499D02*
X-892208D01*
G01X-889531D02*
X-890239D01*
G01X-887562D02*
X-888271D01*
G01X-885594D02*
X-886302D01*
G01X-883625D02*
X-884334D01*
G01X-881657D02*
X-882365D01*
G01X-879688D02*
X-880397D01*
G01X-877720D02*
X-878428D01*
G01X-875751D02*
X-876460D01*
G01X-873783D02*
X-874491D01*
G01X-871814D02*
X-872523D01*
G01X-932700Y979472D02*
X-935160D01*
G01X-918100Y995383D02*
X-918166Y995249D01*
G01X-918363Y995584D02*
X-918494Y995316D01*
G01X-921840Y994512D02*
X-921906Y994378D01*
G01X-923153Y995718D02*
X-923218Y995584D01*
G01X-925056D02*
X-925121Y995450D01*
G01X-919019Y991085D02*
X-919937Y988606D01*
G01X-919216Y991755D02*
X-920200Y988941D01*
G01X-928599Y996991D02*
X-929649Y993842D01*
G01X-916788Y994512D02*
X-916853Y994311D01*
G01X-921775Y994713D02*
X-921840Y994512D01*
G01X-928993Y994646D02*
X-929255Y993842D01*
G01X-928336Y996723D02*
X-928927Y994914D01*
G01X-876696Y977700D02*
X-875515D01*
G01X-878664D02*
X-877483D01*
G01X-886538D02*
X-885357D01*
G01X-888507D02*
X-887326D01*
G01X-892444D02*
X-891263D01*
G01X-894412D02*
X-893231D01*
G01X-896381D02*
X-895200D01*
G01X-902286D02*
X-901105D01*
G01X-908192D02*
X-907011D01*
G01X-910160D02*
X-908979D01*
G01X-912129D02*
X-910948D01*
G01X-918035D02*
X-916853D01*
G01X-920003D02*
X-918822D01*
G01X-923940D02*
X-922759D01*
G01X-925909D02*
X-924727D01*
G01X-926696D02*
X-927877D01*
G01X-920790D02*
X-921972D01*
G01X-914885D02*
X-916066D01*
G01X-912916D02*
X-914098D01*
G01X-905042D02*
X-906223D01*
G01X-903074D02*
X-904255D01*
G01X-899137D02*
X-900318D01*
G01X-897168D02*
X-898349D01*
G01X-889294D02*
X-890475D01*
G01X-883389D02*
X-884570D01*
G01X-881420D02*
X-882601D01*
G01X-879452D02*
X-880633D01*
G01X-873546D02*
X-874727D01*
G01X-871578D02*
X-872759D01*
G01X-926893Y975100D02*
X-927680D01*
G01X-922956D02*
X-923743D01*
G01X-924924D02*
X-925712D01*
G01X-920987D02*
X-921775D01*
G01X-917050D02*
X-917838D01*
G01X-919019D02*
X-919806D01*
G01X-913113D02*
X-913901D01*
G01X-915082D02*
X-915869D01*
G01X-911145D02*
X-911932D01*
G01X-907208D02*
X-907995D01*
G01X-909176D02*
X-909964D01*
G01X-903271D02*
X-904058D01*
G01X-905239D02*
X-906027D01*
G01X-901302D02*
X-902090D01*
G01X-897365D02*
X-898153D01*
G01X-899334D02*
X-900121D01*
G01X-893428D02*
X-894216D01*
G01X-895397D02*
X-896184D01*
G01X-891460D02*
X-892247D01*
G01X-887523D02*
X-888310D01*
G01X-889491D02*
X-890279D01*
G01X-883586D02*
X-884373D01*
G01X-885554D02*
X-886342D01*
G01X-881617D02*
X-882405D01*
G01X-877680D02*
X-878468D01*
G01X-879649D02*
X-880436D01*
G01X-873743D02*
X-874531D01*
G01X-875712D02*
X-876499D01*
G01X-871775D02*
X-872562D01*
G01Y974551D02*
X-871775D01*
G01X-874531D02*
X-873743D01*
G01X-876499D02*
X-875712D01*
G01X-878468D02*
X-877680D01*
G01X-880436D02*
X-879649D01*
G01X-882405D02*
X-881617D01*
G01X-884373D02*
X-883586D01*
G01X-886342D02*
X-885554D01*
G01X-888310D02*
X-887523D01*
G01X-890279D02*
X-889491D01*
G01X-892247D02*
X-891460D01*
G01X-894216D02*
X-893428D01*
G01X-896184D02*
X-895397D01*
G01X-898153D02*
X-897365D01*
G01X-900121D02*
X-899334D01*
G01X-902090D02*
X-901302D01*
G01X-904058D02*
X-903271D01*
G01X-906027D02*
X-905239D01*
G01X-907995D02*
X-907208D01*
G01X-909964D02*
X-909176D01*
G01X-911932D02*
X-911145D01*
G01X-913901D02*
X-913113D01*
G01X-915869D02*
X-915082D01*
G01X-917838D02*
X-917050D01*
G01X-919806D02*
X-919019D01*
G01X-921775D02*
X-920987D01*
G01X-923743D02*
X-922956D01*
G01X-925712D02*
X-924924D01*
G01X-927680D02*
X-926893D01*
G01X-848546Y973960D02*
X-935160D01*
G01X-927090Y972582D02*
X-927483D01*
G01X-923153D02*
X-923546D01*
G01X-925121D02*
X-925515D01*
G01X-921184D02*
X-921578D01*
G01X-917247D02*
X-917641D01*
G01X-919216D02*
X-919609D01*
G01X-913310D02*
X-913704D01*
G01X-915279D02*
X-915672D01*
G01X-911342D02*
X-911735D01*
G01X-907405D02*
X-907798D01*
G01X-909373D02*
X-909767D01*
G01X-903468D02*
X-903861D01*
G01X-905436D02*
X-905830D01*
G01X-901499D02*
X-901893D01*
G01X-897562D02*
X-897956D01*
G01X-899531D02*
X-899924D01*
G01X-893625D02*
X-894019D01*
G01X-895594D02*
X-895987D01*
G01X-891657D02*
X-892050D01*
G01X-887720D02*
X-888113D01*
G01X-889688D02*
X-890082D01*
G01X-883783D02*
X-884176D01*
G01X-885751D02*
X-886145D01*
G01X-881814D02*
X-882208D01*
G01X-877877D02*
X-878271D01*
G01X-879846D02*
X-880239D01*
G01X-873940D02*
X-874334D01*
G01X-875909D02*
X-876302D01*
G01X-871972D02*
X-872365D01*
G01X-872759Y971598D02*
X-871578D01*
G01X-874727D02*
X-873546D01*
G01X-882601D02*
X-881420D01*
G01X-880633D02*
X-879452D01*
G01X-884570D02*
X-883389D01*
G01X-890475D02*
X-889294D01*
G01X-900318D02*
X-899137D01*
G01X-898349D02*
X-897168D01*
G01X-906223D02*
X-905042D01*
G01X-904255D02*
X-903074D01*
G01X-916066D02*
X-914885D01*
G01X-914098D02*
X-912916D01*
G01X-921972D02*
X-920790D01*
G01X-927877D02*
X-926696D01*
G01X-922759D02*
X-923940D01*
G01X-924727D02*
X-925909D01*
G01X-916853D02*
X-918035D01*
G01X-918822D02*
X-920003D01*
G01X-910948D02*
X-912129D01*
G01X-907011D02*
X-908192D01*
G01X-908979D02*
X-910160D01*
G01X-901105D02*
X-902286D01*
G01X-893231D02*
X-894412D01*
G01X-895200D02*
X-896381D01*
G01X-891263D02*
X-892444D01*
G01X-887326D02*
X-888507D01*
G01X-885357D02*
X-886538D01*
G01X-877483D02*
X-878664D01*
G01X-875515D02*
X-876696D01*
G01X-917050Y994177D02*
X-917510Y994110D01*
G01X-916985Y993909D02*
X-917444Y993842D01*
G01Y995986D02*
X-917838Y995919D01*
G01X-922628Y995986D02*
X-922890Y995919D01*
G01X-922628Y995651D02*
X-922890Y995584D01*
G01X-920003Y995986D02*
X-920265Y995919D01*
G01X-920003Y995718D02*
X-920265Y995651D01*
G01X-911604Y994311D02*
X-911735Y994110D01*
G01X-911867Y994512D02*
X-911998Y994311D01*
G01X-913048Y995517D02*
X-913179Y995316D01*
G01X-913310Y995718D02*
X-913441Y995517D01*
G01X-923087Y995450D02*
X-923218Y995249D01*
G01X-917510Y995718D02*
X-917772Y995651D01*
G01X-922103Y994244D02*
X-922365Y994177D01*
G01X-915016Y995986D02*
X-915279Y995919D01*
G01X-915016Y995718D02*
X-915279Y995651D01*
G01X-921972Y993909D02*
X-922234Y993842D01*
G01X-912785Y995986D02*
X-913048Y995919D01*
G01X-912654Y995718D02*
X-912916Y995651D01*
G01X-912129Y994177D02*
X-912391Y994110D01*
G01X-911998Y993909D02*
X-912260Y993842D01*
G01X-911735Y994110D02*
X-911867Y993976D01*
G01X-911998Y994311D02*
X-912129Y994177D01*
G01X-912916Y995651D02*
X-913048Y995517D01*
G01X-913179Y995852D02*
X-913310Y995718D01*
G01X-916525Y994244D02*
X-916722Y994043D01*
G01X-915475Y995517D02*
X-915607Y995383D01*
G01X-915475Y995785D02*
X-915607Y995651D01*
G01X-917903Y995584D02*
X-918100Y995383D01*
G01X-918231Y995718D02*
X-918363Y995584D01*
G01X-920462Y995517D02*
X-920594Y995383D01*
G01X-920462Y995785D02*
X-920594Y995651D01*
G01X-923021Y995852D02*
X-923153Y995718D01*
G01X-924990Y995651D02*
X-925056Y995584D01*
G01X-924990Y995919D02*
X-925187Y995718D01*
G01X-926040Y995651D02*
X-926171Y995517D01*
G01X-926040Y995919D02*
X-926171Y995785D01*
G01X-921512Y994378D02*
X-921775Y994043D01*
G01X-916853Y994311D02*
X-917050Y994177D01*
G01X-911867Y993976D02*
X-911998Y993909D01*
G01X-916722Y994043D02*
X-916985Y993909D01*
G01X-913048Y995919D02*
X-913179Y995852D01*
G01X-917772Y995651D02*
X-917903Y995584D01*
G01X-922890Y995919D02*
X-923021Y995852D01*
G01X-924859Y995718D02*
X-924990Y995651D01*
G01X-915279D02*
X-915475Y995517D01*
G01X-915279Y995919D02*
X-915475Y995785D01*
G01X-918035Y995852D02*
X-918231Y995718D01*
G01X-921775Y994043D02*
X-921972Y993909D01*
G01X-921906Y994378D02*
X-922103Y994244D01*
G01X-920265Y995651D02*
X-920462Y995517D01*
G01X-920265Y995919D02*
X-920462Y995785D01*
G01X-922890Y995584D02*
X-923087Y995450D01*
G01X-917838Y995919D02*
X-918035Y995852D01*
G01X-924793Y995986D02*
X-924990Y995919D01*
G01X-925843Y995718D02*
X-926040Y995651D01*
G01X-925843Y995986D02*
X-926040Y995919D01*
G01X-873349Y1004552D02*
G03X-873546Y1004355I0J-197D01*
G01X-872759D02*
G03X-872956Y1004552I-197J0D01*
G01X-875318D02*
G03X-875515Y1004355I0J-197D01*
G01X-874727D02*
G03X-874924Y1004552I-197J0D01*
G01X-877286D02*
G03X-877483Y1004355I0J-197D01*
G01X-876696D02*
G03X-876893Y1004552I-197J0D01*
G01X-879255D02*
G03X-879452Y1004355I0J-197D01*
G01X-878664D02*
G03X-878861Y1004552I-197J0D01*
G01X-881223D02*
G03X-881420Y1004355I0J-197D01*
G01X-880633D02*
G03X-880830Y1004552I-197J0D01*
G01X-883192D02*
G03X-883389Y1004355I0J-197D01*
G01X-882601D02*
G03X-882798Y1004552I-197J0D01*
G01X-885160D02*
G03X-885357Y1004355I0J-197D01*
G01X-884570D02*
G03X-884767Y1004552I-197J0D01*
G01X-887129D02*
G03X-887326Y1004355I0J-197D01*
G01X-886538D02*
G03X-886735Y1004552I-197J0D01*
G01X-889098D02*
G03X-889294Y1004355I0J-196D01*
G01X-888507D02*
G03X-888704Y1004552I-197J0D01*
G01X-891066D02*
G03X-891263Y1004355I0J-197D01*
G01X-890475D02*
G03X-890672Y1004552I-197J0D01*
G01X-893035D02*
G03X-893231Y1004355I0J-196D01*
G01X-892444D02*
G03X-892641Y1004552I-197J0D01*
G01X-895003D02*
G03X-895200Y1004355I0J-197D01*
G01X-894412D02*
G03X-894609Y1004552I-197J0D01*
G01X-896972D02*
G03X-897168Y1004355I0J-196D01*
G01X-896381D02*
G03X-896578Y1004552I-197J0D01*
G01X-898940D02*
G03X-899137Y1004355I0J-197D01*
G01X-898349D02*
G03X-898546Y1004552I-197J0D01*
G01X-900909D02*
G03X-901105Y1004355I0J-196D01*
G01X-900318D02*
G03X-900515Y1004552I-197J0D01*
G01X-902877D02*
G03X-903074Y1004355I0J-197D01*
G01X-902286D02*
G03X-902483Y1004552I-197J0D01*
G01X-904846D02*
G03X-905042Y1004355I0J-196D01*
G01X-904255D02*
G03X-904452Y1004552I-197J0D01*
G01X-906814D02*
G03X-907011Y1004355I0J-197D01*
G01X-906223D02*
G03X-906420Y1004552I-197J0D01*
G01X-908783D02*
G03X-908979Y1004355I0J-196D01*
G01X-908192D02*
G03X-908389Y1004552I-197J0D01*
G01X-910751D02*
G03X-910948Y1004355I0J-197D01*
G01X-910160D02*
G03X-910357Y1004552I-197J0D01*
G01X-912720D02*
G03X-912916Y1004355I0J-196D01*
G01X-912129D02*
G03X-912326Y1004552I-197J0D01*
G01X-914098Y1004355D02*
G03X-914294Y1004552I-197J0D01*
G01X-909491Y997267D02*
G03X-910279Y998054I-787J0D01*
G01X-914688Y1004552D02*
G03X-914885Y1004355I0J-197D01*
G01X-916657Y1004552D02*
G03X-916853Y1004355I0J-196D01*
G01X-916066D02*
G03X-916263Y1004552I-197J0D01*
G01X-918625D02*
G03X-918822Y1004355I0J-197D01*
G01X-918035D02*
G03X-918231Y1004552I-197J0D01*
G01X-920594D02*
G03X-920790Y1004355I0J-196D01*
G01X-920003D02*
G03X-920200Y1004552I-197J0D01*
G01X-922562D02*
G03X-922759Y1004355I0J-197D01*
G01X-921972D02*
G03X-922168Y1004552I-197J0D01*
G01X-924531D02*
G03X-924727Y1004355I0J-196D01*
G01X-923940D02*
G03X-924137Y1004552I-197J0D01*
G01X-926499D02*
G03X-926696Y1004355I0J-197D01*
G01X-925909D02*
G03X-926105Y1004552I-197J0D01*
G01X-928468D02*
G03X-928664Y1004355I0J-196D01*
G01X-927877D02*
G03X-928074Y1004552I-197J0D01*
G01X-931814Y1004078D02*
G03X-932601I-394J0D01*
G01X-934373Y1006047D02*
G03X-935160Y1005259I0J-787D01*
G01X-932995Y1006047D02*
G03X-933783Y1005259I0J-788D01*
G01X-932601Y998566D02*
G03X-931814I393J0D01*
G01X-929924Y998054D02*
G03X-930712Y997267I0J-788D01*
G01X-933783Y997385D02*
G03X-932995Y996598I787J0D01*
G01X-928160Y1009293D02*
X-928086Y1009192D01*
G01X-928234D02*
X-928283Y1009242D01*
G01X-928258Y1009368D02*
X-928160Y1009293D01*
G01X-872562Y1007425D02*
Y1001322D01*
G01X-872759Y1004355D02*
Y1002034D01*
G01X-873546Y1004355D02*
Y1002034D01*
G01X-873743Y1001322D02*
Y1007425D01*
G01X-874531Y1001322D02*
Y1007425D01*
G01X-874727Y1004355D02*
Y1002034D01*
G01X-875515Y1004355D02*
Y1002034D01*
G01X-875712Y1007425D02*
Y1001322D01*
G01X-876499D02*
Y1007425D01*
G01X-876696Y1004355D02*
Y1002034D01*
G01X-877483Y1004355D02*
Y1002034D01*
G01X-877680Y1007425D02*
Y1001322D01*
G01X-878468D02*
Y1007425D01*
G01X-878664Y1004355D02*
Y1002034D01*
G01X-879452Y1004355D02*
Y1002034D01*
G01X-879649Y1007425D02*
Y1001322D01*
G01X-880436D02*
Y1007425D01*
G01X-880633Y1004355D02*
Y1002034D01*
G01X-881420Y1004355D02*
Y1002034D01*
G01X-881617Y1007425D02*
Y1001322D01*
G01X-882405Y1007425D02*
Y1001322D01*
G01X-882601Y1004355D02*
Y1002034D01*
G01X-883389Y1004355D02*
Y1002034D01*
G01X-883586Y1001322D02*
Y1007425D01*
G01X-884373Y1001322D02*
Y1007425D01*
G01X-884570Y1004355D02*
Y1002034D01*
G01X-885357Y1004355D02*
Y1002034D01*
G01X-885554Y1007425D02*
Y1001322D01*
G01X-886342D02*
Y1007425D01*
G01X-886538Y1004355D02*
Y1002034D01*
G01X-887326Y1004355D02*
Y1002034D01*
G01X-887523Y1007425D02*
Y1001322D01*
G01X-888310Y1007425D02*
Y1001322D01*
G01X-888507Y1004355D02*
Y1002034D01*
G01X-889294Y1004355D02*
Y1002034D01*
G01X-928086Y1009192D02*
X-928062Y1009117D01*
G01X-928209D02*
X-928234Y1009192D01*
G01X-928283Y1009242D02*
X-928357Y1009267D01*
G01X-889491Y1001322D02*
Y1007425D01*
G01X-890279D02*
Y1001322D01*
G01X-890475Y1004355D02*
Y1002034D01*
G01X-891263Y1004355D02*
Y1002034D01*
G01X-891460Y1001322D02*
Y1007425D01*
G01X-892247D02*
Y1001322D01*
G01X-892444Y1004355D02*
Y1002034D01*
G01X-893231Y1004355D02*
Y1002034D01*
G01X-893428Y1001322D02*
Y1007425D01*
G01X-894216D02*
Y1001322D01*
G01X-894412Y1004355D02*
Y1002034D01*
G01X-895200Y1004355D02*
Y1002034D01*
G01X-895397Y1001322D02*
Y1007425D01*
G01X-896184Y1001322D02*
Y1007425D01*
G01X-896381Y1004355D02*
Y1002034D01*
G01X-897168Y1004355D02*
Y1002034D01*
G01X-897365Y1007425D02*
Y1001322D01*
G01X-898153D02*
Y1007425D01*
G01X-898349Y1004355D02*
Y1002034D01*
G01X-899137Y1004355D02*
Y1002034D01*
G01X-899334Y1007425D02*
Y1001322D01*
G01X-900121D02*
Y1007425D01*
G01X-900318Y1004355D02*
Y1002034D01*
G01X-901105Y1004355D02*
Y1002034D01*
G01X-901302Y1007425D02*
Y1001322D01*
G01X-902090Y1007425D02*
Y1001322D01*
G01X-902286Y1004355D02*
Y1002034D01*
G01X-903074Y1004355D02*
Y1002034D01*
G01X-903271Y1001322D02*
Y1007425D01*
G01X-904058D02*
Y1001322D01*
G01X-904255Y1004355D02*
Y1002034D01*
G01X-905042Y1004355D02*
Y1002034D01*
G01X-905239Y1001322D02*
Y1007425D01*
G01X-906027D02*
Y1001322D01*
G01X-906223Y1004355D02*
Y1002034D01*
G01X-907011Y1004355D02*
Y1002034D01*
G01X-907208Y1001322D02*
Y1007425D01*
G01X-907995Y1001322D02*
Y1007425D01*
G01X-908192Y1004355D02*
Y1002034D01*
G01X-908979Y1004355D02*
Y1002034D01*
G01X-909176Y1007425D02*
Y1001322D01*
G01X-909964D02*
Y1007425D01*
G01X-910160Y1004355D02*
Y1002034D01*
G01X-910948Y1004355D02*
Y1002034D01*
G01X-911145Y1007425D02*
Y1001322D01*
G01X-911932Y1007425D02*
Y1001322D01*
G01X-912129Y1004355D02*
Y1002034D01*
G01X-912916Y1004355D02*
Y1002034D01*
G01X-913113Y1001322D02*
Y1007425D01*
G01X-913901D02*
Y1001322D01*
G01X-914098Y1004355D02*
Y1002034D01*
G01X-914885Y1004355D02*
Y1002034D01*
G01X-915082Y1001322D02*
Y1007425D01*
G01X-915869D02*
Y1001322D01*
G01X-916066Y1004355D02*
Y1002034D01*
G01X-916853Y1004355D02*
Y1002034D01*
G01X-917050Y1001322D02*
Y1007425D01*
G01X-917838Y1001322D02*
Y1007425D01*
G01X-918035Y1004355D02*
Y1002034D01*
G01X-918822Y1004355D02*
Y1002034D01*
G01X-919019Y1007425D02*
Y1001322D01*
G01X-919806D02*
Y1007425D01*
G01X-920003Y1004355D02*
Y1002034D01*
G01X-920790Y1004355D02*
Y1002034D01*
G01X-920987Y1007425D02*
Y1001322D01*
G01X-921775D02*
Y1007425D01*
G01X-921972Y1004355D02*
Y1002034D01*
G01X-922759Y1004355D02*
Y1002034D01*
G01X-922956Y1007425D02*
Y1001322D01*
G01X-923743D02*
Y1007425D01*
G01X-923940Y1004355D02*
Y1002034D01*
G01X-924727Y1004355D02*
Y1002034D01*
G01X-924924Y1007425D02*
Y1001322D01*
G01X-925712Y1007425D02*
Y1001322D01*
G01X-925909Y1004355D02*
Y1002034D01*
G01X-926696Y1004355D02*
Y1002034D01*
G01X-926893Y1001322D02*
Y1007425D01*
G01X-927569Y1009393D02*
Y1008212D01*
G01X-927680Y1007425D02*
Y1001322D01*
G01X-927717Y1008212D02*
Y1009192D01*
G01X-927865Y1009016D02*
Y1009217D01*
G01X-927877Y1004355D02*
Y1002034D01*
G01X-928062Y1009117D02*
Y1009016D01*
G01X-928209Y1009041D02*
Y1009117D01*
G01X-928664Y1004355D02*
Y1002034D01*
G01X-928824Y1009267D02*
Y1008890D01*
G01Y1008740D02*
Y1008212D01*
G01X-928861Y1001322D02*
Y1007425D01*
G01X-928972Y1008212D02*
Y1009393D01*
G01X-928381D02*
X-928258Y1009368D01*
G01X-930397Y1003094D02*
Y1006047D01*
G01X-930830D02*
Y1003094D01*
G01X-931118Y996598D02*
Y1003094D01*
G01X-931420Y1006047D02*
Y996598D01*
G01X-931814Y1004078D02*
Y998566D01*
G01X-932011Y999944D02*
Y1006047D01*
G01X-932601Y998566D02*
Y1004078D01*
G01X-933783Y997385D02*
Y1005259D01*
G01X-934176Y999944D02*
Y1006047D01*
G01X-927717Y1009393D02*
X-927569D01*
G01X-928972D02*
X-928381D01*
G01X-928357Y1009267D02*
X-928824D01*
G01Y1008890D02*
X-928357D01*
G01X-928381Y1008740D02*
X-928824D01*
G01X-927569Y1008212D02*
X-927717D01*
G01X-928824D02*
X-928972D01*
G01X-873743Y1007425D02*
X-872562D01*
G01X-883586D02*
X-882405D01*
G01X-889491D02*
X-888310D01*
G01X-891460D02*
X-890279D01*
G01X-893428D02*
X-892247D01*
G01X-895397D02*
X-894216D01*
G01X-903271D02*
X-902090D01*
G01X-905239D02*
X-904058D01*
G01X-907208D02*
X-906027D01*
G01X-913113D02*
X-911932D01*
G01X-915082D02*
X-913901D01*
G01X-917050D02*
X-915869D01*
G01X-926893D02*
X-925712D01*
G01X-928861D02*
X-927680D01*
G01X-923743D02*
X-924924D01*
G01X-921775D02*
X-922956D01*
G01X-919806D02*
X-920987D01*
G01X-917838D02*
X-919019D01*
G01X-909964D02*
X-911145D01*
G01X-907995D02*
X-909176D01*
G01X-900121D02*
X-901302D01*
G01X-898153D02*
X-899334D01*
G01X-896184D02*
X-897365D01*
G01X-886342D02*
X-887523D01*
G01X-884373D02*
X-885554D01*
G01X-880436D02*
X-881617D01*
G01X-878468D02*
X-879649D01*
G01X-876499D02*
X-877680D01*
G01X-874531D02*
X-875712D01*
G01X-934964Y1006736D02*
X-930239D01*
G01X-934373Y1006047D02*
X-930239D01*
G01X-928074Y1004552D02*
X-928468D01*
G01X-924137D02*
X-924531D01*
G01X-926105D02*
X-926499D01*
G01X-920200D02*
X-920594D01*
G01X-922168D02*
X-922562D01*
G01X-918231D02*
X-918625D01*
G01X-914294D02*
X-914688D01*
G01X-916263D02*
X-916657D01*
G01X-910357D02*
X-910751D01*
G01X-912326D02*
X-912720D01*
G01X-908389D02*
X-908783D01*
G01X-904452D02*
X-904846D01*
G01X-906420D02*
X-906814D01*
G01X-900515D02*
X-900909D01*
G01X-902483D02*
X-902877D01*
G01X-898546D02*
X-898940D01*
G01X-894609D02*
X-895003D01*
G01X-896578D02*
X-896972D01*
G01X-890672D02*
X-891066D01*
G01X-892641D02*
X-893035D01*
G01X-886735D02*
X-887129D01*
G01X-888704D02*
X-889098D01*
G01X-884767D02*
X-885160D01*
G01X-880830D02*
X-881223D01*
G01X-882798D02*
X-883192D01*
G01X-876893D02*
X-877286D01*
G01X-878861D02*
X-879255D01*
G01X-874924D02*
X-875318D01*
G01X-872956D02*
X-873349D01*
G01X-932011Y1003094D02*
X-851696D01*
G01X-927877Y1002583D02*
X-928664D01*
G01X-923940D02*
X-924727D01*
G01X-925909D02*
X-926696D01*
G01X-920003D02*
X-920790D01*
G01X-921972D02*
X-922759D01*
G01X-918035D02*
X-918822D01*
G01X-914098D02*
X-914885D01*
G01X-916066D02*
X-916853D01*
G01X-910160D02*
X-910948D01*
G01X-912129D02*
X-912916D01*
G01X-906223D02*
X-907011D01*
G01X-908192D02*
X-908979D01*
G01X-904255D02*
X-905042D01*
G01X-900318D02*
X-901105D01*
G01X-902286D02*
X-903074D01*
G01X-896381D02*
X-897168D01*
G01X-898349D02*
X-899137D01*
G01X-894412D02*
X-895200D01*
G01X-890475D02*
X-891263D01*
G01X-892444D02*
X-893231D01*
G01X-886538D02*
X-887326D01*
G01X-888507D02*
X-889294D01*
G01X-884570D02*
X-885357D01*
G01X-880633D02*
X-881420D01*
G01X-882601D02*
X-883389D01*
G01X-876696D02*
X-877483D01*
G01X-878664D02*
X-879452D01*
G01X-874727D02*
X-875515D01*
G01X-872759D02*
X-873546D01*
G01Y1002034D02*
X-872759D01*
G01X-875515D02*
X-874727D01*
G01X-877483D02*
X-876696D01*
G01X-879452D02*
X-878664D01*
G01X-881420D02*
X-880633D01*
G01X-883389D02*
X-882601D01*
G01X-885357D02*
X-884570D01*
G01X-887326D02*
X-886538D01*
G01X-889294D02*
X-888507D01*
G01X-891263D02*
X-890475D01*
G01X-893231D02*
X-892444D01*
G01X-895200D02*
X-894412D01*
G01X-897168D02*
X-896381D01*
G01X-899137D02*
X-898349D01*
G01X-901105D02*
X-900318D01*
G01X-903074D02*
X-902286D01*
G01X-905042D02*
X-904255D01*
G01X-907011D02*
X-906223D01*
G01X-908979D02*
X-908192D01*
G01X-910948D02*
X-910160D01*
G01X-912916D02*
X-912129D01*
G01X-914885D02*
X-914098D01*
G01X-916853D02*
X-916066D01*
G01X-918822D02*
X-918035D01*
G01X-920790D02*
X-920003D01*
G01X-922759D02*
X-921972D01*
G01X-924727D02*
X-923940D01*
G01X-926696D02*
X-925909D01*
G01X-928664D02*
X-927877D01*
G01X-875712Y1001322D02*
X-874531D01*
G01X-879649D02*
X-878468D01*
G01X-877680D02*
X-876499D01*
G01X-881617D02*
X-880436D01*
G01X-885554D02*
X-884373D01*
G01X-887523D02*
X-886342D01*
G01X-899334D02*
X-898153D01*
G01X-897365D02*
X-896184D01*
G01X-901302D02*
X-900121D01*
G01X-909176D02*
X-907995D01*
G01X-911145D02*
X-909964D01*
G01X-919019D02*
X-917838D01*
G01X-922956D02*
X-921775D01*
G01X-920987D02*
X-919806D01*
G01X-924924D02*
X-923743D01*
G01X-925712D02*
X-926893D01*
G01X-927680D02*
X-928861D01*
G01X-915869D02*
X-917050D01*
G01X-913901D02*
X-915082D01*
G01X-911932D02*
X-913113D01*
G01X-906027D02*
X-907208D01*
G01X-904058D02*
X-905239D01*
G01X-902090D02*
X-903271D01*
G01X-894216D02*
X-895397D01*
G01X-890279D02*
X-891460D01*
G01X-892247D02*
X-893428D01*
G01X-888310D02*
X-889491D01*
G01X-882405D02*
X-883586D01*
G01X-872562D02*
X-873743D01*
G01X-851696Y1000732D02*
X-932011D01*
G01X-933783Y999944D02*
X-935160D01*
G01X-932011D02*
X-932601D01*
G01X-925318D02*
X-927286D01*
G01X-910279Y998054D02*
X-929924D01*
G01X-928074Y996991D02*
X-928599D01*
G01X-920594D02*
X-920922D01*
G01X-910620D02*
X-910948D01*
G01X-932995Y996598D02*
X-931118D01*
G01X-928062Y1009016D02*
X-928086Y1008941D01*
G01X-928234Y1008966D02*
X-928209Y1009041D01*
G01X-928258Y1008765D02*
X-928381Y1008740D01*
G01X-927717Y1009192D02*
X-927865Y1009016D01*
G01Y1009217D02*
X-927717Y1009393D01*
G01X-928086Y1008941D02*
X-928160Y1008840D01*
G01X-928283Y1008916D02*
X-928234Y1008966D01*
G01X-928160Y1008840D02*
X-928258Y1008765D01*
G01X-928357Y1008890D02*
X-928283Y1008916D01*
G01X-798983Y-714465D02*
Y-733402D01*
G01X-789009Y-442524D02*
G03X-801607I-6299J0D01*
G01Y-448824D02*
G03X-789009I6299J0D01*
G01X-776607Y-445674D02*
G03I-18701J0D01*
G01X-801607Y-442524D02*
Y-448824D01*
G01X-789009Y-324414D02*
G03X-801607I-6299J0D01*
G01Y-330713D02*
G03X-789009I6299J0D01*
G01X-776607Y-327564D02*
G03I-18701J0D01*
G01X-801607Y-324414D02*
Y-330713D01*
G01X-793276Y485259D02*
Y477779D01*
G01X-793428Y485259D02*
Y477385D01*
G01X-798349Y485259D02*
Y477779D01*
G01X-798940Y502779D02*
Y477779D01*
G01X-800909Y502779D02*
Y477779D01*
G01X-793428Y485259D02*
X-798349D01*
G01X-780830D02*
X-793428D01*
G01X-773349Y477779D02*
X-800909D01*
G01X-780830Y477385D02*
X-793428D01*
G01X-787129Y560180D02*
G03X-799727I-6299J0D01*
G01Y553881D02*
G03X-787129I6299J0D01*
G01X-769808Y557031D02*
G03X-817053I-23623J0D01*
G01X-769806D02*
G03X-817050I-23622J0D01*
G01X-774328Y552921D02*
G03I-20877J0D01*
G01X-798778Y504855D02*
X-798955Y504719D01*
G01X-798999Y504990D02*
X-798910Y505081D01*
G01X-792989Y523447D02*
X-793481Y522945D01*
G01X-793108Y505488D02*
X-793374Y505171D01*
G01Y505533D02*
X-793108Y505850D01*
G01X-798645Y505036D02*
X-798778Y504855D01*
G01X-793481Y522945D02*
X-793809Y522275D01*
G01X-799132Y504945D02*
X-798999Y504990D01*
G01X-798600Y505171D02*
X-798645Y505036D01*
G01X-798910Y505081D02*
X-798866Y505216D01*
G01X-793809Y522275D02*
X-793973Y521772D01*
G01D02*
X-794137Y520934D01*
G01X-793153Y521772D02*
X-793317Y520767D01*
G01D02*
Y519594D01*
G01X-793374Y505171D02*
Y505533D01*
G01X-794137Y520934D02*
Y519427D01*
G01X-795449Y519594D02*
Y518924D01*
G01Y521604D02*
Y520934D01*
G01X-795751Y498763D02*
Y496795D01*
G01X-795854Y505850D02*
Y503724D01*
G01X-796120Y504040D02*
Y505850D01*
G01X-796145Y498763D02*
Y502779D01*
G01Y498763D02*
Y496795D01*
G01X-797360Y505578D02*
Y503724D01*
G01X-797626D02*
Y505850D01*
G01X-797980D02*
Y503724D01*
G01X-798074Y518924D02*
Y519594D01*
G01Y520934D02*
Y521604D01*
G01X-798113Y498763D02*
Y502779D01*
G01Y498763D02*
Y496795D01*
G01X-798246Y503724D02*
Y505850D01*
G01X-798507Y498763D02*
Y496795D01*
G01X-798600Y505352D02*
Y505171D01*
G01X-798866Y505216D02*
Y505352D01*
G01X-799386Y524117D02*
Y516243D01*
G01X-799727Y560180D02*
Y553881D01*
G01X-799973Y505624D02*
Y504945D01*
G01Y504674D02*
Y503724D01*
G01X-800239D02*
Y505850D01*
G01X-800370Y520934D02*
Y524117D01*
G01Y516243D02*
Y519929D01*
G01X-804964D02*
Y516243D01*
G01Y524117D02*
Y520934D01*
G01X-805948Y516243D02*
Y524117D01*
G01X-817050Y513724D02*
Y557031D01*
G01X-793317Y519594D02*
X-793153Y518589D01*
G01X-794137Y519427D02*
X-793973Y518589D01*
G01D02*
X-793809Y518086D01*
G01X-798645Y505488D02*
X-798600Y505352D01*
G01X-798866D02*
X-798910Y505488D01*
G01X-793809Y518086D02*
X-793481Y517416D01*
G01X-796253Y503724D02*
X-797360Y505578D01*
G01X-797227Y505850D02*
X-796120Y504040D01*
G01X-798778Y505669D02*
X-798645Y505488D01*
G01X-793481Y517416D02*
X-792989Y516914D01*
G01X-798910Y505488D02*
X-798999Y505578D01*
G01X-798955Y505804D02*
X-798778Y505669D01*
G01X-798999Y505578D02*
X-799132Y505624D01*
G01X-799176Y505850D02*
X-798955Y505804D01*
G01X-800370Y524117D02*
X-799386D01*
G01X-805948D02*
X-804964D01*
G01X-798074Y521604D02*
X-795449D01*
G01X-804964Y520934D02*
X-800370D01*
G01X-795449D02*
X-798074D01*
G01X-800370Y519929D02*
X-804964D01*
G01X-798074Y519594D02*
X-795449D01*
G01Y518924D02*
X-798074D01*
G01X-804964Y516243D02*
X-805948D01*
G01X-799386D02*
X-800370D01*
G01X-769806Y513724D02*
X-817050D01*
G01X-797626Y505850D02*
X-797227D01*
G01X-796120D02*
X-795854D01*
G01X-798246D02*
X-797980D01*
G01X-800239D02*
X-799176D01*
G01X-799132Y505624D02*
X-799973D01*
G01Y504945D02*
X-799132D01*
G01X-799176Y504674D02*
X-799973D01*
G01X-797980Y503724D02*
X-798246D01*
G01X-799973D02*
X-800239D01*
G01X-797360D02*
X-797626D01*
G01X-795854D02*
X-796253D01*
G01X-800909Y502779D02*
X-798113D01*
G01X-788113D02*
X-796145D01*
G01X-795751Y498763D02*
X-798507D01*
G01X-795751Y496795D02*
X-798507D01*
G01X-798955Y504719D02*
X-799176Y504674D01*
G01X-794931Y636619D02*
X-794439Y636954D01*
G01X-793947Y636284D02*
X-793454Y636786D01*
G01X-794439Y636954D02*
X-793783Y637959D01*
G01X-793454Y636786D02*
X-793126Y637456D01*
G01X-794767Y635781D02*
X-793947Y636284D01*
G01X-803953Y643488D02*
Y635614D01*
G01X-804937D02*
Y639299D01*
G01X-809531D02*
Y635614D01*
G01X-810515D02*
Y643488D01*
G01X-817050Y631834D02*
Y675141D01*
G01X-798540Y637959D02*
X-798376Y637456D01*
G01D02*
X-798048Y636786D01*
G01X-797720Y637959D02*
X-797063Y636954D01*
G01X-798048Y636786D02*
X-797556Y636284D01*
G01X-797063Y636954D02*
X-796571Y636619D01*
G01X-797556Y636284D02*
X-796735Y635781D01*
G01X-796571Y636619D02*
X-795751Y636451D01*
G01X-796735Y635781D02*
X-795751Y635614D01*
G01X-809531D02*
X-810515D01*
G01X-803953D02*
X-804937D01*
G01X-769806Y631834D02*
X-817050D01*
G01X-795751Y635614D02*
X-794767Y635781D01*
G01X-795751Y636451D02*
X-794931Y636619D01*
G01X-793428Y675928D02*
Y793432D01*
G01X-787129Y678291D02*
G03X-799727I-6299J0D01*
G01Y671991D02*
G03X-787129I6299J0D01*
G01X-769806Y675141D02*
G03X-817050I-23622J0D01*
G01X-764902Y674636D02*
G03I-33881J0D01*
G01X-797556Y642817D02*
X-798048Y642315D01*
G01X-797063Y642147D02*
X-797720Y641142D01*
G01X-798048Y642315D02*
X-798376Y641645D01*
G01D02*
X-798540Y641142D01*
G01D02*
X-798704Y640304D01*
G01X-793783Y637959D02*
X-793618Y638964D01*
G01X-797720Y641142D02*
X-797884Y640137D01*
G01X-796735Y643320D02*
X-797556Y642817D01*
G01X-796571Y642482D02*
X-797063Y642147D01*
G01X-793618Y638964D02*
Y640137D01*
G01X-797884D02*
Y638964D01*
G01X-798704Y640304D02*
Y638797D01*
G01X-799727Y678291D02*
Y671991D01*
G01X-800016Y638964D02*
Y638294D01*
G01Y640975D02*
Y640304D01*
G01X-802641Y638294D02*
Y638964D01*
G01Y640304D02*
Y640975D01*
G01X-804937Y640304D02*
Y643488D01*
G01X-793618Y640137D02*
X-793783Y641142D01*
G01X-797884Y638964D02*
X-797720Y637959D01*
G01X-798704Y638797D02*
X-798540Y637959D01*
G01X-809531Y643488D02*
Y640304D01*
G01X-793126Y641645D02*
X-793454Y642315D01*
G01X-793783Y641142D02*
X-794439Y642147D01*
G01X-793454Y642315D02*
X-793947Y642817D01*
G01X-794439Y642147D02*
X-794931Y642482D01*
G01X-793947Y642817D02*
X-794767Y643320D01*
G01X-794931Y642482D02*
X-795751Y642650D01*
G01X-794767Y643320D02*
X-795751Y643488D01*
G01X-804937D02*
X-803953D01*
G01X-810515D02*
X-809531D01*
G01X-802641Y640975D02*
X-800016D01*
G01X-809531Y640304D02*
X-804937D01*
G01X-800016D02*
X-802641D01*
G01X-804937Y639299D02*
X-809531D01*
G01X-802641Y638964D02*
X-800016D01*
G01Y638294D02*
X-802641D01*
G01X-795751Y643488D02*
X-796735Y643320D01*
G01X-795751Y642650D02*
X-796571Y642482D01*
G01X-806213Y743720D02*
X-806705Y742715D01*
G01X-798832D02*
Y730654D01*
G01X-801293D02*
Y742715D01*
G01X-806705D02*
Y730654D01*
G01X-809166D02*
Y742715D01*
G01X-805721Y744222D02*
X-806213Y743720D01*
G01X-807198Y744725D02*
X-805721Y746233D01*
G01X-813595Y744222D02*
X-814579Y743217D01*
G01Y745228D02*
X-813595Y746233D01*
G01X-827865Y744222D02*
X-828357Y743720D01*
G01X-829341Y744725D02*
X-827865Y746233D01*
G01X-835738Y744222D02*
X-836722Y743217D01*
G01Y745228D02*
X-835738Y746233D01*
G01X-846072Y750253D02*
X-849024Y746735D01*
G01X-828357Y743720D02*
X-828849Y742715D01*
G01X-814579Y743217D02*
Y730654D01*
G01Y746735D02*
Y745228D01*
G01X-817039Y730654D02*
Y746735D01*
G01X-820976Y742715D02*
Y730654D01*
G01X-823436D02*
Y742715D01*
G01X-828849D02*
Y730654D01*
G01X-831309D02*
Y742715D01*
G01X-836722Y743217D02*
Y730654D01*
G01Y746735D02*
Y745228D01*
G01X-839183Y730654D02*
Y746735D01*
G01X-843119Y754273D02*
Y730654D01*
G01X-846072D02*
Y750253D01*
G01X-849024Y746735D02*
Y750756D01*
G01X-799816Y745228D02*
X-798832Y742715D01*
G01X-821960Y745228D02*
X-820976Y742715D01*
G01X-801293D02*
X-801785Y743720D01*
G01X-849024Y750756D02*
X-846072Y754273D01*
G01X-852961Y733166D02*
Y730654D01*
G01X-855421D02*
Y733166D01*
G01X-859358Y754273D02*
Y730654D01*
G01X-862310D02*
Y750253D01*
G01X-809166Y742715D02*
X-809658Y743720D01*
G01X-823436Y742715D02*
X-823928Y743720D01*
G01X-831309Y742715D02*
X-831801Y743720D01*
G01X-805721Y746233D02*
X-804245Y746735D01*
G01X-804737Y744725D02*
X-805721Y744222D01*
G01X-826881Y744725D02*
X-827865Y744222D01*
G01X-812118Y744725D02*
X-813595Y744222D01*
G01Y746233D02*
X-812118Y746735D01*
G01X-827865Y746233D02*
X-826389Y746735D01*
G01X-834262Y744725D02*
X-835738Y744222D01*
G01Y746233D02*
X-834262Y746735D01*
G01X-800801Y746233D02*
X-799816Y745228D01*
G01X-801785Y743720D02*
X-802277Y744222D01*
G01X-808674Y746233D02*
X-807198Y744725D01*
G01X-809658Y743720D02*
X-810150Y744222D01*
G01X-822944Y746233D02*
X-821960Y745228D01*
G01X-823928Y743720D02*
X-824420Y744222D01*
G01X-830817Y746233D02*
X-829341Y744725D01*
G01X-831801Y743720D02*
X-832293Y744222D01*
G01X-802277D02*
X-803261Y744725D01*
G01X-810150Y744222D02*
X-811134Y744725D01*
G01X-824420Y744222D02*
X-825404Y744725D01*
G01X-832293Y744222D02*
X-833278Y744725D01*
G01X-802277Y746735D02*
X-800801Y746233D01*
G01X-810150Y746735D02*
X-808674Y746233D01*
G01X-824420Y746735D02*
X-822944Y746233D01*
G01X-832293Y746735D02*
X-830817Y746233D01*
G01X-846072Y754273D02*
X-843119D01*
G01X-862310D02*
X-859358D01*
G01X-804245Y746735D02*
X-802277D01*
G01X-812118D02*
X-810150D01*
G01X-817039D02*
X-814579D01*
G01X-826389D02*
X-824420D01*
G01X-834262D02*
X-832293D01*
G01X-839183D02*
X-836722D01*
G01X-833278Y744725D02*
X-834262D01*
G01X-825404D02*
X-826881D01*
G01X-811134D02*
X-812118D01*
G01X-803261D02*
X-804737D01*
G01X-855421Y733166D02*
X-852961D01*
G01X-859358Y730654D02*
X-862310D01*
G01X-852961D02*
X-855421D01*
G01X-843119D02*
X-846072D01*
G01X-836722D02*
X-839183D01*
G01X-828849D02*
X-831309D01*
G01X-820976D02*
X-823436D01*
G01X-814579D02*
X-817039D01*
G01X-806705D02*
X-809166D01*
G01X-798832D02*
X-801293D01*
G01X-861975Y986671D02*
X-861972Y986643D01*
G01X-861987Y986697D02*
X-861975Y986671D01*
G01X-862005Y986721D02*
X-861987Y986697D01*
G01X-862029Y986742D02*
X-862005Y986721D01*
G01X-862059Y986760D02*
X-862029Y986742D01*
G01X-862093Y986773D02*
X-862059Y986760D01*
G01X-862130Y986781D02*
X-862093Y986773D01*
G01X-862168Y986783D02*
X-862130Y986781D01*
G01X-860007Y986671D02*
X-860003Y986643D01*
G01X-860018Y986697D02*
X-860007Y986671D01*
G01X-860036Y986721D02*
X-860018Y986697D01*
G01X-860061Y986742D02*
X-860036Y986721D01*
G01X-860091Y986760D02*
X-860061Y986742D01*
G01X-860125Y986773D02*
X-860091Y986760D01*
G01X-860162Y986781D02*
X-860125Y986773D01*
G01X-860200Y986783D02*
X-860162Y986781D01*
G01X-858038Y986671D02*
X-858035Y986643D01*
G01X-858050Y986697D02*
X-858038Y986671D01*
G01X-858068Y986721D02*
X-858050Y986697D01*
G01X-858092Y986742D02*
X-858068Y986721D01*
G01X-858122Y986760D02*
X-858092Y986742D01*
G01X-858156Y986773D02*
X-858122Y986760D01*
G01X-858193Y986781D02*
X-858156Y986773D01*
G01X-858231Y986783D02*
X-858193Y986781D01*
G01X-856070Y986671D02*
X-856066Y986643D01*
G01X-856081Y986697D02*
X-856070Y986671D01*
G01X-856099Y986721D02*
X-856081Y986697D01*
G01X-856124Y986742D02*
X-856099Y986721D01*
G01X-856154Y986760D02*
X-856124Y986742D01*
G01X-856188Y986773D02*
X-856154Y986760D01*
G01X-856225Y986781D02*
X-856188Y986773D01*
G01X-856263Y986783D02*
X-856225Y986781D01*
G01X-828511Y986671D02*
X-828507Y986643D01*
G01X-828522Y986697D02*
X-828511Y986671D01*
G01X-828540Y986721D02*
X-828522Y986697D01*
G01X-828565Y986742D02*
X-828540Y986721D01*
G01X-828595Y986760D02*
X-828565Y986742D01*
G01X-828629Y986773D02*
X-828595Y986760D01*
G01X-828666Y986781D02*
X-828629Y986773D01*
G01X-828704Y986783D02*
X-828666Y986781D01*
G01X-826542Y986671D02*
X-826538Y986643D01*
G01X-826554Y986697D02*
X-826542Y986671D01*
G01X-826572Y986721D02*
X-826554Y986697D01*
G01X-826596Y986742D02*
X-826572Y986721D01*
G01X-826626Y986760D02*
X-826596Y986742D01*
G01X-826660Y986773D02*
X-826626Y986760D01*
G01X-826697Y986781D02*
X-826660Y986773D01*
G01X-826735Y986783D02*
X-826697Y986781D01*
G01X-824574Y986671D02*
X-824570Y986643D01*
G01X-824585Y986697D02*
X-824574Y986671D01*
G01X-824603Y986721D02*
X-824585Y986697D01*
G01X-824628Y986742D02*
X-824603Y986721D01*
G01X-824658Y986760D02*
X-824628Y986742D01*
G01X-824692Y986773D02*
X-824658Y986760D01*
G01X-824729Y986781D02*
X-824692Y986773D01*
G01X-824767Y986783D02*
X-824729Y986781D01*
G01X-822605Y986671D02*
X-822601Y986643D01*
G01X-822617Y986697D02*
X-822605Y986671D01*
G01X-822635Y986721D02*
X-822617Y986697D01*
G01X-822659Y986742D02*
X-822635Y986721D01*
G01X-822689Y986760D02*
X-822659Y986742D01*
G01X-822723Y986773D02*
X-822689Y986760D01*
G01X-822760Y986781D02*
X-822723Y986773D01*
G01X-822798Y986783D02*
X-822760Y986781D01*
G01X-820637Y986671D02*
X-820633Y986643D01*
G01X-820648Y986697D02*
X-820637Y986671D01*
G01X-820666Y986721D02*
X-820648Y986697D01*
G01X-820691Y986742D02*
X-820666Y986721D01*
G01X-820721Y986760D02*
X-820691Y986742D01*
G01X-820755Y986773D02*
X-820721Y986760D01*
G01X-820792Y986781D02*
X-820755Y986773D01*
G01X-820830Y986783D02*
X-820792Y986781D01*
G01X-818668Y986671D02*
X-818664Y986643D01*
G01X-818680Y986697D02*
X-818668Y986671D01*
G01X-818698Y986721D02*
X-818680Y986697D01*
G01X-818722Y986742D02*
X-818698Y986721D01*
G01X-818752Y986760D02*
X-818722Y986742D01*
G01X-818786Y986773D02*
X-818752Y986760D01*
G01X-818823Y986781D02*
X-818786Y986773D01*
G01X-818861Y986783D02*
X-818823Y986781D01*
G01X-816700Y986671D02*
X-816696Y986643D01*
G01X-816711Y986697D02*
X-816700Y986671D01*
G01X-816729Y986721D02*
X-816711Y986697D01*
G01X-816754Y986742D02*
X-816729Y986721D01*
G01X-816784Y986760D02*
X-816754Y986742D01*
G01X-816818Y986773D02*
X-816784Y986760D01*
G01X-816855Y986781D02*
X-816818Y986773D01*
G01X-816893Y986783D02*
X-816855Y986781D01*
G01X-814731Y986671D02*
X-814727Y986643D01*
G01X-814743Y986697D02*
X-814731Y986671D01*
G01X-814761Y986721D02*
X-814743Y986697D01*
G01X-814785Y986742D02*
X-814761Y986721D01*
G01X-814815Y986760D02*
X-814785Y986742D01*
G01X-814849Y986773D02*
X-814815Y986760D01*
G01X-814886Y986781D02*
X-814849Y986773D01*
G01X-814924Y986783D02*
X-814886Y986781D01*
G01X-812763Y986671D02*
X-812759Y986643D01*
G01X-812774Y986697D02*
X-812763Y986671D01*
G01X-812792Y986721D02*
X-812774Y986697D01*
G01X-812817Y986742D02*
X-812792Y986721D01*
G01X-812847Y986760D02*
X-812817Y986742D01*
G01X-812881Y986773D02*
X-812847Y986760D01*
G01X-812918Y986781D02*
X-812881Y986773D01*
G01X-812956Y986783D02*
X-812918Y986781D01*
G01X-810794Y986671D02*
X-810790Y986643D01*
G01X-810806Y986697D02*
X-810794Y986671D01*
G01X-810824Y986721D02*
X-810806Y986697D01*
G01X-810848Y986742D02*
X-810824Y986721D01*
G01X-810878Y986760D02*
X-810848Y986742D01*
G01X-810912Y986773D02*
X-810878Y986760D01*
G01X-810949Y986781D02*
X-810912Y986773D01*
G01X-810987Y986783D02*
X-810949Y986781D01*
G01X-808826Y986671D02*
X-808822Y986643D01*
G01X-808837Y986697D02*
X-808826Y986671D01*
G01X-808855Y986721D02*
X-808837Y986697D01*
G01X-808880Y986742D02*
X-808855Y986721D01*
G01X-808910Y986760D02*
X-808880Y986742D01*
G01X-808944Y986773D02*
X-808910Y986760D01*
G01X-808981Y986781D02*
X-808944Y986773D01*
G01X-809019Y986783D02*
X-808981Y986781D01*
G01X-806857Y986671D02*
X-806853Y986643D01*
G01X-806869Y986697D02*
X-806857Y986671D01*
G01X-806887Y986721D02*
X-806869Y986697D01*
G01X-806911Y986742D02*
X-806887Y986721D01*
G01X-806941Y986760D02*
X-806911Y986742D01*
G01X-806975Y986773D02*
X-806941Y986760D01*
G01X-807012Y986781D02*
X-806975Y986773D01*
G01X-807050Y986783D02*
X-807012Y986781D01*
G01X-804889Y986671D02*
X-804885Y986643D01*
G01X-804900Y986697D02*
X-804889Y986671D01*
G01X-804918Y986721D02*
X-804900Y986697D01*
G01X-804943Y986742D02*
X-804918Y986721D01*
G01X-804973Y986760D02*
X-804943Y986742D01*
G01X-805007Y986773D02*
X-804973Y986760D01*
G01X-805044Y986781D02*
X-805007Y986773D01*
G01X-805082Y986783D02*
X-805044Y986781D01*
G01X-802920Y986671D02*
X-802916Y986643D01*
G01X-802932Y986697D02*
X-802920Y986671D01*
G01X-802950Y986721D02*
X-802932Y986697D01*
G01X-802974Y986742D02*
X-802950Y986721D01*
G01X-803004Y986760D02*
X-802974Y986742D01*
G01X-803038Y986773D02*
X-803004Y986760D01*
G01X-803075Y986781D02*
X-803038Y986773D01*
G01X-803113Y986783D02*
X-803075Y986781D01*
G01X-800952Y986671D02*
X-800948Y986643D01*
G01X-800963Y986697D02*
X-800952Y986671D01*
G01X-800981Y986721D02*
X-800963Y986697D01*
G01X-801006Y986742D02*
X-800981Y986721D01*
G01X-801036Y986760D02*
X-801006Y986742D01*
G01X-801070Y986773D02*
X-801036Y986760D01*
G01X-801107Y986781D02*
X-801070Y986773D01*
G01X-801145Y986783D02*
X-801107Y986781D01*
G01X-798983Y986671D02*
X-798979Y986643D01*
G01X-798995Y986697D02*
X-798983Y986671D01*
G01X-799013Y986721D02*
X-798995Y986697D01*
G01X-799037Y986742D02*
X-799013Y986721D01*
G01X-799067Y986760D02*
X-799037Y986742D01*
G01X-799101Y986773D02*
X-799067Y986760D01*
G01X-799138Y986781D02*
X-799101Y986773D01*
G01X-799176Y986783D02*
X-799138Y986781D01*
G01X-797015Y986671D02*
X-797011Y986643D01*
G01X-797026Y986697D02*
X-797015Y986671D01*
G01X-797044Y986721D02*
X-797026Y986697D01*
G01X-797069Y986742D02*
X-797044Y986721D01*
G01X-797099Y986760D02*
X-797069Y986742D01*
G01X-797133Y986773D02*
X-797099Y986760D01*
G01X-797170Y986781D02*
X-797133Y986773D01*
G01X-797208Y986783D02*
X-797170Y986781D01*
G01X-795046Y986671D02*
X-795042Y986643D01*
G01X-795057Y986697D02*
X-795046Y986671D01*
G01X-795076Y986721D02*
X-795057Y986697D01*
G01X-795100Y986742D02*
X-795076Y986721D01*
G01X-795130Y986760D02*
X-795100Y986742D01*
G01X-795164Y986773D02*
X-795130Y986760D01*
G01X-795201Y986781D02*
X-795164Y986773D01*
G01X-795239Y986783D02*
X-795201Y986781D01*
G01X-793162Y986760D02*
X-793132Y986742D01*
G01X-793196Y986773D02*
X-793162Y986760D01*
G01X-793232Y986781D02*
X-793196Y986773D01*
G01X-793271Y986783D02*
X-793232Y986781D01*
G01X-861979Y986438D02*
X-861972Y986362D01*
G01X-861998Y986501D02*
X-861979Y986438D01*
G01X-862025Y986552D02*
X-861998Y986501D01*
G01X-862058Y986591D02*
X-862025Y986552D01*
G01X-862093Y986618D02*
X-862058Y986591D01*
G01X-862130Y986634D02*
X-862093Y986618D01*
G01X-862168Y986639D02*
X-862130Y986634D01*
G01X-860010Y986438D02*
X-860003Y986362D01*
G01X-860030Y986501D02*
X-860010Y986438D01*
G01X-860057Y986552D02*
X-860030Y986501D01*
G01X-860089Y986591D02*
X-860057Y986552D01*
G01X-860125Y986618D02*
X-860089Y986591D01*
G01X-860162Y986634D02*
X-860125Y986618D01*
G01X-860200Y986639D02*
X-860162Y986634D01*
G01X-858042Y986438D02*
X-858035Y986362D01*
G01X-858061Y986501D02*
X-858042Y986438D01*
G01X-858088Y986552D02*
X-858061Y986501D01*
G01X-858121Y986591D02*
X-858088Y986552D01*
G01X-858156Y986618D02*
X-858121Y986591D01*
G01X-858193Y986634D02*
X-858156Y986618D01*
G01X-858231Y986639D02*
X-858193Y986634D01*
G01X-856073Y986438D02*
X-856066Y986362D01*
G01X-856093Y986501D02*
X-856073Y986438D01*
G01X-856120Y986552D02*
X-856093Y986501D01*
G01X-856152Y986591D02*
X-856120Y986552D01*
G01X-856188Y986618D02*
X-856152Y986591D01*
G01X-856224Y986634D02*
X-856188Y986618D01*
G01X-856263Y986639D02*
X-856224Y986634D01*
G01X-828514Y986438D02*
X-828507Y986362D01*
G01X-828533Y986501D02*
X-828514Y986438D01*
G01X-828561Y986552D02*
X-828533Y986501D01*
G01X-828593Y986591D02*
X-828561Y986552D01*
G01X-828629Y986618D02*
X-828593Y986591D01*
G01X-828665Y986634D02*
X-828629Y986618D01*
G01X-828704Y986639D02*
X-828665Y986634D01*
G01X-826546Y986438D02*
X-826538Y986362D01*
G01X-826565Y986501D02*
X-826546Y986438D01*
G01X-826592Y986552D02*
X-826565Y986501D01*
G01X-826625Y986591D02*
X-826592Y986552D01*
G01X-826660Y986618D02*
X-826625Y986591D01*
G01X-826697Y986634D02*
X-826660Y986618D01*
G01X-826735Y986639D02*
X-826697Y986634D01*
G01X-824577Y986438D02*
X-824570Y986362D01*
G01X-824596Y986501D02*
X-824577Y986438D01*
G01X-824624Y986552D02*
X-824596Y986501D01*
G01X-824656Y986591D02*
X-824624Y986552D01*
G01X-824692Y986618D02*
X-824656Y986591D01*
G01X-824728Y986634D02*
X-824692Y986618D01*
G01X-824767Y986639D02*
X-824728Y986634D01*
G01X-822609Y986438D02*
X-822601Y986362D01*
G01X-822628Y986501D02*
X-822609Y986438D01*
G01X-822655Y986552D02*
X-822628Y986501D01*
G01X-822688Y986591D02*
X-822655Y986552D01*
G01X-822723Y986618D02*
X-822688Y986591D01*
G01X-822760Y986634D02*
X-822723Y986618D01*
G01X-822798Y986639D02*
X-822760Y986634D01*
G01X-820640Y986438D02*
X-820633Y986362D01*
G01X-820659Y986501D02*
X-820640Y986438D01*
G01X-820687Y986552D02*
X-820659Y986501D01*
G01X-820719Y986591D02*
X-820687Y986552D01*
G01X-820755Y986618D02*
X-820719Y986591D01*
G01X-820791Y986634D02*
X-820755Y986618D01*
G01X-820830Y986639D02*
X-820791Y986634D01*
G01X-818672Y986438D02*
X-818664Y986362D01*
G01X-818691Y986501D02*
X-818672Y986438D01*
G01X-818718Y986552D02*
X-818691Y986501D01*
G01X-818751Y986591D02*
X-818718Y986552D01*
G01X-818786Y986618D02*
X-818751Y986591D01*
G01X-818823Y986634D02*
X-818786Y986618D01*
G01X-818861Y986639D02*
X-818823Y986634D01*
G01X-816703Y986438D02*
X-816696Y986362D01*
G01X-816722Y986501D02*
X-816703Y986438D01*
G01X-816750Y986552D02*
X-816722Y986501D01*
G01X-816782Y986591D02*
X-816750Y986552D01*
G01X-816818Y986618D02*
X-816782Y986591D01*
G01X-816854Y986634D02*
X-816818Y986618D01*
G01X-816893Y986639D02*
X-816854Y986634D01*
G01X-814735Y986438D02*
X-814727Y986362D01*
G01X-814754Y986501D02*
X-814735Y986438D01*
G01X-814781Y986552D02*
X-814754Y986501D01*
G01X-814814Y986591D02*
X-814781Y986552D01*
G01X-814849Y986618D02*
X-814814Y986591D01*
G01X-814886Y986634D02*
X-814849Y986618D01*
G01X-814924Y986639D02*
X-814886Y986634D01*
G01X-812766Y986438D02*
X-812759Y986362D01*
G01X-812785Y986501D02*
X-812766Y986438D01*
G01X-812813Y986552D02*
X-812785Y986501D01*
G01X-812845Y986591D02*
X-812813Y986552D01*
G01X-812881Y986618D02*
X-812845Y986591D01*
G01X-812917Y986634D02*
X-812881Y986618D01*
G01X-812956Y986639D02*
X-812917Y986634D01*
G01X-810798Y986438D02*
X-810790Y986362D01*
G01X-810817Y986501D02*
X-810798Y986438D01*
G01X-810844Y986552D02*
X-810817Y986501D01*
G01X-810877Y986591D02*
X-810844Y986552D01*
G01X-810912Y986618D02*
X-810877Y986591D01*
G01X-810949Y986634D02*
X-810912Y986618D01*
G01X-810987Y986639D02*
X-810949Y986634D01*
G01X-808829Y986438D02*
X-808822Y986362D01*
G01X-808848Y986501D02*
X-808829Y986438D01*
G01X-808876Y986552D02*
X-808848Y986501D01*
G01X-808908Y986591D02*
X-808876Y986552D01*
G01X-808944Y986618D02*
X-808908Y986591D01*
G01X-808980Y986634D02*
X-808944Y986618D01*
G01X-809019Y986639D02*
X-808980Y986634D01*
G01X-806861Y986438D02*
X-806853Y986362D01*
G01X-806880Y986501D02*
X-806861Y986438D01*
G01X-806907Y986552D02*
X-806880Y986501D01*
G01X-806940Y986591D02*
X-806907Y986552D01*
G01X-806975Y986618D02*
X-806940Y986591D01*
G01X-807012Y986634D02*
X-806975Y986618D01*
G01X-807050Y986639D02*
X-807012Y986634D01*
G01X-804892Y986438D02*
X-804885Y986362D01*
G01X-804911Y986501D02*
X-804892Y986438D01*
G01X-804939Y986552D02*
X-804911Y986501D01*
G01X-804971Y986591D02*
X-804939Y986552D01*
G01X-805007Y986618D02*
X-804971Y986591D01*
G01X-805043Y986634D02*
X-805007Y986618D01*
G01X-805082Y986639D02*
X-805043Y986634D01*
G01X-802924Y986438D02*
X-802916Y986362D01*
G01X-802943Y986501D02*
X-802924Y986438D01*
G01X-802970Y986552D02*
X-802943Y986501D01*
G01X-803003Y986591D02*
X-802970Y986552D01*
G01X-803038Y986618D02*
X-803003Y986591D01*
G01X-803075Y986634D02*
X-803038Y986618D01*
G01X-803113Y986639D02*
X-803075Y986634D01*
G01X-800955Y986438D02*
X-800948Y986362D01*
G01X-800974Y986501D02*
X-800955Y986438D01*
G01X-801002Y986552D02*
X-800974Y986501D01*
G01X-801034Y986591D02*
X-801002Y986552D01*
G01X-801070Y986618D02*
X-801034Y986591D01*
G01X-801106Y986634D02*
X-801070Y986618D01*
G01X-801145Y986639D02*
X-801106Y986634D01*
G01X-798987Y986438D02*
X-798979Y986362D01*
G01X-799006Y986501D02*
X-798987Y986438D01*
G01X-799033Y986552D02*
X-799006Y986501D01*
G01X-799066Y986591D02*
X-799033Y986552D01*
G01X-799101Y986618D02*
X-799066Y986591D01*
G01X-799138Y986634D02*
X-799101Y986618D01*
G01X-799176Y986639D02*
X-799138Y986634D01*
G01X-797018Y986438D02*
X-797011Y986362D01*
G01X-797037Y986501D02*
X-797018Y986438D01*
G01X-797065Y986552D02*
X-797037Y986501D01*
G01X-797097Y986591D02*
X-797065Y986552D01*
G01X-797133Y986618D02*
X-797097Y986591D01*
G01X-797169Y986634D02*
X-797133Y986618D01*
G01X-797208Y986639D02*
X-797169Y986634D01*
G01X-795050Y986438D02*
X-795042Y986362D01*
G01X-795069Y986501D02*
X-795050Y986438D01*
G01X-795096Y986552D02*
X-795069Y986501D01*
G01X-795129Y986591D02*
X-795096Y986552D01*
G01X-795164Y986618D02*
X-795129Y986591D01*
G01X-795201Y986634D02*
X-795164Y986618D01*
G01X-795239Y986639D02*
X-795201Y986634D01*
G01X-793160Y986591D02*
X-793128Y986552D01*
G01X-793196Y986618D02*
X-793160Y986591D01*
G01X-793232Y986634D02*
X-793196Y986618D01*
G01X-793271Y986639D02*
X-793232Y986634D01*
G01X-862522D02*
X-862483Y986639D01*
G01X-862559Y986618D02*
X-862522Y986634D01*
G01X-862594Y986591D02*
X-862559Y986618D01*
G01X-862626Y986552D02*
X-862594Y986591D01*
G01X-862654Y986501D02*
X-862626Y986552D01*
G01X-862673Y986438D02*
X-862654Y986501D01*
G01X-862680Y986362D02*
X-862673Y986438D01*
G01X-860553Y986634D02*
X-860515Y986639D01*
G01X-860590Y986618D02*
X-860553Y986634D01*
G01X-860625Y986591D02*
X-860590Y986618D01*
G01X-860658Y986552D02*
X-860625Y986591D01*
G01X-860685Y986501D02*
X-860658Y986552D01*
G01X-860704Y986438D02*
X-860685Y986501D01*
G01X-860712Y986362D02*
X-860704Y986438D01*
G01X-858585Y986634D02*
X-858546Y986639D01*
G01X-858622Y986618D02*
X-858585Y986634D01*
G01X-858657Y986591D02*
X-858622Y986618D01*
G01X-858689Y986552D02*
X-858657Y986591D01*
G01X-858717Y986501D02*
X-858689Y986552D01*
G01X-858736Y986438D02*
X-858717Y986501D01*
G01X-858743Y986362D02*
X-858736Y986438D01*
G01X-856616Y986634D02*
X-856578Y986639D01*
G01X-856653Y986618D02*
X-856616Y986634D01*
G01X-856688Y986591D02*
X-856653Y986618D01*
G01X-856721Y986552D02*
X-856688Y986591D01*
G01X-856748Y986501D02*
X-856721Y986552D01*
G01X-856767Y986438D02*
X-856748Y986501D01*
G01X-856775Y986362D02*
X-856767Y986438D01*
G01X-862522Y986781D02*
X-862483Y986783D01*
G01X-862559Y986773D02*
X-862522Y986781D01*
G01X-862593Y986760D02*
X-862559Y986773D01*
G01X-862623Y986742D02*
X-862593Y986760D01*
G01X-862647Y986721D02*
X-862623Y986742D01*
G01X-862665Y986697D02*
X-862647Y986721D01*
G01X-862676Y986671D02*
X-862665Y986697D01*
G01X-862680Y986643D02*
X-862676Y986671D01*
G01X-860554Y986781D02*
X-860515Y986783D01*
G01X-860590Y986773D02*
X-860554Y986781D01*
G01X-860624Y986760D02*
X-860590Y986773D01*
G01X-860654Y986742D02*
X-860624Y986760D01*
G01X-860679Y986721D02*
X-860654Y986742D01*
G01X-860697Y986697D02*
X-860679Y986721D01*
G01X-860708Y986671D02*
X-860697Y986697D01*
G01X-860712Y986643D02*
X-860708Y986671D01*
G01X-858585Y986781D02*
X-858546Y986783D01*
G01X-858622Y986773D02*
X-858585Y986781D01*
G01X-858656Y986760D02*
X-858622Y986773D01*
G01X-858686Y986742D02*
X-858656Y986760D01*
G01X-858710Y986721D02*
X-858686Y986742D01*
G01X-858728Y986697D02*
X-858710Y986721D01*
G01X-858739Y986671D02*
X-858728Y986697D01*
G01X-858743Y986643D02*
X-858739Y986671D01*
G01X-856617Y986781D02*
X-856578Y986783D01*
G01X-856653Y986773D02*
X-856617Y986781D01*
G01X-856687Y986760D02*
X-856653Y986773D01*
G01X-856717Y986742D02*
X-856687Y986760D01*
G01X-856742Y986721D02*
X-856717Y986742D01*
G01X-856760Y986697D02*
X-856742Y986721D01*
G01X-856771Y986671D02*
X-856760Y986697D01*
G01X-856775Y986643D02*
X-856771Y986671D01*
G01X-829058Y986781D02*
X-829019Y986783D01*
G01X-829094Y986773D02*
X-829058Y986781D01*
G01X-829128Y986760D02*
X-829094Y986773D01*
G01X-829158Y986742D02*
X-829128Y986760D01*
G01X-829183Y986721D02*
X-829158Y986742D01*
G01X-829201Y986697D02*
X-829183Y986721D01*
G01X-829212Y986671D02*
X-829201Y986697D01*
G01X-829216Y986643D02*
X-829212Y986671D01*
G01X-829057Y986634D02*
X-829019Y986639D01*
G01X-829094Y986618D02*
X-829057Y986634D01*
G01X-829129Y986591D02*
X-829094Y986618D01*
G01X-829162Y986552D02*
X-829129Y986591D01*
G01X-829189Y986501D02*
X-829162Y986552D01*
G01X-829208Y986438D02*
X-829189Y986501D01*
G01X-829216Y986362D02*
X-829208Y986438D01*
G01X-827089Y986634D02*
X-827050Y986639D01*
G01X-827125Y986618D02*
X-827089Y986634D01*
G01X-827161Y986591D02*
X-827125Y986618D01*
G01X-827193Y986552D02*
X-827161Y986591D01*
G01X-827221Y986501D02*
X-827193Y986552D01*
G01X-827240Y986438D02*
X-827221Y986501D01*
G01X-827247Y986362D02*
X-827240Y986438D01*
G01X-825120Y986634D02*
X-825082Y986639D01*
G01X-825157Y986618D02*
X-825120Y986634D01*
G01X-825192Y986591D02*
X-825157Y986618D01*
G01X-825225Y986552D02*
X-825192Y986591D01*
G01X-825252Y986501D02*
X-825225Y986552D01*
G01X-825271Y986438D02*
X-825252Y986501D01*
G01X-825279Y986362D02*
X-825271Y986438D01*
G01X-823152Y986634D02*
X-823113Y986639D01*
G01X-823188Y986618D02*
X-823152Y986634D01*
G01X-823224Y986591D02*
X-823188Y986618D01*
G01X-823256Y986552D02*
X-823224Y986591D01*
G01X-823284Y986501D02*
X-823256Y986552D01*
G01X-823303Y986438D02*
X-823284Y986501D01*
G01X-823310Y986362D02*
X-823303Y986438D01*
G01X-821183Y986634D02*
X-821145Y986639D01*
G01X-821220Y986618D02*
X-821183Y986634D01*
G01X-821255Y986591D02*
X-821220Y986618D01*
G01X-821288Y986552D02*
X-821255Y986591D01*
G01X-821315Y986501D02*
X-821288Y986552D01*
G01X-821334Y986438D02*
X-821315Y986501D01*
G01X-821342Y986362D02*
X-821334Y986438D01*
G01X-819215Y986634D02*
X-819176Y986639D01*
G01X-819251Y986618D02*
X-819215Y986634D01*
G01X-819287Y986591D02*
X-819251Y986618D01*
G01X-819319Y986552D02*
X-819287Y986591D01*
G01X-819347Y986501D02*
X-819319Y986552D01*
G01X-819366Y986438D02*
X-819347Y986501D01*
G01X-819373Y986362D02*
X-819366Y986438D01*
G01X-817246Y986634D02*
X-817208Y986639D01*
G01X-817283Y986618D02*
X-817246Y986634D01*
G01X-817318Y986591D02*
X-817283Y986618D01*
G01X-817351Y986552D02*
X-817318Y986591D01*
G01X-817378Y986501D02*
X-817351Y986552D01*
G01X-817397Y986438D02*
X-817378Y986501D01*
G01X-817405Y986362D02*
X-817397Y986438D01*
G01X-815278Y986634D02*
X-815239Y986639D01*
G01X-815314Y986618D02*
X-815278Y986634D01*
G01X-815350Y986591D02*
X-815314Y986618D01*
G01X-815382Y986552D02*
X-815350Y986591D01*
G01X-815410Y986501D02*
X-815382Y986552D01*
G01X-815429Y986438D02*
X-815410Y986501D01*
G01X-815436Y986362D02*
X-815429Y986438D01*
G01X-813309Y986634D02*
X-813271Y986639D01*
G01X-813346Y986618D02*
X-813309Y986634D01*
G01X-813381Y986591D02*
X-813346Y986618D01*
G01X-813414Y986552D02*
X-813381Y986591D01*
G01X-813441Y986501D02*
X-813414Y986552D01*
G01X-813460Y986438D02*
X-813441Y986501D01*
G01X-813468Y986362D02*
X-813460Y986438D01*
G01X-811341Y986634D02*
X-811302Y986639D01*
G01X-811377Y986618D02*
X-811341Y986634D01*
G01X-811413Y986591D02*
X-811377Y986618D01*
G01X-811445Y986552D02*
X-811413Y986591D01*
G01X-811473Y986501D02*
X-811445Y986552D01*
G01X-811492Y986438D02*
X-811473Y986501D01*
G01X-811499Y986362D02*
X-811492Y986438D01*
G01X-809372Y986634D02*
X-809334Y986639D01*
G01X-809409Y986618D02*
X-809372Y986634D01*
G01X-809444Y986591D02*
X-809409Y986618D01*
G01X-809477Y986552D02*
X-809444Y986591D01*
G01X-809504Y986501D02*
X-809477Y986552D01*
G01X-809523Y986438D02*
X-809504Y986501D01*
G01X-809531Y986362D02*
X-809523Y986438D01*
G01X-807404Y986634D02*
X-807365Y986639D01*
G01X-807440Y986618D02*
X-807404Y986634D01*
G01X-807476Y986591D02*
X-807440Y986618D01*
G01X-807508Y986552D02*
X-807476Y986591D01*
G01X-807536Y986501D02*
X-807508Y986552D01*
G01X-807555Y986438D02*
X-807536Y986501D01*
G01X-807562Y986362D02*
X-807555Y986438D01*
G01X-805435Y986634D02*
X-805397Y986639D01*
G01X-805472Y986618D02*
X-805435Y986634D01*
G01X-805507Y986591D02*
X-805472Y986618D01*
G01X-805540Y986552D02*
X-805507Y986591D01*
G01X-805567Y986501D02*
X-805540Y986552D01*
G01X-805586Y986438D02*
X-805567Y986501D01*
G01X-805594Y986362D02*
X-805586Y986438D01*
G01X-803467Y986634D02*
X-803428Y986639D01*
G01X-803503Y986618D02*
X-803467Y986634D01*
G01X-803539Y986591D02*
X-803503Y986618D01*
G01X-803571Y986552D02*
X-803539Y986591D01*
G01X-803599Y986501D02*
X-803571Y986552D01*
G01X-803618Y986438D02*
X-803599Y986501D01*
G01X-803625Y986362D02*
X-803618Y986438D01*
G01X-801498Y986634D02*
X-801460Y986639D01*
G01X-801535Y986618D02*
X-801498Y986634D01*
G01X-801570Y986591D02*
X-801535Y986618D01*
G01X-801603Y986552D02*
X-801570Y986591D01*
G01X-801630Y986501D02*
X-801603Y986552D01*
G01X-801649Y986438D02*
X-801630Y986501D01*
G01X-801657Y986362D02*
X-801649Y986438D01*
G01X-799530Y986634D02*
X-799491Y986639D01*
G01X-799566Y986618D02*
X-799530Y986634D01*
G01X-799602Y986591D02*
X-799566Y986618D01*
G01X-799634Y986552D02*
X-799602Y986591D01*
G01X-799662Y986501D02*
X-799634Y986552D01*
G01X-799681Y986438D02*
X-799662Y986501D01*
G01X-799688Y986362D02*
X-799681Y986438D01*
G01X-797561Y986634D02*
X-797523Y986639D01*
G01X-797598Y986618D02*
X-797561Y986634D01*
G01X-797633Y986591D02*
X-797598Y986618D01*
G01X-797666Y986552D02*
X-797633Y986591D01*
G01X-797693Y986501D02*
X-797666Y986552D01*
G01X-797712Y986438D02*
X-797693Y986501D01*
G01X-797720Y986362D02*
X-797712Y986438D01*
G01X-795593Y986634D02*
X-795554Y986639D01*
G01X-795629Y986618D02*
X-795593Y986634D01*
G01X-795665Y986591D02*
X-795629Y986618D01*
G01X-795697Y986552D02*
X-795665Y986591D01*
G01X-795725Y986501D02*
X-795697Y986552D01*
G01X-795744Y986438D02*
X-795725Y986501D01*
G01X-795751Y986362D02*
X-795744Y986438D01*
G01X-827089Y986781D02*
X-827050Y986783D01*
G01X-827126Y986773D02*
X-827089Y986781D01*
G01X-827160Y986760D02*
X-827126Y986773D01*
G01X-827189Y986742D02*
X-827160Y986760D01*
G01X-827214Y986721D02*
X-827189Y986742D01*
G01X-827232Y986697D02*
X-827214Y986721D01*
G01X-827243Y986671D02*
X-827232Y986697D01*
G01X-827247Y986643D02*
X-827243Y986671D01*
G01X-825121Y986781D02*
X-825082Y986783D01*
G01X-825157Y986773D02*
X-825121Y986781D01*
G01X-825191Y986760D02*
X-825157Y986773D01*
G01X-825221Y986742D02*
X-825191Y986760D01*
G01X-825246Y986721D02*
X-825221Y986742D01*
G01X-825264Y986697D02*
X-825246Y986721D01*
G01X-825275Y986671D02*
X-825264Y986697D01*
G01X-825279Y986643D02*
X-825275Y986671D01*
G01X-823152Y986781D02*
X-823113Y986783D01*
G01X-823189Y986773D02*
X-823152Y986781D01*
G01X-823223Y986760D02*
X-823189Y986773D01*
G01X-823252Y986742D02*
X-823223Y986760D01*
G01X-823277Y986721D02*
X-823252Y986742D01*
G01X-823295Y986697D02*
X-823277Y986721D01*
G01X-823306Y986671D02*
X-823295Y986697D01*
G01X-823310Y986643D02*
X-823306Y986671D01*
G01X-821184Y986781D02*
X-821145Y986783D01*
G01X-821220Y986773D02*
X-821184Y986781D01*
G01X-821254Y986760D02*
X-821220Y986773D01*
G01X-821284Y986742D02*
X-821254Y986760D01*
G01X-821309Y986721D02*
X-821284Y986742D01*
G01X-821327Y986697D02*
X-821309Y986721D01*
G01X-821338Y986671D02*
X-821327Y986697D01*
G01X-821342Y986643D02*
X-821338Y986671D01*
G01X-819215Y986781D02*
X-819176Y986783D01*
G01X-819252Y986773D02*
X-819215Y986781D01*
G01X-819286Y986760D02*
X-819252Y986773D01*
G01X-819315Y986742D02*
X-819286Y986760D01*
G01X-819340Y986721D02*
X-819315Y986742D01*
G01X-819358Y986697D02*
X-819340Y986721D01*
G01X-819369Y986671D02*
X-819358Y986697D01*
G01X-819373Y986643D02*
X-819369Y986671D01*
G01X-817247Y986781D02*
X-817208Y986783D01*
G01X-817283Y986773D02*
X-817247Y986781D01*
G01X-817317Y986760D02*
X-817283Y986773D01*
G01X-817347Y986742D02*
X-817317Y986760D01*
G01X-817372Y986721D02*
X-817347Y986742D01*
G01X-817390Y986697D02*
X-817372Y986721D01*
G01X-817401Y986671D02*
X-817390Y986697D01*
G01X-817405Y986643D02*
X-817401Y986671D01*
G01X-815278Y986781D02*
X-815239Y986783D01*
G01X-815315Y986773D02*
X-815278Y986781D01*
G01X-815349Y986760D02*
X-815315Y986773D01*
G01X-815378Y986742D02*
X-815349Y986760D01*
G01X-815403Y986721D02*
X-815378Y986742D01*
G01X-815421Y986697D02*
X-815403Y986721D01*
G01X-815432Y986671D02*
X-815421Y986697D01*
G01X-815436Y986643D02*
X-815432Y986671D01*
G01X-813310Y986781D02*
X-813271Y986783D01*
G01X-813346Y986773D02*
X-813310Y986781D01*
G01X-813380Y986760D02*
X-813346Y986773D01*
G01X-813410Y986742D02*
X-813380Y986760D01*
G01X-813435Y986721D02*
X-813410Y986742D01*
G01X-813453Y986697D02*
X-813435Y986721D01*
G01X-813464Y986671D02*
X-813453Y986697D01*
G01X-813468Y986643D02*
X-813464Y986671D01*
G01X-811341Y986781D02*
X-811302Y986783D01*
G01X-811378Y986773D02*
X-811341Y986781D01*
G01X-811412Y986760D02*
X-811378Y986773D01*
G01X-811441Y986742D02*
X-811412Y986760D01*
G01X-811466Y986721D02*
X-811441Y986742D01*
G01X-811484Y986697D02*
X-811466Y986721D01*
G01X-811495Y986671D02*
X-811484Y986697D01*
G01X-811499Y986643D02*
X-811495Y986671D01*
G01X-809373Y986781D02*
X-809334Y986783D01*
G01X-809409Y986773D02*
X-809373Y986781D01*
G01X-809443Y986760D02*
X-809409Y986773D01*
G01X-809473Y986742D02*
X-809443Y986760D01*
G01X-809498Y986721D02*
X-809473Y986742D01*
G01X-809516Y986697D02*
X-809498Y986721D01*
G01X-809527Y986671D02*
X-809516Y986697D01*
G01X-809531Y986643D02*
X-809527Y986671D01*
G01X-807404Y986781D02*
X-807365Y986783D01*
G01X-807441Y986773D02*
X-807404Y986781D01*
G01X-807475Y986760D02*
X-807441Y986773D01*
G01X-807504Y986742D02*
X-807475Y986760D01*
G01X-807529Y986721D02*
X-807504Y986742D01*
G01X-807547Y986697D02*
X-807529Y986721D01*
G01X-807558Y986671D02*
X-807547Y986697D01*
G01X-807562Y986643D02*
X-807558Y986671D01*
G01X-805436Y986781D02*
X-805397Y986783D01*
G01X-805472Y986773D02*
X-805436Y986781D01*
G01X-805506Y986760D02*
X-805472Y986773D01*
G01X-805536Y986742D02*
X-805506Y986760D01*
G01X-805561Y986721D02*
X-805536Y986742D01*
G01X-805579Y986697D02*
X-805561Y986721D01*
G01X-805590Y986671D02*
X-805579Y986697D01*
G01X-805594Y986643D02*
X-805590Y986671D01*
G01X-803467Y986781D02*
X-803428Y986783D01*
G01X-803504Y986773D02*
X-803467Y986781D01*
G01X-803538Y986760D02*
X-803504Y986773D01*
G01X-803567Y986742D02*
X-803538Y986760D01*
G01X-803592Y986721D02*
X-803567Y986742D01*
G01X-803610Y986697D02*
X-803592Y986721D01*
G01X-803621Y986671D02*
X-803610Y986697D01*
G01X-803625Y986643D02*
X-803621Y986671D01*
G01X-801499Y986781D02*
X-801460Y986783D01*
G01X-801535Y986773D02*
X-801499Y986781D01*
G01X-801569Y986760D02*
X-801535Y986773D01*
G01X-801599Y986742D02*
X-801569Y986760D01*
G01X-801624Y986721D02*
X-801599Y986742D01*
G01X-801642Y986697D02*
X-801624Y986721D01*
G01X-801653Y986671D02*
X-801642Y986697D01*
G01X-801657Y986643D02*
X-801653Y986671D01*
G01X-799530Y986781D02*
X-799491Y986783D01*
G01X-799567Y986773D02*
X-799530Y986781D01*
G01X-799601Y986760D02*
X-799567Y986773D01*
G01X-799630Y986742D02*
X-799601Y986760D01*
G01X-799655Y986721D02*
X-799630Y986742D01*
G01X-799673Y986697D02*
X-799655Y986721D01*
G01X-799684Y986671D02*
X-799673Y986697D01*
G01X-799688Y986643D02*
X-799684Y986671D01*
G01X-797562Y986781D02*
X-797523Y986783D01*
G01X-797598Y986773D02*
X-797562Y986781D01*
G01X-797632Y986760D02*
X-797598Y986773D01*
G01X-797662Y986742D02*
X-797632Y986760D01*
G01X-797687Y986721D02*
X-797662Y986742D01*
G01X-797705Y986697D02*
X-797687Y986721D01*
G01X-797716Y986671D02*
X-797705Y986697D01*
G01X-797720Y986643D02*
X-797716Y986671D01*
G01X-795593Y986781D02*
X-795554Y986783D01*
G01X-795630Y986773D02*
X-795593Y986781D01*
G01X-795664Y986760D02*
X-795630Y986773D01*
G01X-795693Y986742D02*
X-795664Y986760D01*
G01X-795718Y986721D02*
X-795693Y986742D01*
G01X-795736Y986697D02*
X-795718Y986721D01*
G01X-795747Y986671D02*
X-795736Y986697D01*
G01X-795751Y986643D02*
X-795747Y986671D01*
G01X-793625Y986781D02*
X-793586Y986783D01*
G01X-793661Y986773D02*
X-793625Y986781D01*
G01X-793695Y986760D02*
X-793661Y986773D01*
G01X-793725Y986742D02*
X-793695Y986760D01*
G01X-793750Y986721D02*
X-793725Y986742D01*
G01X-793768Y986697D02*
X-793750Y986721D01*
G01X-793779Y986671D02*
X-793768Y986697D01*
G01X-793783Y986643D02*
X-793779Y986671D01*
G01X-793624Y986634D02*
X-793586Y986639D01*
G01X-793661Y986618D02*
X-793624Y986634D01*
G01X-793696Y986591D02*
X-793661Y986618D01*
G01X-793729Y986552D02*
X-793696Y986591D01*
G01X-793756Y986501D02*
X-793729Y986552D01*
G01X-793775Y986438D02*
X-793756Y986501D01*
G01X-793783Y986362D02*
X-793775Y986438D01*
G01X-793822Y972779D02*
G03X-793625Y972582I197J0D01*
G01X-795200D02*
G03X-795003Y972779I0J197D01*
G01X-795790D02*
G03X-795594Y972582I197J0D01*
G01X-797168D02*
G03X-796972Y972779I0J196D01*
G01X-797759D02*
G03X-797562Y972582I197J0D01*
G01X-799137D02*
G03X-798940Y972779I0J197D01*
G01X-799727D02*
G03X-799531Y972582I197J0D01*
G01X-801105D02*
G03X-800909Y972779I0J196D01*
G01X-801696D02*
G03X-801499Y972582I197J0D01*
G01X-803074D02*
G03X-802877Y972779I0J197D01*
G01X-811853Y987621D02*
G03X-811066Y988409I0J787D01*
G01X-803664Y972779D02*
G03X-803468Y972582I197J0D01*
G01X-805042D02*
G03X-804846Y972779I0J196D01*
G01X-805633D02*
G03X-805436Y972582I197J0D01*
G01X-807011D02*
G03X-806814Y972779I0J197D01*
G01X-807601D02*
G03X-807405Y972582I197J0D01*
G01X-808979D02*
G03X-808783Y972779I0J196D01*
G01X-809570D02*
G03X-809373Y972582I197J0D01*
G01X-810948D02*
G03X-810751Y972779I0J197D01*
G01X-811538D02*
G03X-811342Y972582I197J0D01*
G01X-812916D02*
G03X-812720Y972779I0J196D01*
G01X-813507D02*
G03X-813310Y972582I197J0D01*
G01X-814885D02*
G03X-814688Y972779I0J197D01*
G01X-815475D02*
G03X-815279Y972582I197J0D01*
G01X-816853D02*
G03X-816657Y972779I0J196D01*
G01X-817444D02*
G03X-817247Y972582I197J0D01*
G01X-818822D02*
G03X-818625Y972779I0J197D01*
G01X-819412D02*
G03X-819216Y972582I197J0D01*
G01X-832286Y988409D02*
G03X-831499Y987621I788J0D01*
G01X-831814Y983606D02*
G03I-984J0D01*
G01X-834275Y979472D02*
G03X-833094Y980653I0J1181D01*
G01X-831027Y983606D02*
G03I-1771J0D01*
G01X-830633D02*
G03I-2165J0D01*
G01X-820790Y972582D02*
G03X-820594Y972779I0J196D01*
G01X-821381D02*
G03X-821184Y972582I197J0D01*
G01X-822759D02*
G03X-822562Y972779I0J197D01*
G01X-823349D02*
G03X-823153Y972582I197J0D01*
G01X-824727D02*
G03X-824531Y972779I0J196D01*
G01X-825318D02*
G03X-825121Y972582I197J0D01*
G01X-826696D02*
G03X-826499Y972779I0J197D01*
G01X-827286D02*
G03X-827090Y972582I197J0D01*
G01X-828664D02*
G03X-828468Y972779I0J196D01*
G01X-829255D02*
G03X-829058Y972582I197J0D01*
G01X-852188Y980653D02*
G03X-851007Y979472I1181J0D01*
G01X-849334Y973960D02*
G03X-848546Y974747I0J788D01*
G01X-836735D02*
G03X-835948Y973960I787J0D01*
G01X-850515Y983606D02*
G03I-1968J0D01*
G01X-849727D02*
G03I-2756J0D01*
G01X-849334D02*
G03I-3149J0D01*
G01X-856223Y972582D02*
G03X-856027Y972779I0J196D01*
G01X-856814D02*
G03X-856617Y972582I197J0D01*
G01X-858192D02*
G03X-857995Y972779I0J197D01*
G01X-858783D02*
G03X-858586Y972582I197J0D01*
G01X-860160D02*
G03X-859964Y972779I0J196D01*
G01X-860751D02*
G03X-860554Y972582I197J0D01*
G01X-862129D02*
G03X-861932Y972779I0J197D01*
G01X-862720D02*
G03X-862523Y972582I197J0D01*
G01X-820134Y994914D02*
X-820069Y994512D01*
G01X-815738Y995450D02*
X-815672Y995115D01*
G01X-816066Y995450D02*
X-816000Y995115D01*
G01X-820725Y995517D02*
X-820659Y995182D01*
G01X-813113Y995316D02*
X-813048Y995048D01*
G01X-813441Y995316D02*
X-813376Y995048D01*
G01X-814819Y994780D02*
X-814754Y994512D01*
G01X-818100Y995450D02*
X-818035Y995182D01*
G01X-821053Y995450D02*
X-820987Y995182D01*
G01X-823087Y995450D02*
X-823021Y995182D01*
G01X-815147Y994780D02*
X-815016Y994311D01*
G01X-813179Y995517D02*
X-813113Y995316D01*
G01X-815804Y995651D02*
X-815738Y995450D01*
G01X-819806Y994780D02*
X-819741Y994579D01*
G01X-823415Y995316D02*
X-823349Y995115D01*
G01X-829911Y996723D02*
X-829321Y994914D01*
G01X-829255Y994646D02*
X-828993Y993842D01*
G01X-829649Y996991D02*
X-828599Y993842D01*
G01X-822759Y991755D02*
X-821775Y988941D01*
G01X-822956Y991085D02*
X-822037Y988606D01*
G01X-825777Y995785D02*
X-825646Y995450D01*
G01X-819741Y994579D02*
X-819675Y994445D01*
G01X-820069Y994512D02*
X-819937Y994244D01*
G01X-820790Y995651D02*
X-820725Y995517D01*
G01X-823153Y995584D02*
X-823087Y995450D01*
G01X-824793Y994244D02*
X-824727Y994110D01*
G01X-826040Y995584D02*
X-825974Y995450D01*
G01X-827090Y995584D02*
X-827024Y995450D01*
G01X-813310Y995718D02*
X-813179Y995517D01*
G01X-813573D02*
X-813441Y995316D01*
G01X-814754Y994512D02*
X-814622Y994311D01*
G01X-815016D02*
X-814885Y994110D01*
G01X-818494Y995517D02*
X-818363Y995316D01*
G01X-823546Y995517D02*
X-823415Y995316D01*
G01X-824793Y994579D02*
X-824662Y994378D01*
G01X-818297Y995718D02*
X-818100Y995450D01*
G01X-813441Y995852D02*
X-813310Y995718D01*
G01X-813704Y995651D02*
X-813573Y995517D01*
G01X-815935Y995785D02*
X-815804Y995651D01*
G01X-814622Y994311D02*
X-814491Y994177D01*
G01X-816197Y995584D02*
X-816066Y995450D01*
G01X-814885Y994110D02*
X-814754Y993976D01*
G01X-794112Y983923D02*
X-794019Y985583D01*
G01X-794027Y985767D02*
X-794072Y984973D01*
G01X-796081Y983923D02*
X-795987Y985583D01*
G01X-795995Y985767D02*
X-796040Y984973D01*
G01X-798049Y983923D02*
X-797956Y985583D01*
G01X-797964Y985767D02*
X-798009Y984973D01*
G01X-800018Y983923D02*
X-799924Y985583D01*
G01X-799932Y985767D02*
X-799977Y984973D01*
G01X-794027Y985767D02*
X-794019Y985924D01*
G01X-795995Y985767D02*
X-795987Y985924D01*
G01X-797964Y985767D02*
X-797956Y985924D01*
G01X-799932Y985767D02*
X-799924Y985924D01*
G01X-801901Y985767D02*
X-801893Y985924D01*
G01X-794112Y983923D02*
X-794072Y984973D01*
G01X-796081Y983923D02*
X-796040Y984973D01*
G01X-798049Y983923D02*
X-798009Y984973D01*
G01X-800018Y983923D02*
X-799977Y984973D01*
G01X-801986Y983923D02*
X-801946Y984973D01*
G01X-793271Y986783D02*
Y986639D01*
G01X-793428Y987543D02*
Y979669D01*
G01X-793586Y986639D02*
Y986783D01*
G01X-793783Y986643D02*
Y982464D01*
G01X-793822Y972779D02*
Y975100D01*
G01X-794019Y971598D02*
Y977700D01*
G01Y987940D02*
Y985583D01*
G01X-794806D02*
Y987940D01*
G01Y977700D02*
Y971598D01*
G01X-795003Y975100D02*
Y972779D01*
G01X-795042Y986643D02*
Y982464D01*
G01X-795239Y986783D02*
Y986639D01*
G01X-795554D02*
Y986783D01*
G01X-795751Y986643D02*
Y982464D01*
G01X-795790Y972779D02*
Y975100D01*
G01X-795987Y971598D02*
Y977700D01*
G01Y987940D02*
Y985583D01*
G01X-796775D02*
Y987940D01*
G01Y977700D02*
Y971598D01*
G01X-796972Y975100D02*
Y972779D01*
G01X-797011Y986643D02*
Y982464D01*
G01X-797208Y986783D02*
Y986639D01*
G01X-797523D02*
Y986783D01*
G01X-797720Y986643D02*
Y982464D01*
G01X-797759Y972779D02*
Y975100D01*
G01X-797956Y971598D02*
Y977700D01*
G01Y987940D02*
Y985583D01*
G01X-798743D02*
Y987940D01*
G01Y971598D02*
Y977700D01*
G01X-798940Y975100D02*
Y972779D01*
G01X-798979Y986643D02*
Y982464D01*
G01X-799176Y986783D02*
Y986639D01*
G01X-799491D02*
Y986783D01*
G01X-799688Y986643D02*
Y982464D01*
G01X-799727Y972779D02*
Y975100D01*
G01X-799924Y977700D02*
Y971598D01*
G01Y987940D02*
Y985583D01*
G01X-800712D02*
Y987940D01*
G01Y971598D02*
Y977700D01*
G01X-800909Y975100D02*
Y972779D01*
G01X-800948Y986643D02*
Y982464D01*
G01X-801145Y986783D02*
Y986639D01*
G01X-801460D02*
Y986783D01*
G01X-801657Y986643D02*
Y982464D01*
G01X-801696Y972779D02*
Y975100D01*
G01X-801893Y977700D02*
Y971598D01*
G01Y987940D02*
Y985583D01*
G01X-802680D02*
Y987940D01*
G01Y977700D02*
Y971598D01*
G01X-802877Y975100D02*
Y972779D01*
G01X-802916Y986643D02*
Y982464D01*
G01X-803113Y986783D02*
Y986639D01*
G01X-803428D02*
Y986783D01*
G01X-803625Y986643D02*
Y982464D01*
G01X-803664Y972779D02*
Y975100D01*
G01X-803861Y971598D02*
Y977700D01*
G01Y987940D02*
Y985583D01*
G01X-804649D02*
Y987940D01*
G01Y971598D02*
Y977700D01*
G01X-804846Y975100D02*
Y972779D01*
G01X-804885Y986643D02*
Y982464D01*
G01X-805082Y986783D02*
Y986639D01*
G01X-805397D02*
Y986783D01*
G01X-805594Y986643D02*
Y982464D01*
G01X-805633Y972779D02*
Y975100D01*
G01X-805830Y977700D02*
Y971598D01*
G01Y987940D02*
Y985583D01*
G01X-806617D02*
Y987940D01*
G01Y971598D02*
Y977700D01*
G01X-806814Y975100D02*
Y972779D01*
G01X-806853Y986643D02*
Y982464D01*
G01X-807050Y986783D02*
Y986639D01*
G01X-807365D02*
Y986783D01*
G01X-807562Y986643D02*
Y982464D01*
G01X-807601Y972779D02*
Y975100D01*
G01X-807798Y977700D02*
Y971598D01*
G01Y987940D02*
Y985583D01*
G01X-808586D02*
Y987940D01*
G01Y977700D02*
Y971598D01*
G01X-808783Y975100D02*
Y972779D01*
G01X-808822Y986643D02*
Y982464D01*
G01X-809019Y986783D02*
Y986639D01*
G01X-794713Y983923D02*
X-794753Y984973D01*
G01X-796681Y983923D02*
X-796722Y984973D01*
G01X-798650Y983923D02*
X-798690Y984973D01*
G01X-800618Y983923D02*
X-800659Y984973D01*
G01X-802587Y983923D02*
X-802627Y984973D01*
G01X-804555Y983923D02*
X-804596Y984973D01*
G01X-806524Y983923D02*
X-806564Y984973D01*
G01X-808492Y983923D02*
X-808533Y984973D01*
G01X-810461Y983923D02*
X-810501Y984973D01*
G01X-812429Y983923D02*
X-812470Y984973D01*
G01X-794806Y985924D02*
X-794798Y985767D01*
G01X-796775Y985924D02*
X-796767Y985767D01*
G01X-798743Y985924D02*
X-798735Y985767D01*
G01X-800712Y985924D02*
X-800704Y985767D01*
G01X-802680Y985924D02*
X-802672Y985767D01*
G01X-804649Y985924D02*
X-804641Y985767D01*
G01X-806617Y985924D02*
X-806609Y985767D01*
G01X-808586Y985924D02*
X-808578Y985767D01*
G01X-810554Y985924D02*
X-810546Y985767D01*
G01X-812523Y985924D02*
X-812515Y985767D01*
G01X-814491Y985924D02*
X-814483Y985767D01*
G01X-794713Y983923D02*
X-794806Y985583D01*
G01X-796681Y983923D02*
X-796775Y985583D01*
G01X-798650Y983923D02*
X-798743Y985583D01*
G01X-800618Y983923D02*
X-800712Y985583D01*
G01X-802587Y983923D02*
X-802680Y985583D01*
G01X-804555Y983923D02*
X-804649Y985583D01*
G01X-806524Y983923D02*
X-806617Y985583D01*
G01X-808492Y983923D02*
X-808586Y985583D01*
G01X-810461Y983923D02*
X-810554Y985583D01*
G01X-812429Y983923D02*
X-812523Y985583D01*
G01X-814398Y983923D02*
X-814491Y985583D01*
G01X-794753Y984973D02*
X-794798Y985767D01*
G01X-796722Y984973D02*
X-796767Y985767D01*
G01X-798690Y984973D02*
X-798735Y985767D01*
G01X-800659Y984973D02*
X-800704Y985767D01*
G01X-802627Y984973D02*
X-802672Y985767D01*
G01X-804596Y984973D02*
X-804641Y985767D01*
G01X-806564Y984973D02*
X-806609Y985767D01*
G01X-808533Y984973D02*
X-808578Y985767D01*
G01X-810501Y984973D02*
X-810546Y985767D01*
G01X-812470Y984973D02*
X-812515Y985767D01*
G01X-814438Y984973D02*
X-814483Y985767D01*
G01X-820922Y995785D02*
X-820790Y995651D01*
G01X-819675Y994445D02*
X-819478Y994244D01*
G01X-821184Y995584D02*
X-821053Y995450D01*
G01X-819937Y994244D02*
X-819806Y994110D01*
G01X-823349Y995785D02*
X-823153Y995584D01*
G01X-825909Y995919D02*
X-825777Y995785D01*
G01X-826105Y995651D02*
X-826040Y995584D01*
G01X-824727Y994110D02*
X-824596Y993976D01*
G01X-826958Y995919D02*
X-826762Y995718D01*
G01X-827155Y995651D02*
X-827090Y995584D01*
G01X-816132Y995919D02*
X-815935Y995785D01*
G01X-818691Y995651D02*
X-818494Y995517D01*
G01X-821118Y995919D02*
X-820922Y995785D01*
G01X-819806Y994110D02*
X-819609Y993976D01*
G01X-823546Y995919D02*
X-823349Y995785D01*
G01X-824662Y994378D02*
X-824465Y994244D01*
G01X-818297Y995718D02*
X-818625Y995919D01*
G01X-820069Y995316D02*
X-820134Y994914D01*
G01X-801986Y983923D02*
X-801893Y985583D01*
G01X-801901Y985767D02*
X-801946Y984973D01*
G01X-803955Y983923D02*
X-803861Y985583D01*
G01X-803869Y985767D02*
X-803914Y984973D01*
G01X-805923Y983923D02*
X-805830Y985583D01*
G01X-805838Y985767D02*
X-805883Y984973D01*
G01X-807892Y983923D02*
X-807798Y985583D01*
G01X-807806Y985767D02*
X-807851Y984973D01*
G01X-809860Y983923D02*
X-809767Y985583D01*
G01X-809775Y985767D02*
X-809820Y984973D01*
G01X-811829Y983923D02*
X-811735Y985583D01*
G01X-811743Y985767D02*
X-811788Y984973D01*
G01X-813797Y983923D02*
X-813704Y985583D01*
G01X-813712Y985767D02*
X-813757Y984973D01*
G01X-815766Y983923D02*
X-815672Y985583D01*
G01X-815680Y985767D02*
X-815725Y984973D01*
G01X-817734Y983923D02*
X-817641Y985583D01*
G01X-817649Y985767D02*
X-817694Y984973D01*
G01X-819703Y983923D02*
X-819609Y985583D01*
G01X-819617Y985767D02*
X-819662Y984973D01*
G01X-821671Y983923D02*
X-821578Y985583D01*
G01X-821586Y985767D02*
X-821631Y984973D01*
G01X-823640Y983923D02*
X-823546Y985583D01*
G01X-823554Y985767D02*
X-823599Y984973D01*
G01X-825608Y983923D02*
X-825515Y985583D01*
G01X-825523Y985767D02*
X-825568Y984973D01*
G01X-827577Y983923D02*
X-827483Y985583D01*
G01X-827491Y985767D02*
X-827536Y984973D01*
G01X-829545Y983923D02*
X-829452Y985583D01*
G01X-829460Y985767D02*
X-829505Y984973D01*
G01X-803869Y985767D02*
X-803861Y985924D01*
G01X-805838Y985767D02*
X-805830Y985924D01*
G01X-807806Y985767D02*
X-807798Y985924D01*
G01X-809775Y985767D02*
X-809767Y985924D01*
G01X-811743Y985767D02*
X-811735Y985924D01*
G01X-813712Y985767D02*
X-813704Y985924D01*
G01X-815680Y985767D02*
X-815672Y985924D01*
G01X-817649Y985767D02*
X-817641Y985924D01*
G01X-819617Y985767D02*
X-819609Y985924D01*
G01X-821586Y985767D02*
X-821578Y985924D01*
G01X-823554Y985767D02*
X-823546Y985924D01*
G01X-825523Y985767D02*
X-825515Y985924D01*
G01X-827491Y985767D02*
X-827483Y985924D01*
G01X-829460Y985767D02*
X-829452Y985924D01*
G01X-803955Y983923D02*
X-803914Y984973D01*
G01X-805923Y983923D02*
X-805883Y984973D01*
G01X-807892Y983923D02*
X-807851Y984973D01*
G01X-809860Y983923D02*
X-809820Y984973D01*
G01X-811829Y983923D02*
X-811788Y984973D01*
G01X-813797Y983923D02*
X-813757Y984973D01*
G01X-815766Y983923D02*
X-815725Y984973D01*
G01X-817734Y983923D02*
X-817694Y984973D01*
G01X-819703Y983923D02*
X-819662Y984973D01*
G01X-821671Y983923D02*
X-821631Y984973D01*
G01X-823640Y983923D02*
X-823599Y984973D01*
G01X-825608Y983923D02*
X-825568Y984973D01*
G01X-827577Y983923D02*
X-827536Y984973D01*
G01X-829545Y983923D02*
X-829505Y984973D01*
G01X-809334Y986639D02*
Y986783D01*
G01X-809531Y986643D02*
Y982464D01*
G01X-809570Y972779D02*
Y975100D01*
G01X-809767Y971598D02*
Y977700D01*
G01Y987940D02*
Y985583D01*
G01X-810554D02*
Y987940D01*
G01Y977700D02*
Y971598D01*
G01X-810751Y975100D02*
Y972779D01*
G01X-810790Y986643D02*
Y982464D01*
G01X-810987Y986783D02*
Y986639D01*
G01X-811066Y997267D02*
Y988409D01*
G01X-811302Y986639D02*
Y986783D01*
G01X-811499Y986643D02*
Y982464D01*
G01X-811538Y972779D02*
Y975100D01*
G01X-811735Y971598D02*
Y977700D01*
G01Y987940D02*
Y985583D01*
G01X-812195Y996991D02*
Y993842D01*
G01X-812523Y985583D02*
Y987940D01*
G01Y977700D02*
Y971598D01*
G01Y996991D02*
Y993842D01*
G01X-812720Y975100D02*
Y972779D01*
G01X-812759Y986643D02*
Y982464D01*
G01X-812956Y986783D02*
Y986639D01*
G01X-813048Y995048D02*
Y994780D01*
G01X-813271Y986639D02*
Y986783D01*
G01X-813376Y995048D02*
Y994780D01*
G01X-813468Y986643D02*
Y982464D01*
G01X-813507Y972779D02*
Y975100D01*
G01X-813704Y971598D02*
Y977700D01*
G01Y987940D02*
Y985583D01*
G01X-814491D02*
Y987940D01*
G01Y971598D02*
Y977700D01*
G01X-814688Y975100D02*
Y972779D01*
G01X-814727Y986643D02*
Y982464D01*
G01X-814819Y995048D02*
Y994780D01*
G01X-814924Y986783D02*
Y986639D01*
G01X-815147Y995048D02*
Y994780D01*
G01X-815239Y986639D02*
Y986783D01*
G01X-815436Y986643D02*
Y982464D01*
G01X-815475Y972779D02*
Y975100D01*
G01X-815672Y977700D02*
Y971598D01*
G01Y987940D02*
Y985583D01*
G01Y995115D02*
Y993842D01*
G01X-816000Y995115D02*
Y993842D01*
G01X-816460Y985583D02*
Y987940D01*
G01Y971598D02*
Y977700D01*
G01X-816657Y975100D02*
Y972779D01*
G01X-816696Y986643D02*
Y982464D01*
G01X-816893Y986783D02*
Y986639D01*
G01X-817181Y995383D02*
Y993842D01*
G01Y995986D02*
Y995651D01*
G01X-817208Y986639D02*
Y986783D01*
G01X-817405Y986643D02*
Y982464D01*
G01X-817444Y972779D02*
Y975100D01*
G01X-817510Y995986D02*
Y993842D01*
G01X-817641Y977700D02*
Y971598D01*
G01Y987940D02*
Y985583D01*
G01X-818035Y995182D02*
Y994914D01*
G01X-818363Y995316D02*
Y995182D01*
G01X-818428Y985583D02*
Y987940D01*
G01Y977700D02*
Y971598D01*
G01X-818625Y975100D02*
Y972779D01*
G01X-818664Y986643D02*
Y982464D01*
G01X-818861Y986783D02*
Y986639D01*
G01X-819176D02*
Y986783D01*
G01X-819373Y986643D02*
Y982464D01*
G01X-819412Y972779D02*
Y975100D01*
G01X-819609Y971598D02*
Y977700D01*
G01Y987940D02*
Y985583D01*
G01X-819741Y995249D02*
Y995182D01*
G01X-819806Y994914D02*
Y994780D01*
G01X-820200Y991755D02*
Y988606D01*
G01X-820397Y985583D02*
Y987940D01*
G01Y977700D02*
Y971598D01*
G01X-820594Y975100D02*
Y972779D01*
G01Y991085D02*
Y988606D01*
G01X-820633Y986643D02*
Y982464D01*
G01X-820659Y995182D02*
Y993842D01*
G01X-820830Y986783D02*
Y986639D01*
G01X-820987Y995182D02*
Y993842D01*
G01X-821145Y986639D02*
Y986783D01*
G01X-821342Y986643D02*
Y982464D01*
G01X-821381Y972779D02*
Y975100D01*
G01X-821578Y971598D02*
Y977700D01*
G01Y987940D02*
Y985583D01*
G01X-822168Y995383D02*
Y993842D01*
G01Y996991D02*
Y995651D01*
G01X-822365Y985583D02*
Y987940D01*
G01Y971598D02*
Y977700D01*
G01X-822496Y996991D02*
Y993842D01*
G01X-822562Y975100D02*
Y972779D01*
G01X-822601Y986643D02*
Y982464D01*
G01X-822798Y986783D02*
Y986639D01*
G01X-822956Y991085D02*
Y988606D01*
G01X-823021Y995182D02*
Y994646D01*
G01X-823113Y986639D02*
Y986783D01*
G01X-823310Y986643D02*
Y982464D01*
G01X-823349Y972779D02*
Y975100D01*
G01Y991755D02*
Y988606D01*
G01Y995115D02*
Y994713D01*
G01X-823546Y977700D02*
Y971598D01*
G01Y987940D02*
Y985583D01*
G01X-824334D02*
Y987940D01*
G01Y977700D02*
Y971598D01*
G01X-824531Y975100D02*
Y972779D01*
G01X-824570Y986643D02*
Y982464D01*
G01X-824767Y986783D02*
Y986639D01*
G01X-824793Y995249D02*
Y994579D01*
G01Y994244D02*
Y992770D01*
G01Y995986D02*
Y995584D01*
G01X-825082Y986639D02*
Y986783D01*
G01X-825121Y995986D02*
Y992770D01*
G01X-825279Y986643D02*
Y982464D01*
G01X-825318Y972779D02*
Y975100D01*
G01X-825515Y971598D02*
Y977700D01*
G01Y987940D02*
Y985583D01*
G01X-825646Y995450D02*
Y993842D01*
G01X-825974Y995450D02*
Y993842D01*
G01X-826302Y985583D02*
Y987940D01*
G01Y977700D02*
Y971598D01*
G01X-826499Y975100D02*
Y972779D01*
G01X-826538Y986643D02*
Y982464D01*
G01X-826696Y995450D02*
Y993842D01*
G01X-826735Y986783D02*
Y986639D01*
G01X-826893Y996007D02*
Y999944D01*
G01X-827024Y995450D02*
Y993842D01*
G01X-827050Y986639D02*
Y986783D01*
G01X-827247Y986643D02*
Y982464D01*
G01X-827286Y972779D02*
Y975100D01*
G01X-827483Y971598D02*
Y977700D01*
G01Y987940D02*
Y985583D01*
G01X-827746Y995517D02*
Y993842D01*
G01Y995986D02*
Y995785D01*
G01X-828074Y995986D02*
Y993842D01*
G01X-828271Y985583D02*
Y987940D01*
G01Y971598D02*
Y977700D01*
G01X-828468Y975100D02*
Y972779D01*
G01X-828507Y986643D02*
Y982464D01*
G01X-828704Y986783D02*
Y986639D01*
G01X-828861Y999944D02*
Y996007D01*
G01X-829019Y986639D02*
Y986783D01*
G01X-829216Y986643D02*
Y982464D01*
G01X-829255Y972779D02*
Y975100D01*
G01X-829452Y977700D02*
Y971598D01*
G01Y987940D02*
Y985583D01*
G01X-830239D02*
Y987940D01*
G01X-831814Y1006736D02*
Y995909D01*
G01X-832011Y982019D02*
Y973960D01*
G01X-832286Y997267D02*
Y988409D01*
G01X-833094Y980653D02*
Y990495D01*
G01X-834275Y979472D02*
Y983409D01*
G01X-836538Y995909D02*
Y1006736D01*
G01X-836735Y1005259D02*
Y973960D01*
G01X-848546Y1005259D02*
Y973960D01*
G01X-848743Y1006736D02*
Y995909D01*
G01X-814398Y983923D02*
X-814438Y984973D01*
G01X-816366Y983923D02*
X-816407Y984973D01*
G01X-818335Y983923D02*
X-818375Y984973D01*
G01X-820303Y983923D02*
X-820344Y984973D01*
G01X-822272Y983923D02*
X-822312Y984973D01*
G01X-824240Y983923D02*
X-824281Y984973D01*
G01X-826209Y983923D02*
X-826249Y984973D01*
G01X-828177Y983923D02*
X-828218Y984973D01*
G01X-830146Y983923D02*
X-830186Y984973D01*
G01X-816460Y985924D02*
X-816452Y985767D01*
G01X-818428Y985924D02*
X-818420Y985767D01*
G01X-820397Y985924D02*
X-820389Y985767D01*
G01X-822365Y985924D02*
X-822357Y985767D01*
G01X-824334Y985924D02*
X-824326Y985767D01*
G01X-826302Y985924D02*
X-826294Y985767D01*
G01X-828271Y985924D02*
X-828263Y985767D01*
G01X-830239Y985924D02*
X-830231Y985767D01*
G01X-816366Y983923D02*
X-816460Y985583D01*
G01X-818335Y983923D02*
X-818428Y985583D01*
G01X-820303Y983923D02*
X-820397Y985583D01*
G01X-822272Y983923D02*
X-822365Y985583D01*
G01X-824240Y983923D02*
X-824334Y985583D01*
G01X-826209Y983923D02*
X-826302Y985583D01*
G01X-828177Y983923D02*
X-828271Y985583D01*
G01X-830146Y983923D02*
X-830239Y985583D01*
G01X-855736Y983923D02*
X-855830Y985583D01*
G01X-816407Y984973D02*
X-816452Y985767D01*
G01X-818375Y984973D02*
X-818420Y985767D01*
G01X-820344Y984973D02*
X-820389Y985767D01*
G01X-822312Y984973D02*
X-822357Y985767D01*
G01X-824281Y984973D02*
X-824326Y985767D01*
G01X-826249Y984973D02*
X-826294Y985767D01*
G01X-828218Y984973D02*
X-828263Y985767D01*
G01X-830186Y984973D02*
X-830231Y985767D01*
G01X-855777Y984973D02*
X-855822Y985767D01*
G01X-813441Y995852D02*
X-813573Y995919D01*
G01X-816197Y995584D02*
X-816328Y995651D01*
G01X-814622Y993909D02*
X-814754Y993976D01*
G01X-821184Y995584D02*
X-821315Y995651D01*
G01X-819347Y994177D02*
X-819478Y994244D01*
G01X-823546Y995517D02*
X-823809Y995651D01*
G01X-826105D02*
X-826237Y995718D01*
G01X-827155Y995651D02*
X-827286Y995718D01*
G01X-824465Y993909D02*
X-824596Y993976D01*
G01X-820594Y991085D02*
X-821512Y988606D01*
G01X-820790Y991755D02*
X-821775Y988941D01*
G01X-815016Y995517D02*
X-815082Y995316D01*
G01X-818363Y994512D02*
X-818428Y994311D01*
G01X-823349Y994713D02*
X-823415Y994512D01*
G01X-813048Y994780D02*
X-813179Y994311D01*
G01X-813376Y994780D02*
X-813441Y994512D01*
G01X-814754Y995316D02*
X-814819Y995048D01*
G01X-815082Y995316D02*
X-815147Y995048D01*
G01X-818035Y994512D02*
X-818100Y994244D01*
G01X-823021Y994646D02*
X-823087Y994378D01*
G01X-855136Y983923D02*
X-855042Y985583D01*
G01X-855050Y985767D02*
X-855095Y984973D01*
G01X-857104Y983923D02*
X-857011Y985583D01*
G01X-857019Y985767D02*
X-857064Y984973D01*
G01X-859073Y983923D02*
X-858979Y985583D01*
G01X-858987Y985767D02*
X-859032Y984973D01*
G01X-861041Y983923D02*
X-860948Y985583D01*
G01X-860956Y985767D02*
X-861001Y984973D01*
G01X-863010Y983923D02*
X-862916Y985583D01*
G01X-862924Y985767D02*
X-862969Y984973D01*
G01X-855050Y985767D02*
X-855042Y985924D01*
G01X-857019Y985767D02*
X-857011Y985924D01*
G01X-858987Y985767D02*
X-858979Y985924D01*
G01X-860956Y985767D02*
X-860948Y985924D01*
G01X-862924Y985767D02*
X-862916Y985924D01*
G01X-855136Y983923D02*
X-855095Y984973D01*
G01X-857104Y983923D02*
X-857064Y984973D01*
G01X-859073Y983923D02*
X-859032Y984973D01*
G01X-861041Y983923D02*
X-861001Y984973D01*
G01X-863010Y983923D02*
X-862969Y984973D01*
G01X-851007Y983409D02*
Y979472D01*
G01X-852188Y990495D02*
Y980653D01*
G01X-853271Y980965D02*
Y973960D01*
G01X-853468Y995909D02*
Y1006736D01*
G01X-855042Y987940D02*
Y985583D01*
G01X-855830D02*
Y987940D01*
G01Y971598D02*
Y977700D01*
G01X-856027Y975100D02*
Y972779D01*
G01X-856066Y986643D02*
Y982464D01*
G01X-856263Y986783D02*
Y986639D01*
G01X-856420Y999944D02*
Y996007D01*
G01X-856578Y986639D02*
Y986783D01*
G01X-856775Y986643D02*
Y982464D01*
G01X-856814Y972779D02*
Y975100D01*
G01X-857011Y977700D02*
Y971598D01*
G01Y987940D02*
Y985583D01*
G01X-857798D02*
Y987940D01*
G01Y971598D02*
Y977700D01*
G01X-857995Y975100D02*
Y972779D01*
G01X-858035Y986643D02*
Y982464D01*
G01X-858231Y986783D02*
Y986639D01*
G01X-858389Y999944D02*
Y996007D01*
G01X-858546Y986639D02*
Y986783D01*
G01X-858743Y986643D02*
Y982464D01*
G01X-858783Y972779D02*
Y975100D01*
G01X-858979Y977700D02*
Y971598D01*
G01Y987940D02*
Y985583D01*
G01X-859767D02*
Y987940D01*
G01Y977700D02*
Y971598D01*
G01X-859964Y975100D02*
Y972779D01*
G01X-860003Y986643D02*
Y982464D01*
G01X-860200Y986783D02*
Y986639D01*
G01X-860515D02*
Y986783D01*
G01X-860712Y986643D02*
Y982464D01*
G01X-860751Y972779D02*
Y975100D01*
G01X-860948Y971598D02*
Y977700D01*
G01Y987940D02*
Y985583D01*
G01X-861735D02*
Y987940D01*
G01Y977700D02*
Y971598D01*
G01X-861932Y975100D02*
Y972779D01*
G01X-861972Y986643D02*
Y982464D01*
G01X-862168Y986783D02*
Y986639D01*
G01X-862483D02*
Y986783D01*
G01X-862680Y986643D02*
Y982464D01*
G01X-862720Y972779D02*
Y975100D01*
G01X-862916Y971598D02*
Y977700D01*
G01Y987940D02*
Y985583D01*
G01X-863704D02*
Y987940D01*
G01X-855736Y983923D02*
X-855777Y984973D01*
G01X-857705Y983923D02*
X-857746Y984973D01*
G01X-859673Y983923D02*
X-859714Y984973D01*
G01X-861642Y983923D02*
X-861683Y984973D01*
G01X-863611Y983923D02*
X-863651Y984973D01*
G01X-855830Y985924D02*
X-855822Y985767D01*
G01X-857798Y985924D02*
X-857790Y985767D01*
G01X-859767Y985924D02*
X-859759Y985767D01*
G01X-861735Y985924D02*
X-861727Y985767D01*
G01X-863704Y985924D02*
X-863696Y985767D01*
G01X-857705Y983923D02*
X-857798Y985583D01*
G01X-859673Y983923D02*
X-859767Y985583D01*
G01X-861642Y983923D02*
X-861735Y985583D01*
G01X-863611Y983923D02*
X-863704Y985583D01*
G01X-857746Y984973D02*
X-857790Y985767D01*
G01X-859714Y984973D02*
X-859759Y985767D01*
G01X-861683Y984973D02*
X-861727Y985767D01*
G01X-863651Y984973D02*
X-863696Y985767D01*
G01X-816132Y995919D02*
X-816328Y995986D01*
G01X-821118Y995919D02*
X-821315Y995986D01*
G01X-819412Y993909D02*
X-819609Y993976D01*
G01X-825909Y995919D02*
X-826105Y995986D01*
G01X-826958Y995919D02*
X-827155Y995986D01*
G01X-813573Y995919D02*
X-813835Y995986D01*
G01X-813704Y995651D02*
X-813966Y995718D01*
G01X-816328Y995651D02*
X-816591Y995718D01*
G01X-814229Y994110D02*
X-814491Y994177D01*
G01X-821315Y995651D02*
X-821578Y995718D01*
G01X-814360Y993842D02*
X-814622Y993909D01*
G01X-823546Y995919D02*
X-823809Y995986D01*
G01X-819084Y994110D02*
X-819347Y994177D01*
G01X-824202D02*
X-824465Y994244D01*
G01X-824202Y993842D02*
X-824465Y993909D01*
G01X-819675Y995383D02*
X-819741Y995249D01*
G01X-819937Y995584D02*
X-820069Y995316D01*
G01X-823415Y994512D02*
X-823481Y994378D01*
G01X-824727Y995718D02*
X-824793Y995584D01*
G01X-826630D02*
X-826696Y995450D01*
G01X-830174Y996991D02*
X-831223Y993842D01*
G01X-830567Y994646D02*
X-830830Y993842D01*
G01X-829911Y996723D02*
X-830502Y994914D01*
G01X-818625Y995919D02*
X-819019Y995986D01*
G01X-818691Y995651D02*
X-819084Y995718D01*
G01X-819019Y993842D02*
X-819412Y993909D01*
G01X-813179Y994311D02*
X-813310Y994110D01*
G01X-813441Y994512D02*
X-813573Y994311D01*
G01X-814622Y995517D02*
X-814754Y995316D01*
G01X-814885Y995718D02*
X-815016Y995517D01*
G01X-824662Y995450D02*
X-824793Y995249D01*
G01X-858389Y996007D02*
X-856420D01*
G01X-826893D02*
X-828861D01*
G01X-827746Y995986D02*
X-828074D01*
G01X-824793D02*
X-825121D01*
G01X-827155D02*
X-827418D01*
G01X-826105D02*
X-826368D01*
G01X-821315D02*
X-821578D01*
G01X-823809D02*
X-824202D01*
G01X-813835D02*
X-814360D01*
G01X-817181D02*
X-817510D01*
G01X-816328D02*
X-816591D01*
G01X-848743Y995909D02*
X-853468D01*
G01X-831814D02*
X-836538D01*
G01X-827286Y995718D02*
X-827418D01*
G01X-826237D02*
X-826433D01*
G01X-813966D02*
X-814229D01*
G01X-823809Y995651D02*
X-824202D01*
G01X-818363Y995182D02*
X-819741D01*
G01X-829321Y994914D02*
X-830502D01*
G01X-818035D02*
X-819806D01*
G01X-829255Y994646D02*
X-830567D01*
G01X-818035Y994512D02*
X-818363D01*
G01X-823940Y994177D02*
X-824202D01*
G01X-813966Y994110D02*
X-814229D01*
G01X-830830Y993842D02*
X-831223D01*
G01X-827746D02*
X-828074D01*
G01X-828599D02*
X-828993D01*
G01X-826696D02*
X-827024D01*
G01X-825646D02*
X-825974D01*
G01X-820659D02*
X-820987D01*
G01X-822168D02*
X-822496D01*
G01X-823809D02*
X-824202D01*
G01X-813835D02*
X-814360D01*
G01X-815672D02*
X-816000D01*
G01X-817181D02*
X-817510D01*
G01X-812195D02*
X-812523D01*
G01X-824793Y992770D02*
X-825121D01*
G01X-822759Y991755D02*
X-823349D01*
G01X-820200D02*
X-820790D01*
G01X-771479Y990495D02*
X-833094D01*
G01X-822956Y988606D02*
X-823349D01*
G01X-821512D02*
X-822037D01*
G01X-820200D02*
X-820594D01*
G01X-862916Y987940D02*
X-863704D01*
G01X-860948D02*
X-861735D01*
G01X-858979D02*
X-859767D01*
G01X-857011D02*
X-857798D01*
G01X-855042D02*
X-855830D01*
G01X-829452D02*
X-830239D01*
G01X-827483D02*
X-828271D01*
G01X-825515D02*
X-826302D01*
G01X-823546D02*
X-824334D01*
G01X-821578D02*
X-822365D01*
G01X-819609D02*
X-820397D01*
G01X-817641D02*
X-818428D01*
G01X-815672D02*
X-816460D01*
G01X-813704D02*
X-814491D01*
G01X-811735D02*
X-812523D01*
G01X-809767D02*
X-810554D01*
G01X-807798D02*
X-808586D01*
G01X-805830D02*
X-806617D01*
G01X-803861D02*
X-804649D01*
G01X-801893D02*
X-802680D01*
G01X-799924D02*
X-800712D01*
G01X-797956D02*
X-798743D01*
G01X-795987D02*
X-796775D01*
G01X-794019D02*
X-794806D01*
G01X-811853Y987621D02*
X-831499D01*
G01X-862916Y987257D02*
X-863704D01*
G01X-860948D02*
X-861735D01*
G01X-858979D02*
X-859767D01*
G01X-857011D02*
X-857798D01*
G01X-855042D02*
X-855830D01*
G01X-829452D02*
X-830239D01*
G01X-827483D02*
X-828271D01*
G01X-825515D02*
X-826302D01*
G01X-823546D02*
X-824334D01*
G01X-821578D02*
X-822365D01*
G01X-819609D02*
X-820397D01*
G01X-817641D02*
X-818428D01*
G01X-815672D02*
X-816460D01*
G01X-813704D02*
X-814491D01*
G01X-811735D02*
X-812523D01*
G01X-809767D02*
X-810554D01*
G01X-807798D02*
X-808586D01*
G01X-805830D02*
X-806617D01*
G01X-803861D02*
X-804649D01*
G01X-801893D02*
X-802680D01*
G01X-799924D02*
X-800712D01*
G01X-797956D02*
X-798743D01*
G01X-795987D02*
X-796775D01*
G01X-794019D02*
X-794806D01*
G01X-862916Y987195D02*
X-863704D01*
G01X-860948D02*
X-861735D01*
G01X-858979D02*
X-859767D01*
G01X-857011D02*
X-857798D01*
G01X-855042D02*
X-855830D01*
G01X-829452D02*
X-830239D01*
G01X-827483D02*
X-828271D01*
G01X-825515D02*
X-826302D01*
G01X-823546D02*
X-824334D01*
G01X-821578D02*
X-822365D01*
G01X-819609D02*
X-820397D01*
G01X-817641D02*
X-818428D01*
G01X-815672D02*
X-816460D01*
G01X-813704D02*
X-814491D01*
G01X-811735D02*
X-812523D01*
G01X-809767D02*
X-810554D01*
G01X-807798D02*
X-808586D01*
G01X-805830D02*
X-806617D01*
G01X-803861D02*
X-804649D01*
G01X-801893D02*
X-802680D01*
G01X-799924D02*
X-800712D01*
G01X-797956D02*
X-798743D01*
G01X-795987D02*
X-796775D01*
G01X-794019D02*
X-794806D01*
G01X-796775Y986868D02*
X-795987D01*
G01X-794806D02*
X-794019D01*
G01X-800712D02*
X-799924D01*
G01X-798743D02*
X-797956D01*
G01X-802680D02*
X-801893D01*
G01X-806617D02*
X-805830D01*
G01X-804649D02*
X-803861D01*
G01X-810554D02*
X-809767D01*
G01X-808586D02*
X-807798D01*
G01X-812523D02*
X-811735D01*
G01X-816460D02*
X-815672D01*
G01X-814491D02*
X-813704D01*
G01X-820397D02*
X-819609D01*
G01X-818428D02*
X-817641D01*
G01X-822365D02*
X-821578D01*
G01X-826302D02*
X-825515D01*
G01X-824334D02*
X-823546D01*
G01X-830239D02*
X-829452D01*
G01X-828271D02*
X-827483D01*
G01X-855830D02*
X-855042D01*
G01X-859767D02*
X-858979D01*
G01X-857798D02*
X-857011D01*
G01X-863704D02*
X-862916D01*
G01X-861735D02*
X-860948D01*
G01X-793586Y986783D02*
X-793271D01*
G01X-797523D02*
X-797208D01*
G01X-795554D02*
X-795239D01*
G01X-799491D02*
X-799176D01*
G01X-803428D02*
X-803113D01*
G01X-801460D02*
X-801145D01*
G01X-807365D02*
X-807050D01*
G01X-805397D02*
X-805082D01*
G01X-809334D02*
X-809019D01*
G01X-813271D02*
X-812956D01*
G01X-811302D02*
X-810987D01*
G01X-817208D02*
X-816893D01*
G01X-815239D02*
X-814924D01*
G01X-819176D02*
X-818861D01*
G01X-823113D02*
X-822798D01*
G01X-821145D02*
X-820830D01*
G01X-827050D02*
X-826735D01*
G01X-825082D02*
X-824767D01*
G01X-829019D02*
X-828704D01*
G01X-856578D02*
X-856263D01*
G01X-860515D02*
X-860200D01*
G01X-858546D02*
X-858231D01*
G01X-862483D02*
X-862168D01*
G01X-793586Y986639D02*
X-793271D01*
G01X-797523D02*
X-797208D01*
G01X-795554D02*
X-795239D01*
G01X-799491D02*
X-799176D01*
G01X-803428D02*
X-803113D01*
G01X-801460D02*
X-801145D01*
G01X-807365D02*
X-807050D01*
G01X-805397D02*
X-805082D01*
G01X-809334D02*
X-809019D01*
G01X-813271D02*
X-812956D01*
G01X-811302D02*
X-810987D01*
G01X-817208D02*
X-816893D01*
G01X-815239D02*
X-814924D01*
G01X-819176D02*
X-818861D01*
G01X-823113D02*
X-822798D01*
G01X-821145D02*
X-820830D01*
G01X-827050D02*
X-826735D01*
G01X-825082D02*
X-824767D01*
G01X-829019D02*
X-828704D01*
G01X-856578D02*
X-856263D01*
G01X-860515D02*
X-860200D01*
G01X-858546D02*
X-858231D01*
G01X-862483D02*
X-862168D01*
G01X-861972Y986259D02*
X-862680D01*
G01X-860003D02*
X-860712D01*
G01X-858035D02*
X-858743D01*
G01X-856066D02*
X-856775D01*
G01X-828507D02*
X-829216D01*
G01X-826538D02*
X-827247D01*
G01X-824570D02*
X-825279D01*
G01X-822601D02*
X-823310D01*
G01X-820633D02*
X-821342D01*
G01X-818664D02*
X-819373D01*
G01X-816696D02*
X-817405D01*
G01X-814727D02*
X-815436D01*
G01X-812759D02*
X-813468D01*
G01X-810790D02*
X-811499D01*
G01X-808822D02*
X-809531D01*
G01X-806853D02*
X-807562D01*
G01X-804885D02*
X-805594D01*
G01X-802916D02*
X-803625D01*
G01X-800948D02*
X-801657D01*
G01X-798979D02*
X-799688D01*
G01X-797011D02*
X-797720D01*
G01X-795042D02*
X-795751D01*
G01X-793074D02*
X-793783D01*
G01Y986223D02*
X-793074D01*
G01X-797720D02*
X-797011D01*
G01X-795751D02*
X-795042D01*
G01X-799688D02*
X-798979D01*
G01X-803625D02*
X-802916D01*
G01X-801657D02*
X-800948D01*
G01X-807562D02*
X-806853D01*
G01X-805594D02*
X-804885D01*
G01X-809531D02*
X-808822D01*
G01X-813468D02*
X-812759D01*
G01X-811499D02*
X-810790D01*
G01X-817405D02*
X-816696D01*
G01X-815436D02*
X-814727D01*
G01X-819373D02*
X-818664D01*
G01X-823310D02*
X-822601D01*
G01X-821342D02*
X-820633D01*
G01X-827247D02*
X-826538D01*
G01X-825279D02*
X-824570D01*
G01X-829216D02*
X-828507D01*
G01X-856775D02*
X-856066D01*
G01X-858743D02*
X-858035D01*
G01X-862680D02*
X-861972D01*
G01X-860712D02*
X-860003D01*
G01X-833094Y986165D02*
X-771479D01*
G01X-861972Y985891D02*
X-862680D01*
G01X-860003D02*
X-860712D01*
G01X-858035D02*
X-858743D01*
G01X-856066D02*
X-856775D01*
G01X-828507D02*
X-829216D01*
G01X-826538D02*
X-827247D01*
G01X-824570D02*
X-825279D01*
G01X-822601D02*
X-823310D01*
G01X-820633D02*
X-821342D01*
G01X-818664D02*
X-819373D01*
G01X-816696D02*
X-817405D01*
G01X-814727D02*
X-815436D01*
G01X-812759D02*
X-813468D01*
G01X-810790D02*
X-811499D01*
G01X-808822D02*
X-809531D01*
G01X-806853D02*
X-807562D01*
G01X-804885D02*
X-805594D01*
G01X-802916D02*
X-803625D01*
G01X-800948D02*
X-801657D01*
G01X-798979D02*
X-799688D01*
G01X-797011D02*
X-797720D01*
G01X-795042D02*
X-795751D01*
G01X-793074D02*
X-793783D01*
G01X-862924Y985767D02*
X-863696D01*
G01X-860956D02*
X-861727D01*
G01X-858987D02*
X-859759D01*
G01X-857019D02*
X-857790D01*
G01X-855050D02*
X-855822D01*
G01X-829460D02*
X-830231D01*
G01X-827491D02*
X-828263D01*
G01X-825523D02*
X-826294D01*
G01X-823554D02*
X-824326D01*
G01X-821586D02*
X-822357D01*
G01X-819617D02*
X-820389D01*
G01X-817649D02*
X-818420D01*
G01X-815680D02*
X-816452D01*
G01X-813712D02*
X-814483D01*
G01X-811743D02*
X-812515D01*
G01X-809775D02*
X-810546D01*
G01X-807806D02*
X-808578D01*
G01X-805838D02*
X-806609D01*
G01X-803869D02*
X-804641D01*
G01X-801901D02*
X-802672D01*
G01X-799932D02*
X-800704D01*
G01X-797964D02*
X-798735D01*
G01X-795995D02*
X-796767D01*
G01X-794027D02*
X-794798D01*
G01X-796767Y985433D02*
X-795995D01*
G01X-794798D02*
X-794027D01*
G01X-800704D02*
X-799932D01*
G01X-798735D02*
X-797964D01*
G01X-802672D02*
X-801901D01*
G01X-806609D02*
X-805838D01*
G01X-804641D02*
X-803869D01*
G01X-810546D02*
X-809775D01*
G01X-808578D02*
X-807806D01*
G01X-812515D02*
X-811743D01*
G01X-816452D02*
X-815680D01*
G01X-814483D02*
X-813712D01*
G01X-820389D02*
X-819617D01*
G01X-818420D02*
X-817649D01*
G01X-822357D02*
X-821586D01*
G01X-826294D02*
X-825523D01*
G01X-824326D02*
X-823554D01*
G01X-830231D02*
X-829460D01*
G01X-828263D02*
X-827491D01*
G01X-855822D02*
X-855050D01*
G01X-859759D02*
X-858987D01*
G01X-857790D02*
X-857019D01*
G01X-863696D02*
X-862924D01*
G01X-861727D02*
X-860956D01*
G01X-793783Y985043D02*
X-793074D01*
G01X-797720D02*
X-797011D01*
G01X-795751D02*
X-795042D01*
G01X-799688D02*
X-798979D01*
G01X-803625D02*
X-802916D01*
G01X-801657D02*
X-800948D01*
G01X-807562D02*
X-806853D01*
G01X-805594D02*
X-804885D01*
G01X-809531D02*
X-808822D01*
G01X-813468D02*
X-812759D01*
G01X-811499D02*
X-810790D01*
G01X-817405D02*
X-816696D01*
G01X-815436D02*
X-814727D01*
G01X-819373D02*
X-818664D01*
G01X-823310D02*
X-822601D01*
G01X-821342D02*
X-820633D01*
G01X-827247D02*
X-826538D01*
G01X-825279D02*
X-824570D01*
G01X-829216D02*
X-828507D01*
G01X-856775D02*
X-856066D01*
G01X-858743D02*
X-858035D01*
G01X-862680D02*
X-861972D01*
G01X-860712D02*
X-860003D01*
G01X-862969Y984973D02*
X-863651D01*
G01X-861001D02*
X-861683D01*
G01X-859032D02*
X-859714D01*
G01X-857064D02*
X-857746D01*
G01X-855095D02*
X-855777D01*
G01X-829505D02*
X-830186D01*
G01X-827536D02*
X-828218D01*
G01X-825568D02*
X-826249D01*
G01X-823599D02*
X-824281D01*
G01X-821631D02*
X-822312D01*
G01X-819662D02*
X-820344D01*
G01X-817694D02*
X-818375D01*
G01X-815725D02*
X-816407D01*
G01X-813757D02*
X-814438D01*
G01X-811788D02*
X-812470D01*
G01X-809820D02*
X-810501D01*
G01X-807851D02*
X-808533D01*
G01X-805883D02*
X-806564D01*
G01X-803914D02*
X-804596D01*
G01X-801946D02*
X-802627D01*
G01X-799977D02*
X-800659D01*
G01X-798009D02*
X-798690D01*
G01X-796040D02*
X-796722D01*
G01X-794072D02*
X-794753D01*
G01X-861972Y984866D02*
X-862680D01*
G01X-860003D02*
X-860712D01*
G01X-858035D02*
X-858743D01*
G01X-856066D02*
X-856775D01*
G01X-828507D02*
X-829216D01*
G01X-826538D02*
X-827247D01*
G01X-824570D02*
X-825279D01*
G01X-822601D02*
X-823310D01*
G01X-820633D02*
X-821342D01*
G01X-818664D02*
X-819373D01*
G01X-816696D02*
X-817405D01*
G01X-814727D02*
X-815436D01*
G01X-812759D02*
X-813468D01*
G01X-810790D02*
X-811499D01*
G01X-808822D02*
X-809531D01*
G01X-806853D02*
X-807562D01*
G01X-804885D02*
X-805594D01*
G01X-802916D02*
X-803625D01*
G01X-800948D02*
X-801657D01*
G01X-798979D02*
X-799688D01*
G01X-797011D02*
X-797720D01*
G01X-795042D02*
X-795751D01*
G01X-793074D02*
X-793783D01*
G01X-863010Y983923D02*
X-863611D01*
G01X-861041D02*
X-861642D01*
G01X-859073D02*
X-859673D01*
G01X-857104D02*
X-857705D01*
G01X-855136D02*
X-855736D01*
G01X-829545D02*
X-830146D01*
G01X-827577D02*
X-828177D01*
G01X-825608D02*
X-826209D01*
G01X-823640D02*
X-824240D01*
G01X-821671D02*
X-822272D01*
G01X-819703D02*
X-820303D01*
G01X-817734D02*
X-818335D01*
G01X-815766D02*
X-816366D01*
G01X-813797D02*
X-814398D01*
G01X-811829D02*
X-812429D01*
G01X-809860D02*
X-810461D01*
G01X-807892D02*
X-808492D01*
G01X-805923D02*
X-806524D01*
G01X-803955D02*
X-804555D01*
G01X-801986D02*
X-802587D01*
G01X-800018D02*
X-800618D01*
G01X-798049D02*
X-798650D01*
G01X-796081D02*
X-796681D01*
G01X-794112D02*
X-794713D01*
G01X-861972Y983724D02*
X-862680D01*
G01X-860003D02*
X-860712D01*
G01X-858035D02*
X-858743D01*
G01X-856066D02*
X-856775D01*
G01X-828507D02*
X-829216D01*
G01X-826538D02*
X-827247D01*
G01X-824570D02*
X-825279D01*
G01X-822601D02*
X-823310D01*
G01X-820633D02*
X-821342D01*
G01X-818664D02*
X-819373D01*
G01X-816696D02*
X-817405D01*
G01X-814727D02*
X-815436D01*
G01X-812759D02*
X-813468D01*
G01X-810790D02*
X-811499D01*
G01X-808822D02*
X-809531D01*
G01X-806853D02*
X-807562D01*
G01X-804885D02*
X-805594D01*
G01X-802916D02*
X-803625D01*
G01X-800948D02*
X-801657D01*
G01X-798979D02*
X-799688D01*
G01X-797011D02*
X-797720D01*
G01X-795042D02*
X-795751D01*
G01X-793074D02*
X-793783D01*
G01X-797365Y983606D02*
X-789491D01*
G01X-848546D02*
X-849727D01*
G01X-834570D02*
X-836735D01*
G01Y983409D02*
X-750121D01*
G01X-861972Y982464D02*
X-862680D01*
G01X-860003D02*
X-860712D01*
G01X-858035D02*
X-858743D01*
G01X-856066D02*
X-856775D01*
G01X-828507D02*
X-829216D01*
G01X-826538D02*
X-827247D01*
G01X-824570D02*
X-825279D01*
G01X-822601D02*
X-823310D01*
G01X-820633D02*
X-821342D01*
G01X-818664D02*
X-819373D01*
G01X-816696D02*
X-817405D01*
G01X-814727D02*
X-815436D01*
G01X-812759D02*
X-813468D01*
G01X-810790D02*
X-811499D01*
G01X-808822D02*
X-809531D01*
G01X-806853D02*
X-807562D01*
G01X-804885D02*
X-805594D01*
G01X-802916D02*
X-803625D01*
G01X-800948D02*
X-801657D01*
G01X-798979D02*
X-799688D01*
G01X-797011D02*
X-797720D01*
G01X-795042D02*
X-795751D01*
G01X-793074D02*
X-793783D01*
G01X-848546Y979472D02*
X-851007D01*
G01X-834275D02*
X-836735D01*
G01X-813310Y994110D02*
X-813441Y993976D01*
G01X-813573Y994311D02*
X-813704Y994177D01*
G01X-814491Y995651D02*
X-814622Y995517D01*
G01X-814754Y995852D02*
X-814885Y995718D01*
G01X-818100Y994244D02*
X-818297Y994043D01*
G01X-817050Y995517D02*
X-817181Y995383D01*
G01X-817050Y995785D02*
X-817181Y995651D01*
G01X-823087Y994378D02*
X-823349Y994043D01*
G01X-794019Y977700D02*
X-792838D01*
G01X-795987D02*
X-794806D01*
G01X-797956D02*
X-796775D01*
G01X-803861D02*
X-802680D01*
G01X-809767D02*
X-808586D01*
G01X-811735D02*
X-810554D01*
G01X-813704D02*
X-812523D01*
G01X-819609D02*
X-818428D01*
G01X-821578D02*
X-820397D01*
G01X-825515D02*
X-824334D01*
G01X-827483D02*
X-826302D01*
G01X-860948D02*
X-859767D01*
G01X-862916D02*
X-861735D01*
G01X-857798D02*
X-858979D01*
G01X-855830D02*
X-857011D01*
G01X-828271D02*
X-829452D01*
G01X-822365D02*
X-823546D01*
G01X-816460D02*
X-817641D01*
G01X-814491D02*
X-815672D01*
G01X-806617D02*
X-807798D01*
G01X-804649D02*
X-805830D01*
G01X-800712D02*
X-801893D01*
G01X-798743D02*
X-799924D01*
G01X-859964Y975100D02*
X-860751D01*
G01X-861932D02*
X-862720D01*
G01X-857995D02*
X-858783D01*
G01X-856027D02*
X-856814D01*
G01X-828468D02*
X-829255D01*
G01X-824531D02*
X-825318D01*
G01X-826499D02*
X-827286D01*
G01X-820594D02*
X-821381D01*
G01X-822562D02*
X-823349D01*
G01X-818625D02*
X-819412D01*
G01X-814688D02*
X-815475D01*
G01X-816657D02*
X-817444D01*
G01X-810751D02*
X-811538D01*
G01X-812720D02*
X-813507D01*
G01X-808783D02*
X-809570D01*
G01X-804846D02*
X-805633D01*
G01X-806814D02*
X-807601D01*
G01X-800909D02*
X-801696D01*
G01X-802877D02*
X-803664D01*
G01X-796972D02*
X-797759D01*
G01X-798940D02*
X-799727D01*
G01X-795003D02*
X-795790D01*
G01X-793035D02*
X-793822D01*
G01Y974551D02*
X-793035D01*
G01X-795790D02*
X-795003D01*
G01X-797759D02*
X-796972D01*
G01X-799727D02*
X-798940D01*
G01X-801696D02*
X-800909D01*
G01X-803664D02*
X-802877D01*
G01X-805633D02*
X-804846D01*
G01X-807601D02*
X-806814D01*
G01X-809570D02*
X-808783D01*
G01X-811538D02*
X-810751D01*
G01X-813507D02*
X-812720D01*
G01X-815475D02*
X-814688D01*
G01X-817444D02*
X-816657D01*
G01X-819412D02*
X-818625D01*
G01X-821381D02*
X-820594D01*
G01X-823349D02*
X-822562D01*
G01X-825318D02*
X-824531D01*
G01X-827286D02*
X-826499D01*
G01X-829255D02*
X-828468D01*
G01X-856814D02*
X-856027D01*
G01X-858783D02*
X-857995D01*
G01X-860751D02*
X-859964D01*
G01X-862720D02*
X-861932D01*
G01X-750121Y973960D02*
X-836735D01*
G01X-862129Y972582D02*
X-862523D01*
G01X-858192D02*
X-858586D01*
G01X-860160D02*
X-860554D01*
G01X-856223D02*
X-856617D01*
G01X-828664D02*
X-829058D01*
G01X-824727D02*
X-825121D01*
G01X-826696D02*
X-827090D01*
G01X-820790D02*
X-821184D01*
G01X-822759D02*
X-823153D01*
G01X-818822D02*
X-819216D01*
G01X-814885D02*
X-815279D01*
G01X-816853D02*
X-817247D01*
G01X-810948D02*
X-811342D01*
G01X-812916D02*
X-813310D01*
G01X-808979D02*
X-809373D01*
G01X-805042D02*
X-805436D01*
G01X-807011D02*
X-807405D01*
G01X-801105D02*
X-801499D01*
G01X-803074D02*
X-803468D01*
G01X-799137D02*
X-799531D01*
G01X-795200D02*
X-795594D01*
G01X-797168D02*
X-797562D01*
G01X-793231D02*
X-793625D01*
G01X-799924Y971598D02*
X-798743D01*
G01X-801893D02*
X-800712D01*
G01X-805830D02*
X-804649D01*
G01X-807798D02*
X-806617D01*
G01X-815672D02*
X-814491D01*
G01X-817641D02*
X-816460D01*
G01X-823546D02*
X-822365D01*
G01X-829452D02*
X-828271D01*
G01X-857011D02*
X-855830D01*
G01X-858979D02*
X-857798D01*
G01X-859767D02*
X-860948D01*
G01X-861735D02*
X-862916D01*
G01X-824334D02*
X-825515D01*
G01X-826302D02*
X-827483D01*
G01X-820397D02*
X-821578D01*
G01X-818428D02*
X-819609D01*
G01X-810554D02*
X-811735D01*
G01X-812523D02*
X-813704D01*
G01X-808586D02*
X-809767D01*
G01X-802680D02*
X-803861D01*
G01X-796775D02*
X-797956D01*
G01X-794806D02*
X-795987D01*
G01X-792838D02*
X-794019D01*
G01X-818625Y994177D02*
X-819084Y994110D01*
G01X-818559Y993909D02*
X-819019Y993842D01*
G01Y995986D02*
X-819412Y995919D01*
G01X-819478Y995584D02*
X-819675Y995383D01*
G01X-819806Y995718D02*
X-819937Y995584D01*
G01X-822037Y995517D02*
X-822168Y995383D01*
G01X-822037Y995785D02*
X-822168Y995651D01*
G01X-824596Y995852D02*
X-824727Y995718D01*
G01X-826565Y995651D02*
X-826630Y995584D01*
G01X-826565Y995919D02*
X-826762Y995718D01*
G01X-827615Y995651D02*
X-827746Y995517D01*
G01X-827615Y995919D02*
X-827746Y995785D01*
G01X-824202Y995986D02*
X-824465Y995919D01*
G01X-824202Y995651D02*
X-824465Y995584D01*
G01X-821578Y995986D02*
X-821840Y995919D01*
G01X-821578Y995718D02*
X-821840Y995651D01*
G01X-819084Y995718D02*
X-819347Y995651D01*
G01X-823678Y994244D02*
X-823940Y994177D01*
G01X-816591Y995986D02*
X-816853Y995919D01*
G01X-816591Y995718D02*
X-816853Y995651D01*
G01X-823546Y993909D02*
X-823809Y993842D01*
G01X-814360Y995986D02*
X-814622Y995919D01*
G01X-814229Y995718D02*
X-814491Y995651D01*
G01X-813704Y994177D02*
X-813966Y994110D01*
G01X-813573Y993909D02*
X-813835Y993842D01*
G01X-818428Y994311D02*
X-818625Y994177D01*
G01X-816853Y995651D02*
X-817050Y995517D01*
G01X-816853Y995919D02*
X-817050Y995785D01*
G01X-819609Y995852D02*
X-819806Y995718D01*
G01X-823349Y994043D02*
X-823546Y993909D01*
G01X-823481Y994378D02*
X-823678Y994244D01*
G01X-821840Y995651D02*
X-822037Y995517D01*
G01X-821840Y995919D02*
X-822037Y995785D01*
G01X-824465Y995584D02*
X-824662Y995450D01*
G01X-813441Y993976D02*
X-813573Y993909D01*
G01X-818297Y994043D02*
X-818559Y993909D01*
G01X-814622Y995919D02*
X-814754Y995852D01*
G01X-819347Y995651D02*
X-819478Y995584D01*
G01X-824465Y995919D02*
X-824596Y995852D01*
G01X-826433Y995718D02*
X-826565Y995651D01*
G01X-819412Y995919D02*
X-819609Y995852D01*
G01X-826368Y995986D02*
X-826565Y995919D01*
G01X-827418Y995718D02*
X-827615Y995651D01*
G01X-827418Y995986D02*
X-827615Y995919D01*
G01X-794609Y1004552D02*
G03X-794806Y1004355I0J-197D01*
G01X-794019D02*
G03X-794216Y1004552I-197J0D01*
G01X-796578D02*
G03X-796775Y1004355I0J-197D01*
G01X-795987D02*
G03X-796184Y1004552I-197J0D01*
G01X-798546D02*
G03X-798743Y1004355I0J-197D01*
G01X-797956D02*
G03X-798153Y1004552I-197J0D01*
G01X-800515D02*
G03X-800712Y1004355I0J-197D01*
G01X-799924D02*
G03X-800121Y1004552I-197J0D01*
G01X-802483D02*
G03X-802680Y1004355I0J-197D01*
G01X-801893D02*
G03X-802090Y1004552I-197J0D01*
G01X-804452D02*
G03X-804649Y1004355I0J-197D01*
G01X-803861D02*
G03X-804058Y1004552I-197J0D01*
G01X-806420D02*
G03X-806617Y1004355I0J-197D01*
G01X-805830D02*
G03X-806027Y1004552I-197J0D01*
G01X-808389D02*
G03X-808586Y1004355I0J-197D01*
G01X-807798D02*
G03X-807995Y1004552I-197J0D01*
G01X-810357D02*
G03X-810554Y1004355I0J-197D01*
G01X-809767D02*
G03X-809964Y1004552I-197J0D01*
G01X-812326D02*
G03X-812523Y1004355I0J-197D01*
G01X-811735D02*
G03X-811932Y1004552I-197J0D01*
G01X-814294D02*
G03X-814491Y1004355I0J-197D01*
G01X-813704D02*
G03X-813901Y1004552I-197J0D01*
G01X-816263D02*
G03X-816460Y1004355I0J-197D01*
G01X-815672D02*
G03X-815869Y1004552I-197J0D01*
G01X-818231D02*
G03X-818428Y1004355I0J-197D01*
G01X-817641D02*
G03X-817838Y1004552I-197J0D01*
G01X-811066Y997267D02*
G03X-811853Y998054I-787J0D01*
G01X-820200Y1004552D02*
G03X-820397Y1004355I0J-197D01*
G01X-819609D02*
G03X-819806Y1004552I-197J0D01*
G01X-822168D02*
G03X-822365Y1004355I0J-197D01*
G01X-821578D02*
G03X-821775Y1004552I-197J0D01*
G01X-824137D02*
G03X-824334Y1004355I0J-197D01*
G01X-823546D02*
G03X-823743Y1004552I-197J0D01*
G01X-826105D02*
G03X-826302Y1004355I0J-197D01*
G01X-825515D02*
G03X-825712Y1004552I-197J0D01*
G01X-828074D02*
G03X-828271Y1004355I0J-197D01*
G01X-827483D02*
G03X-827680Y1004552I-197J0D01*
G01X-830042D02*
G03X-830239Y1004355I0J-197D01*
G01X-829452D02*
G03X-829649Y1004552I-197J0D01*
G01X-833389Y1004078D02*
G03X-834176I-394J0D01*
G01X-834570Y1006047D02*
G03X-835357Y1005259I0J-787D01*
G01X-834176Y998566D02*
G03X-833389I394J0D01*
G01X-831499Y998054D02*
G03X-832286Y997267I0J-787D01*
G01X-835357Y997385D02*
G03X-834570Y996598I787J0D01*
G01X-851105Y1004078D02*
G03X-851893I-394J0D01*
G01X-848546Y1005259D02*
G03X-849334Y1006047I-788J0D01*
G01X-849924Y1005259D02*
G03X-850712Y1006047I-788J0D01*
G01X-835948D02*
G03X-836735Y1005259I0J-787D01*
G01X-851893Y998566D02*
G03X-851105I394J0D01*
G01X-850712Y996598D02*
G03X-849924Y997385I0J788D01*
G01X-855633Y1004552D02*
G03X-855830Y1004355I0J-197D01*
G01X-855042D02*
G03X-855239Y1004552I-197J0D01*
G01X-857601D02*
G03X-857798Y1004355I0J-197D01*
G01X-857011D02*
G03X-857208Y1004552I-197J0D01*
G01X-859570D02*
G03X-859767Y1004355I0J-197D01*
G01X-858979D02*
G03X-859176Y1004552I-197J0D01*
G01X-861538D02*
G03X-861735Y1004355I0J-197D01*
G01X-860948D02*
G03X-861145Y1004552I-197J0D01*
G01X-863507D02*
G03X-863704Y1004355I0J-197D01*
G01X-862916D02*
G03X-863113Y1004552I-197J0D01*
G01X-810856Y1058635D02*
X-810200Y1057630D01*
G01X-829661Y1009192D02*
X-829636Y1009117D01*
G01X-829784D02*
X-829809Y1009192D01*
G01X-829735Y1009293D02*
X-829661Y1009192D01*
G01X-829809D02*
X-829858Y1009242D01*
G01X-810856Y1051934D02*
X-817090Y1055285D01*
G01X-814793D02*
X-810200Y1052939D01*
G01X-793822Y1007425D02*
Y1001322D01*
G01X-794019Y1004355D02*
Y1002034D01*
G01X-794452Y1053944D02*
Y1051934D01*
G01X-794806Y1004355D02*
Y1002034D01*
G01X-795003Y1001322D02*
Y1007425D01*
G01X-795790D02*
Y1001322D01*
G01X-795987Y1004355D02*
Y1002034D01*
G01X-796775Y1004355D02*
Y1002034D01*
G01X-796972Y1001322D02*
Y1007425D01*
G01X-797733Y1051934D02*
Y1047243D01*
G01Y1062991D02*
Y1053944D01*
G01X-797759Y1001322D02*
Y1007425D01*
G01X-797956Y1004355D02*
Y1002034D01*
G01X-798743Y1004355D02*
Y1002034D01*
G01X-798940Y1007425D02*
Y1001322D01*
G01X-799701Y1047243D02*
Y1051934D01*
G01Y1060311D02*
Y1053944D01*
G01X-799727Y1001322D02*
Y1007425D01*
G01X-799924Y1004355D02*
Y1002034D01*
G01X-800712Y1004355D02*
Y1002034D01*
G01X-800909Y1007425D02*
Y1001322D01*
G01X-801696D02*
Y1007425D01*
G01X-801893Y1004355D02*
Y1002034D01*
G01X-802680Y1004355D02*
Y1002034D01*
G01X-802877Y1007425D02*
Y1001322D01*
G01X-803664Y1007425D02*
Y1001322D01*
G01X-803861Y1004355D02*
Y1002034D01*
G01X-804649Y1004355D02*
Y1002034D01*
G01X-804846Y1001322D02*
Y1007425D01*
G01X-805633D02*
Y1001322D01*
G01X-805830Y1004355D02*
Y1002034D01*
G01X-806617Y1004355D02*
Y1002034D01*
G01X-806814Y1001322D02*
Y1007425D01*
G01X-807575Y1051934D02*
Y1053944D01*
G01X-807601Y1007425D02*
Y1001322D01*
G01X-807798Y1004355D02*
Y1002034D01*
G01X-808586Y1004355D02*
Y1002034D01*
G01X-808783Y1001322D02*
Y1007425D01*
G01X-829833Y1009368D02*
X-829735Y1009293D01*
G01X-809570Y1001322D02*
Y1007425D01*
G01X-809767Y1004355D02*
Y1002034D01*
G01X-810554Y1004355D02*
Y1002034D01*
G01X-810751Y1007425D02*
Y1001322D01*
G01X-811538D02*
Y1007425D01*
G01X-811735Y1004355D02*
Y1002034D01*
G01X-812523Y1004355D02*
Y1002034D01*
G01X-812720Y1007425D02*
Y1001322D01*
G01X-813507Y1007425D02*
Y1001322D01*
G01X-813704Y1004355D02*
Y1002034D01*
G01X-814491Y1004355D02*
Y1002034D01*
G01X-814688Y1001322D02*
Y1007425D01*
G01X-815475D02*
Y1001322D01*
G01X-815672Y1004355D02*
Y1002034D01*
G01X-816460Y1004355D02*
Y1002034D01*
G01X-816657Y1001322D02*
Y1007425D01*
G01X-817444D02*
Y1001322D01*
G01X-817641Y1004355D02*
Y1002034D01*
G01X-818428Y1004355D02*
Y1002034D01*
G01X-818625Y1001322D02*
Y1007425D01*
G01X-819412Y1001322D02*
Y1007425D01*
G01X-819609Y1004355D02*
Y1002034D01*
G01X-819714Y1062991D02*
Y1047243D01*
G01X-820397Y1004355D02*
Y1002034D01*
G01X-820594Y1007425D02*
Y1001322D01*
G01X-821381D02*
Y1007425D01*
G01X-821578Y1004355D02*
Y1002034D01*
G01X-821683Y1056625D02*
Y1062991D01*
G01Y1047243D02*
Y1054615D01*
G01X-822365Y1004355D02*
Y1002034D01*
G01X-822562Y1007425D02*
Y1001322D01*
G01X-823349D02*
Y1007425D01*
G01X-823546Y1004355D02*
Y1002034D01*
G01X-824334Y1004355D02*
Y1002034D01*
G01X-824531Y1007425D02*
Y1001322D01*
G01X-825318D02*
Y1007425D01*
G01X-825515Y1004355D02*
Y1002034D01*
G01X-826302Y1004355D02*
Y1002034D01*
G01X-826499Y1007425D02*
Y1001322D01*
G01X-827286Y1007425D02*
Y1001322D01*
G01X-827483Y1004355D02*
Y1002034D01*
G01X-828271Y1004355D02*
Y1002034D01*
G01X-828468Y1001322D02*
Y1007425D01*
G01X-829144Y1009393D02*
Y1008212D01*
G01X-829255Y1007425D02*
Y1001322D01*
G01X-829292Y1008212D02*
Y1009192D01*
G01X-829440Y1009016D02*
Y1009217D01*
G01X-829452Y1004355D02*
Y1002034D01*
G01X-829636Y1009117D02*
Y1009016D01*
G01X-829784Y1009041D02*
Y1009117D01*
G01X-830239Y1004355D02*
Y1002034D01*
G01X-830399Y1009267D02*
Y1008890D01*
G01Y1008740D02*
Y1008212D01*
G01X-830436Y1001322D02*
Y1007425D01*
G01X-830547Y1008212D02*
Y1009393D01*
G01X-830869Y1054615D02*
Y1047243D01*
G01Y1062991D02*
Y1056625D01*
G01X-831972Y1003094D02*
Y1006047D01*
G01X-832405D02*
Y1003094D01*
G01X-832693Y996598D02*
Y1003094D01*
G01X-832838Y1047243D02*
Y1062991D01*
G01X-832995Y1006047D02*
Y996598D01*
G01X-833389Y1004078D02*
Y998566D01*
G01X-833586Y999944D02*
Y1006047D01*
G01X-834176Y998566D02*
Y1004078D01*
G01X-835357Y997385D02*
Y1005259D01*
G01X-835751Y999944D02*
Y1006047D01*
G01X-840003Y1103291D02*
Y1003330D01*
G01X-829858Y1009242D02*
X-829932Y1009267D01*
G01X-849531Y999944D02*
Y1006047D01*
G01X-849924Y1005259D02*
Y997385D01*
G01X-851105Y1004078D02*
Y998566D01*
G01X-851696Y999944D02*
Y1006047D01*
G01X-851893Y998566D02*
Y1004078D01*
G01X-852286Y996598D02*
Y1006047D01*
G01X-852589Y1003094D02*
Y996598D01*
G01X-852877Y1006047D02*
Y1003094D01*
G01X-853309Y1006047D02*
Y1003094D01*
G01X-854846Y1001322D02*
Y1007425D01*
G01X-855042Y1004355D02*
Y1002034D01*
G01X-855830Y1004355D02*
Y1002034D01*
G01X-856027Y1007425D02*
Y1001322D01*
G01X-856814D02*
Y1007425D01*
G01X-857011Y1004355D02*
Y1002034D01*
G01X-857798Y1004355D02*
Y1002034D01*
G01X-857995Y1007425D02*
Y1001322D01*
G01X-858783D02*
Y1007425D01*
G01X-858979Y1004355D02*
Y1002034D01*
G01X-859767Y1004355D02*
Y1002034D01*
G01X-859964Y1007425D02*
Y1001322D01*
G01X-860751Y1007425D02*
Y1001322D01*
G01X-860948Y1004355D02*
Y1002034D01*
G01X-861735Y1004355D02*
Y1002034D01*
G01X-861932Y1001322D02*
Y1007425D01*
G01X-862720D02*
Y1001322D01*
G01X-862916Y1004355D02*
Y1002034D01*
G01X-863704Y1004355D02*
Y1002034D01*
G01X-863901Y1001322D02*
Y1007425D01*
G01X-829956Y1009393D02*
X-829833Y1009368D01*
G01X-799701Y1062991D02*
X-797733D01*
G01X-821683D02*
X-819714D01*
G01X-832838D02*
X-830869D01*
G01X-829636Y1009016D02*
X-829661Y1008941D01*
G01X-829809Y1008966D02*
X-829784Y1009041D01*
G01X-830869Y1056625D02*
X-821683D01*
G01Y1054615D02*
X-830869D01*
G01X-797733Y1053944D02*
X-794452D01*
G01X-799701D02*
X-805279D01*
G01X-799701Y1051934D02*
X-807575D01*
G01X-794452D02*
X-797733D01*
G01X-830869Y1047243D02*
X-832838D01*
G01X-819714D02*
X-821683D01*
G01X-797733D02*
X-799701D01*
G01X-829292Y1009393D02*
X-829144D01*
G01X-830547D02*
X-829956D01*
G01X-829932Y1009267D02*
X-830399D01*
G01Y1008890D02*
X-829932D01*
G01X-829956Y1008740D02*
X-830399D01*
G01X-829144Y1008212D02*
X-829292D01*
G01X-830399D02*
X-830547D01*
G01X-796972Y1007425D02*
X-795790D01*
G01X-795003D02*
X-793822D01*
G01X-804846D02*
X-803664D01*
G01X-806814D02*
X-805633D01*
G01X-808783D02*
X-807601D01*
G01X-816657D02*
X-815475D01*
G01X-814688D02*
X-813507D01*
G01X-818625D02*
X-817444D01*
G01X-828468D02*
X-827286D01*
G01X-830436D02*
X-829255D01*
G01X-861932D02*
X-860751D01*
G01X-863901D02*
X-862720D01*
G01X-856814D02*
X-857995D01*
G01X-858783D02*
X-859964D01*
G01X-854846D02*
X-856027D01*
G01X-823349D02*
X-824531D01*
G01X-825318D02*
X-826499D01*
G01X-821381D02*
X-822562D01*
G01X-819412D02*
X-820594D01*
G01X-811538D02*
X-812720D01*
G01X-809570D02*
X-810751D01*
G01X-801696D02*
X-802877D01*
G01X-799727D02*
X-800909D01*
G01X-797759D02*
X-798940D01*
G01X-836538Y1006736D02*
X-831814D01*
G01X-853468D02*
X-848743D01*
G01X-835948Y1006047D02*
X-831814D01*
G01X-853468D02*
X-849334D01*
G01X-861145Y1004552D02*
X-861538D01*
G01X-863113D02*
X-863507D01*
G01X-857208D02*
X-857601D01*
G01X-859176D02*
X-859570D01*
G01X-855239D02*
X-855633D01*
G01X-827680D02*
X-828074D01*
G01X-829649D02*
X-830042D01*
G01X-825712D02*
X-826105D01*
G01X-821775D02*
X-822168D01*
G01X-823743D02*
X-824137D01*
G01X-817838D02*
X-818231D01*
G01X-819806D02*
X-820200D01*
G01X-813901D02*
X-814294D01*
G01X-815869D02*
X-816263D01*
G01X-811932D02*
X-812326D01*
G01X-807995D02*
X-808389D01*
G01X-809964D02*
X-810357D01*
G01X-804058D02*
X-804452D01*
G01X-806027D02*
X-806420D01*
G01X-802090D02*
X-802483D01*
G01X-798153D02*
X-798546D01*
G01X-800121D02*
X-800515D01*
G01X-794216D02*
X-794609D01*
G01X-796184D02*
X-796578D01*
G01X-840003Y1003330D02*
X-714019D01*
G01X-833586Y1003094D02*
X-753271D01*
G01X-860948Y1002583D02*
X-861735D01*
G01X-862916D02*
X-863704D01*
G01X-857011D02*
X-857798D01*
G01X-858979D02*
X-859767D01*
G01X-855042D02*
X-855830D01*
G01X-827483D02*
X-828271D01*
G01X-829452D02*
X-830239D01*
G01X-823546D02*
X-824334D01*
G01X-825515D02*
X-826302D01*
G01X-821578D02*
X-822365D01*
G01X-817641D02*
X-818428D01*
G01X-819609D02*
X-820397D01*
G01X-813704D02*
X-814491D01*
G01X-815672D02*
X-816460D01*
G01X-811735D02*
X-812523D01*
G01X-807798D02*
X-808586D01*
G01X-809767D02*
X-810554D01*
G01X-803861D02*
X-804649D01*
G01X-805830D02*
X-806617D01*
G01X-801893D02*
X-802680D01*
G01X-797956D02*
X-798743D01*
G01X-799924D02*
X-800712D01*
G01X-794019D02*
X-794806D01*
G01X-795987D02*
X-796775D01*
G01X-794806Y1002034D02*
X-794019D01*
G01X-796775D02*
X-795987D01*
G01X-798743D02*
X-797956D01*
G01X-800712D02*
X-799924D01*
G01X-802680D02*
X-801893D01*
G01X-804649D02*
X-803861D01*
G01X-806617D02*
X-805830D01*
G01X-808586D02*
X-807798D01*
G01X-810554D02*
X-809767D01*
G01X-812523D02*
X-811735D01*
G01X-814491D02*
X-813704D01*
G01X-816460D02*
X-815672D01*
G01X-818428D02*
X-817641D01*
G01X-820397D02*
X-819609D01*
G01X-822365D02*
X-821578D01*
G01X-824334D02*
X-823546D01*
G01X-826302D02*
X-825515D01*
G01X-828271D02*
X-827483D01*
G01X-830239D02*
X-829452D01*
G01X-855830D02*
X-855042D01*
G01X-857798D02*
X-857011D01*
G01X-859767D02*
X-858979D01*
G01X-861735D02*
X-860948D01*
G01X-863704D02*
X-862916D01*
G01X-800909Y1001322D02*
X-799727D01*
G01X-798940D02*
X-797759D01*
G01X-802877D02*
X-801696D01*
G01X-810751D02*
X-809570D01*
G01X-812720D02*
X-811538D01*
G01X-820594D02*
X-819412D01*
G01X-822562D02*
X-821381D01*
G01X-824531D02*
X-823349D01*
G01X-826499D02*
X-825318D01*
G01X-856027D02*
X-854846D01*
G01X-857995D02*
X-856814D01*
G01X-859964D02*
X-858783D01*
G01X-860751D02*
X-861932D01*
G01X-862720D02*
X-863901D01*
G01X-827286D02*
X-828468D01*
G01X-829255D02*
X-830436D01*
G01X-817444D02*
X-818625D01*
G01X-815475D02*
X-816657D01*
G01X-813507D02*
X-814688D01*
G01X-807601D02*
X-808783D01*
G01X-803664D02*
X-804846D01*
G01X-805633D02*
X-806814D01*
G01X-795790D02*
X-796972D01*
G01X-793822D02*
X-795003D01*
G01X-753271Y1000732D02*
X-833586D01*
G01X-856420Y999944D02*
X-858389D01*
G01X-851105D02*
X-851696D01*
G01X-848546D02*
X-849924D01*
G01X-833586D02*
X-834176D01*
G01X-835357D02*
X-836735D01*
G01X-826893D02*
X-828861D01*
G01X-811853Y998054D02*
X-831499D01*
G01X-829649Y996991D02*
X-830174D01*
G01X-822168D02*
X-822496D01*
G01X-812195D02*
X-812523D01*
G01X-834570Y996598D02*
X-832693D01*
G01X-850712D02*
X-852589D01*
G01X-829292Y1009192D02*
X-829440Y1009016D01*
G01Y1009217D02*
X-829292Y1009393D01*
G01X-829661Y1008941D02*
X-829735Y1008840D01*
G01X-810200Y1052939D02*
X-810856Y1051934D01*
G01X-829833Y1008765D02*
X-829956Y1008740D01*
G01X-829858Y1008916D02*
X-829809Y1008966D01*
G01X-805279Y1053944D02*
X-799701Y1060311D01*
G01X-807575Y1053944D02*
X-799701Y1062991D01*
G01X-829735Y1008840D02*
X-829833Y1008765D01*
G01X-817090Y1055285D02*
X-810856Y1058635D01*
G01X-829932Y1008890D02*
X-829858Y1008916D01*
G01X-810200Y1057630D02*
X-814793Y1055285D01*
G01X-798983Y1463291D02*
Y1444354D01*
G01X-705347Y-497839D02*
G03I-18701J0D01*
G01X-716174D02*
G03I-7874J0D01*
G01X-789009Y-442524D02*
Y-448824D01*
G01Y-324414D02*
Y-330713D01*
G01X-722384Y-233747D02*
Y-225789D01*
G01Y-245474D02*
Y-236260D01*
G01X-724845Y-225789D02*
Y-245474D01*
G01X-740429Y-230396D02*
X-740839Y-228721D01*
G01X-735918Y-231234D02*
X-736738Y-232490D01*
G01X-752322Y-230396D02*
X-751502Y-229140D01*
G01X-764625Y-235422D02*
X-764215Y-234585D01*
G01X-771187Y-235422D02*
X-770777Y-234585D01*
G01X-772417Y-233328D02*
X-773237Y-235422D01*
G01X-754372Y-228721D02*
X-754782Y-230396D01*
G01X-740019Y-245474D02*
Y-243380D01*
G01X-752322Y-231234D02*
Y-230396D01*
G01X-754782Y-243380D02*
Y-245474D01*
G01Y-230396D02*
Y-231234D01*
G01X-758063Y-245474D02*
Y-232072D01*
G01X-760114Y-235003D02*
Y-245474D01*
G01Y-232072D02*
Y-233328D01*
G01X-764625Y-245474D02*
Y-235422D01*
G01X-766676D02*
Y-245474D01*
G01X-771187D02*
Y-235422D01*
G01X-754782Y-231234D02*
X-754372Y-232909D01*
G01X-752732Y-227046D02*
X-754372Y-228721D01*
G01X-764215Y-234585D02*
X-763805Y-234166D01*
G01X-765035Y-232490D02*
X-766265Y-233747D01*
G01X-783080Y-235422D02*
X-782670Y-234585D01*
G01X-789641Y-235422D02*
X-789231Y-234585D01*
G01X-790872Y-233328D02*
X-791692Y-235422D01*
G01X-773237D02*
Y-245474D01*
G01X-776518D02*
Y-232072D01*
G01X-778569Y-235003D02*
Y-245474D01*
G01Y-232072D02*
Y-233328D01*
G01X-783080Y-245474D02*
Y-235422D01*
G01X-785130D02*
Y-245474D01*
G01X-789641D02*
Y-235422D01*
G01X-791692D02*
Y-245474D01*
G01X-751502Y-232909D02*
X-752322Y-231234D01*
G01X-767086Y-234585D02*
X-766676Y-235422D01*
G01X-736738Y-238354D02*
X-735918Y-239610D01*
G01X-743300Y-229140D02*
X-742479Y-230396D01*
G01X-770777Y-234585D02*
X-770366Y-234166D01*
G01X-771597Y-232490D02*
X-772417Y-233328D01*
G01X-782670Y-234585D02*
X-782260Y-234166D01*
G01X-783490Y-232490D02*
X-784720Y-233747D01*
G01X-789231Y-234585D02*
X-788821Y-234166D01*
G01X-790052Y-232490D02*
X-790872Y-233328D01*
G01X-785540Y-234585D02*
X-785130Y-235422D01*
G01X-754372Y-232909D02*
X-753552Y-234166D01*
G01X-730996Y-235422D02*
X-736738Y-238354D01*
G01X-763805Y-234166D02*
X-762985Y-233747D01*
G01X-751092Y-226208D02*
X-752732Y-227046D01*
G01X-735918Y-239610D02*
X-728126Y-235422D01*
G01X-751502Y-229140D02*
X-750271Y-228302D01*
G01X-740839Y-228721D02*
X-742479Y-227046D01*
G01X-760114Y-233328D02*
X-760934Y-232490D01*
G01Y-234166D02*
X-760114Y-235003D01*
G01X-770366Y-234166D02*
X-769546Y-233747D01*
G01X-782260Y-234166D02*
X-781439Y-233747D01*
G01X-788821Y-234166D02*
X-788001Y-233747D01*
G01X-766265D02*
X-767496Y-232490D01*
G01Y-234166D02*
X-767086Y-234585D01*
G01X-778569Y-233328D02*
X-779389Y-232490D01*
G01Y-234166D02*
X-778569Y-235003D01*
G01X-784720Y-233747D02*
X-785950Y-232490D01*
G01Y-234166D02*
X-785540Y-234585D01*
G01X-740019Y-243380D02*
X-751502Y-232909D01*
G01X-753552Y-234166D02*
X-743300Y-243380D01*
G01X-763805Y-232072D02*
X-765035Y-232490D01*
G01X-770366Y-232072D02*
X-771597Y-232490D01*
G01X-782260Y-232072D02*
X-783490Y-232490D01*
G01X-788821Y-232072D02*
X-790052Y-232490D01*
G01X-744530Y-228302D02*
X-743300Y-229140D01*
G01X-728126Y-235422D02*
X-735918Y-231234D01*
G01X-742479Y-227046D02*
X-744120Y-226208D01*
G01X-736738Y-232490D02*
X-730996Y-235422D01*
G01X-768316Y-233747D02*
X-767496Y-234166D01*
G01X-786771Y-233747D02*
X-785950Y-234166D01*
G01X-760934Y-232490D02*
X-762164Y-232072D01*
G01Y-233747D02*
X-760934Y-234166D01*
G01X-767496Y-232490D02*
X-768726Y-232072D01*
G01X-779389Y-232490D02*
X-780619Y-232072D01*
G01Y-233747D02*
X-779389Y-234166D01*
G01X-785950Y-232490D02*
X-787181Y-232072D01*
G01X-746580Y-227883D02*
X-744530Y-228302D01*
G01X-744120Y-226208D02*
X-746990Y-225789D01*
G01D02*
X-748631D01*
G01X-722384D02*
X-724845D01*
G01X-748221Y-227883D02*
X-746580D01*
G01X-742479Y-230396D02*
X-740429D01*
G01X-787181Y-232072D02*
X-788821D01*
G01X-780619D02*
X-782260D01*
G01X-776518D02*
X-778569D01*
G01X-768726D02*
X-770366D01*
G01X-762164D02*
X-763805D01*
G01X-758063D02*
X-760114D01*
G01X-762985Y-233747D02*
X-762164D01*
G01X-769546D02*
X-768316D01*
G01X-781439D02*
X-780619D01*
G01X-788001D02*
X-786771D01*
G01X-710901D02*
X-722384D01*
G01Y-236260D02*
X-710901D01*
G01X-743300Y-243380D02*
X-754782D01*
G01X-724845Y-245474D02*
X-722384D01*
G01X-754782D02*
X-740019D01*
G01X-760114D02*
X-758063D01*
G01X-766676D02*
X-764625D01*
G01X-773237D02*
X-771187D01*
G01X-778569D02*
X-776518D01*
G01X-785130D02*
X-783080D01*
G01X-791692D02*
X-789641D01*
G01X-748631Y-225789D02*
X-751092Y-226208D01*
G01X-750271Y-228302D02*
X-748221Y-227883D01*
G01X-717158Y-56894D02*
G03I-6890J0D01*
G01X-705347D02*
G03I-18701J0D01*
G01Y76964D02*
G03I-18701J0D01*
G01X-757513Y100586D02*
G03X-753576Y104523I0J3937D01*
G01X-717158Y76964D02*
G03I-6890J0D01*
G01X-753576Y104523D02*
Y230507D01*
G01X-717158Y210822D02*
G03I-6890J0D01*
G01X-705347D02*
G03I-18701J0D01*
G01X-749639Y234444D02*
G03X-753576Y230507I0J-3937D01*
G01X-696954Y234444D02*
X-749639D01*
G01X-792838Y472858D02*
G03X-781420I5709J0D01*
G01X-703468Y504865D02*
G03I-18700J0D01*
G01X-773349Y502779D02*
Y477779D01*
G01X-775318D02*
Y502779D01*
G01X-775909Y485259D02*
Y477779D01*
G01X-780830Y485259D02*
Y477385D01*
G01X-780982Y485259D02*
Y477779D01*
G01X-781420Y477385D02*
Y472858D01*
G01X-792838Y477385D02*
Y472858D01*
G01X-780830Y485259D02*
X-775909D01*
G01X-781420Y472858D02*
X-792838D01*
G01X-783192Y557031D02*
X-637916D01*
G01X-714294Y504865D02*
G03I-7874J0D01*
G01X-775764Y520767D02*
X-775928Y520599D01*
G01X-776256Y520934D02*
X-775764Y521437D01*
G01X-778389Y520767D02*
X-778717Y520432D01*
G01X-775436Y520934D02*
X-775764Y520767D01*
G01X-782818Y520934D02*
X-783146Y520767D01*
G01X-790200Y516411D02*
X-789380Y516914D01*
G01X-792168Y523950D02*
X-792989Y523447D01*
G01X-790364Y517249D02*
X-789872Y517584D01*
G01X-792004Y523112D02*
X-792496Y522777D01*
G01X-778717Y521102D02*
X-778389Y521437D01*
G01X-783146Y520767D02*
X-783310Y520599D01*
G01X-783638Y520934D02*
X-783146Y521437D01*
G01X-789380Y516914D02*
X-788888Y517416D01*
G01X-785771Y520767D02*
X-786099Y520432D01*
G01Y521102D02*
X-785771Y521437D01*
G01X-789872Y517584D02*
X-789216Y518589D01*
G01X-792496Y522777D02*
X-793153Y521772D01*
G01X-775928Y520599D02*
X-776092Y520264D01*
G01X-783310Y520599D02*
X-783474Y520264D01*
G01X-788888Y517416D02*
X-788559Y518086D01*
G01X-775764Y521437D02*
X-775272Y521604D01*
G01X-777897Y520934D02*
X-778389Y520767D01*
G01Y521437D02*
X-777897Y521604D01*
G01X-783146Y521437D02*
X-782654Y521604D01*
G01X-785279Y520934D02*
X-785771Y520767D01*
G01Y521437D02*
X-785279Y521604D01*
G01X-788559Y518086D02*
X-788395Y518589D01*
G01D02*
X-788231Y519427D01*
G01X-789216Y518589D02*
X-789052Y519594D01*
G01X-746184Y696795D02*
Y557031D01*
G01X-769806D02*
Y513724D01*
G01X-773468Y520264D02*
Y516243D01*
G01X-774288D02*
Y520264D01*
G01X-775751Y498763D02*
Y496795D01*
G01X-776092Y520264D02*
Y516243D01*
G01X-776145Y498763D02*
Y502779D01*
G01Y498763D02*
Y496795D01*
G01X-776912Y516243D02*
Y520264D01*
G01X-778113Y498763D02*
Y502779D01*
G01Y498763D02*
Y496795D01*
G01X-778507Y498763D02*
Y496795D01*
G01X-778717Y520432D02*
Y516243D01*
G01Y521604D02*
Y521102D01*
G01X-779537Y516243D02*
Y521604D01*
G01X-780849Y520264D02*
Y516243D01*
G01X-781670D02*
Y520264D01*
G01X-783474D02*
Y516243D01*
G01X-784294D02*
Y520264D01*
G01X-785751Y498763D02*
Y496795D01*
G01X-786099Y520432D02*
Y516243D01*
G01Y521604D02*
Y521102D01*
G01X-786145Y498763D02*
Y502779D01*
G01Y498763D02*
Y496795D01*
G01X-786919Y516243D02*
Y521604D01*
G01X-787129Y560180D02*
Y553881D01*
G01X-788113Y498763D02*
Y496795D01*
G01Y502779D02*
Y498763D01*
G01X-788231Y519427D02*
Y520934D01*
G01X-788507Y498763D02*
Y496795D01*
G01X-789052Y519594D02*
Y520767D01*
G01X-792843Y505850D02*
Y503724D01*
G01X-793108D02*
Y505488D01*
G01X-789052Y520767D02*
X-789216Y521772D01*
G01X-788231Y520934D02*
X-788395Y521772D01*
G01D02*
X-788559Y522275D01*
G01X-773796Y521102D02*
X-773468Y520264D01*
G01X-781178Y521102D02*
X-780849Y520264D01*
G01X-774288D02*
X-774452Y520599D01*
G01X-776912Y520264D02*
X-777077Y520599D01*
G01X-781670Y520264D02*
X-781834Y520599D01*
G01X-784294Y520264D02*
X-784458Y520599D01*
G01X-788559Y522275D02*
X-788888Y522945D01*
G01X-789216Y521772D02*
X-789872Y522777D01*
G01X-793153Y518589D02*
X-792496Y517584D01*
G01X-774124Y521437D02*
X-773796Y521102D01*
G01X-774452Y520599D02*
X-774616Y520767D01*
G01X-776748Y521437D02*
X-776256Y520934D01*
G01X-777077Y520599D02*
X-777241Y520767D01*
G01X-781506Y521437D02*
X-781178Y521102D01*
G01X-781834Y520599D02*
X-781998Y520767D01*
G01X-784130Y521437D02*
X-783638Y520934D01*
G01X-784458Y520599D02*
X-784622Y520767D01*
G01X-788888Y522945D02*
X-789380Y523447D01*
G01X-789872Y522777D02*
X-790364Y523112D01*
G01X-792496Y517584D02*
X-792004Y517249D01*
G01X-789380Y523447D02*
X-790200Y523950D01*
G01X-792989Y516914D02*
X-792168Y516411D01*
G01X-774616Y520767D02*
X-774944Y520934D01*
G01X-777241Y520767D02*
X-777569Y520934D01*
G01X-781998Y520767D02*
X-782326Y520934D01*
G01X-784622Y520767D02*
X-784951Y520934D01*
G01X-774616Y521604D02*
X-774124Y521437D01*
G01X-777241Y521604D02*
X-776748Y521437D01*
G01X-781998Y521604D02*
X-781506Y521437D01*
G01X-784622Y521604D02*
X-784130Y521437D01*
G01X-790364Y523112D02*
X-791184Y523280D01*
G01X-792004Y517249D02*
X-791184Y517081D01*
G01X-790200Y523950D02*
X-791184Y524117D01*
G01X-792168Y516411D02*
X-791184Y516243D01*
G01X-769808Y557031D02*
X-746184D01*
G01X-775272Y521604D02*
X-774616D01*
G01X-777897D02*
X-777241D01*
G01X-779537D02*
X-778717D01*
G01X-782654D02*
X-781998D01*
G01X-785279D02*
X-784622D01*
G01X-786919D02*
X-786099D01*
G01X-784951Y520934D02*
X-785279D01*
G01X-782326D02*
X-782818D01*
G01X-777569D02*
X-777897D01*
G01X-774944D02*
X-775436D01*
G01X-786099Y516243D02*
X-786919D01*
G01X-783474D02*
X-784294D01*
G01X-780849D02*
X-781670D01*
G01X-778717D02*
X-779537D01*
G01X-776092D02*
X-776912D01*
G01X-773468D02*
X-774288D01*
G01X-793108Y505850D02*
X-792843D01*
G01Y503724D02*
X-793108D01*
G01X-776145Y502779D02*
X-773349D01*
G01X-778113D02*
X-786145D01*
G01X-785751Y498763D02*
X-788507D01*
G01X-775751D02*
X-778507D01*
G01X-785751Y496795D02*
X-788507D01*
G01X-775751D02*
X-778507D01*
G01X-791184Y524117D02*
X-792168Y523950D01*
G01X-791184Y516243D02*
X-790200Y516411D01*
G01X-791184Y523280D02*
X-792004Y523112D01*
G01X-791184Y517081D02*
X-790364Y517249D01*
G01X-775736Y560457D02*
X-639037Y616661D01*
G01X-793126Y637456D02*
X-792962Y637959D01*
G01X-769806Y675141D02*
Y631834D01*
G01X-778035Y639634D02*
Y635614D01*
G01X-778855D02*
Y639634D01*
G01X-780659D02*
Y635614D01*
G01X-781479D02*
Y639634D01*
G01X-783284Y639802D02*
Y635614D01*
G01X-784104D02*
Y640975D01*
G01X-785416Y639634D02*
Y635614D01*
G01X-786237D02*
Y639634D01*
G01X-788041D02*
Y635614D01*
G01X-788861D02*
Y639634D01*
G01X-790666Y639802D02*
Y635614D01*
G01X-791486D02*
Y640975D01*
G01X-790666Y635614D02*
X-791486D01*
G01X-788041D02*
X-788861D01*
G01X-785416D02*
X-786237D01*
G01X-780659D02*
X-781479D01*
G01X-783284D02*
X-784104D01*
G01X-778035D02*
X-778855D01*
G01X-777742Y648080D02*
X-639037Y616661D01*
G01X-783192Y675141D02*
X-637916D01*
G01X-730788Y702789D02*
X-730132Y703794D01*
G01X-733413Y707982D02*
X-734069Y706977D01*
G01X-724226Y705804D02*
X-724390Y705469D01*
G01X-729804Y702621D02*
X-729476Y703291D01*
G01X-734397Y708150D02*
X-734725Y707480D01*
G01X-780495Y639969D02*
X-780659Y639634D01*
G01X-729476Y703291D02*
X-729312Y703794D01*
G01X-734725Y707480D02*
X-734889Y706977D01*
G01X-729312Y703794D02*
X-729147Y704632D01*
G01X-734889Y706977D02*
X-735053Y706139D01*
G01X-730132Y703794D02*
X-729968Y704799D01*
G01X-734069Y706977D02*
X-734233Y705972D01*
G01X-721766Y705469D02*
Y701449D01*
G01X-722586D02*
Y705469D01*
G01X-724390D02*
Y701449D01*
G01X-725210D02*
Y705469D01*
G01X-727015Y705637D02*
Y701449D01*
G01Y706810D02*
Y706307D01*
G01X-727835Y701449D02*
Y706810D01*
G01X-729968Y705972D02*
X-730132Y706977D01*
G01X-734233Y704799D02*
X-734069Y703794D01*
G01X-729147Y706139D02*
X-729312Y706977D01*
G01X-780331Y640137D02*
X-780495Y639969D01*
G01X-780823Y640304D02*
X-780331Y640807D01*
G01X-782956Y640137D02*
X-783284Y639802D01*
G01Y640472D02*
X-782956Y640807D01*
G01X-787713Y640137D02*
X-787877Y639969D01*
G01X-788205Y640304D02*
X-787713Y640807D01*
G01X-724062Y705972D02*
X-724226Y705804D01*
G01X-724554Y706139D02*
X-724062Y706642D01*
G01X-790338Y640137D02*
X-790666Y639802D01*
G01X-730296Y702119D02*
X-729804Y702621D01*
G01X-790666Y640472D02*
X-790338Y640807D01*
G01X-726687Y705972D02*
X-727015Y705637D01*
G01Y706307D02*
X-726687Y706642D01*
G01X-733905Y708652D02*
X-734397Y708150D01*
G01X-787877Y639969D02*
X-788041Y639634D01*
G01X-792962Y637959D02*
X-792798Y638797D01*
G01X-729147Y704632D02*
Y706139D01*
G01X-729968Y704799D02*
Y705972D01*
G01X-734233D02*
Y704799D01*
G01X-735053Y706139D02*
Y704632D01*
G01X-736365Y704799D02*
Y704129D01*
G01Y706810D02*
Y706139D01*
G01X-738990D02*
Y706810D01*
G01Y704129D02*
Y704799D01*
G01X-740302Y709323D02*
Y701449D01*
G01X-741287Y706139D02*
Y709323D01*
G01Y701449D02*
Y705134D01*
G01X-745880D02*
Y701449D01*
G01Y709323D02*
Y706139D01*
G01X-746864Y701449D02*
Y709323D01*
G01X-750318Y696795D02*
Y736165D01*
G01X-735053Y704632D02*
X-734889Y703794D01*
G01X-729312Y706977D02*
X-729476Y707480D01*
G01X-734889Y703794D02*
X-734725Y703291D01*
G01X-722094Y706307D02*
X-721766Y705469D01*
G01X-780003Y640304D02*
X-780331Y640137D01*
G01X-787385Y640304D02*
X-787713Y640137D01*
G01X-731116Y701616D02*
X-730296Y702119D01*
G01X-733084Y709155D02*
X-733905Y708652D01*
G01X-731280Y702454D02*
X-730788Y702789D01*
G01X-732920Y708317D02*
X-733413Y707982D01*
G01X-783284Y640975D02*
Y640472D01*
G01X-787129Y678291D02*
Y671991D01*
G01X-790666Y640975D02*
Y640472D01*
G01X-792798Y638797D02*
Y640304D01*
G01D02*
X-792962Y641142D01*
G01X-722586Y705469D02*
X-722750Y705804D01*
G01X-725210Y705469D02*
X-725375Y705804D01*
G01X-729476Y707480D02*
X-729804Y708150D01*
G01X-734725Y703291D02*
X-734397Y702621D01*
G01X-780331Y640807D02*
X-779839Y640975D01*
G01X-782464Y640304D02*
X-782956Y640137D01*
G01Y640807D02*
X-782464Y640975D01*
G01X-787713Y640807D02*
X-787221Y640975D01*
G01X-789846Y640304D02*
X-790338Y640137D01*
G01Y640807D02*
X-789846Y640975D01*
G01X-723734Y706139D02*
X-724062Y705972D01*
G01X-792962Y641142D02*
X-793126Y641645D01*
G01X-778363Y640472D02*
X-778035Y639634D01*
G01X-785744Y640472D02*
X-785416Y639634D01*
G01X-730132Y706977D02*
X-730788Y707982D01*
G01X-734069Y703794D02*
X-733413Y702789D01*
G01X-724062Y706642D02*
X-723570Y706810D01*
G01X-726195Y706139D02*
X-726687Y705972D01*
G01Y706642D02*
X-726195Y706810D01*
G01X-778855Y639634D02*
X-779019Y639969D01*
G01X-781479Y639634D02*
X-781643Y639969D01*
G01X-786237Y639634D02*
X-786401Y639969D01*
G01X-788861Y639634D02*
X-789025Y639969D01*
G01X-722422Y706642D02*
X-722094Y706307D01*
G01X-722750Y705804D02*
X-722914Y705972D01*
G01X-725046Y706642D02*
X-724554Y706139D01*
G01X-725375Y705804D02*
X-725539Y705972D01*
G01X-729804Y708150D02*
X-730296Y708652D01*
G01X-734397Y702621D02*
X-733905Y702119D01*
G01X-778691Y640807D02*
X-778363Y640472D01*
G01X-779019Y639969D02*
X-779183Y640137D01*
G01X-781315Y640807D02*
X-780823Y640304D01*
G01X-781643Y639969D02*
X-781807Y640137D01*
G01X-786073Y640807D02*
X-785744Y640472D01*
G01X-786401Y639969D02*
X-786565Y640137D01*
G01X-788697Y640807D02*
X-788205Y640304D01*
G01X-789025Y639969D02*
X-789189Y640137D01*
G01X-730788Y707982D02*
X-731280Y708317D01*
G01X-733413Y702789D02*
X-732920Y702454D01*
G01X-730296Y708652D02*
X-731116Y709155D01*
G01X-733905Y702119D02*
X-733084Y701616D01*
G01X-722914Y705972D02*
X-723242Y706139D01*
G01X-725539Y705972D02*
X-725867Y706139D01*
G01X-779183Y640137D02*
X-779511Y640304D01*
G01X-781807Y640137D02*
X-782136Y640304D01*
G01X-786565Y640137D02*
X-786893Y640304D01*
G01X-789189Y640137D02*
X-789517Y640304D01*
G01X-722914Y706810D02*
X-722422Y706642D01*
G01X-725539Y706810D02*
X-725046Y706642D01*
G01X-731280Y708317D02*
X-732100Y708485D01*
G01X-732920Y702454D02*
X-732100Y702286D01*
G01X-731116Y709155D02*
X-732100Y709323D01*
G01X-779183Y640975D02*
X-778691Y640807D01*
G01X-781807Y640975D02*
X-781315Y640807D01*
G01X-786565Y640975D02*
X-786073Y640807D01*
G01X-789189Y640975D02*
X-788697Y640807D01*
G01X-733084Y701616D02*
X-732100Y701449D01*
G01X-723570Y706810D02*
X-722914D01*
G01X-726195D02*
X-725539D01*
G01X-727835D02*
X-727015D01*
G01X-738990D02*
X-736365D01*
G01X-745880Y706139D02*
X-741287D01*
G01X-736365D02*
X-738990D01*
G01X-725867D02*
X-726195D01*
G01X-723242D02*
X-723734D01*
G01X-741287Y705134D02*
X-745880D01*
G01X-738990Y704799D02*
X-736365D01*
G01Y704129D02*
X-738990D01*
G01X-745880Y701449D02*
X-746864D01*
G01X-740302D02*
X-741287D01*
G01X-724390D02*
X-725210D01*
G01X-727015D02*
X-727835D01*
G01X-721766D02*
X-722586D01*
G01X-710948Y696795D02*
X-750318D01*
G01X-779839Y640975D02*
X-779183D01*
G01X-782464D02*
X-781807D01*
G01X-784104D02*
X-783284D01*
G01X-787221D02*
X-786565D01*
G01X-789846D02*
X-789189D01*
G01X-791486D02*
X-790666D01*
G01X-789517Y640304D02*
X-789846D01*
G01X-786893D02*
X-787385D01*
G01X-782136D02*
X-782464D01*
G01X-779511D02*
X-780003D01*
G01X-732100Y709323D02*
X-733084Y709155D01*
G01X-732100Y701449D02*
X-731116Y701616D01*
G01X-732100Y708485D02*
X-732920Y708317D01*
G01X-732100Y702286D02*
X-731280Y702454D01*
G01X-746184Y978291D02*
Y736165D01*
G01X-750318D02*
X-710948D01*
G01X-741287Y709323D02*
X-740302D01*
G01X-746864D02*
X-745880D01*
G01X-793078Y986671D02*
X-793074Y986643D01*
G01X-793089Y986697D02*
X-793078Y986671D01*
G01X-793107Y986721D02*
X-793089Y986697D01*
G01X-793132Y986742D02*
X-793107Y986721D01*
G01X-791109Y986671D02*
X-791105Y986643D01*
G01X-791120Y986697D02*
X-791109Y986671D01*
G01X-791139Y986721D02*
X-791120Y986697D01*
G01X-791163Y986742D02*
X-791139Y986721D01*
G01X-791193Y986760D02*
X-791163Y986742D01*
G01X-791227Y986773D02*
X-791193Y986760D01*
G01X-791264Y986781D02*
X-791227Y986773D01*
G01X-791302Y986783D02*
X-791264Y986781D01*
G01X-789141Y986671D02*
X-789137Y986643D01*
G01X-789152Y986697D02*
X-789141Y986671D01*
G01X-789170Y986721D02*
X-789152Y986697D01*
G01X-789195Y986742D02*
X-789170Y986721D01*
G01X-789225Y986760D02*
X-789195Y986742D01*
G01X-789259Y986773D02*
X-789225Y986760D01*
G01X-789295Y986781D02*
X-789259Y986773D01*
G01X-789334Y986783D02*
X-789295Y986781D01*
G01X-787172Y986671D02*
X-787168Y986643D01*
G01X-787183Y986697D02*
X-787172Y986671D01*
G01X-787202Y986721D02*
X-787183Y986697D01*
G01X-787226Y986742D02*
X-787202Y986721D01*
G01X-787256Y986760D02*
X-787226Y986742D01*
G01X-787290Y986773D02*
X-787256Y986760D01*
G01X-787327Y986781D02*
X-787290Y986773D01*
G01X-787365Y986783D02*
X-787327Y986781D01*
G01X-785204Y986671D02*
X-785200Y986643D01*
G01X-785215Y986697D02*
X-785204Y986671D01*
G01X-785233Y986721D02*
X-785215Y986697D01*
G01X-785258Y986742D02*
X-785233Y986721D01*
G01X-785288Y986760D02*
X-785258Y986742D01*
G01X-785322Y986773D02*
X-785288Y986760D01*
G01X-785358Y986781D02*
X-785322Y986773D01*
G01X-785397Y986783D02*
X-785358Y986781D01*
G01X-783235Y986671D02*
X-783231Y986643D01*
G01X-783246Y986697D02*
X-783235Y986671D01*
G01X-783265Y986721D02*
X-783246Y986697D01*
G01X-783289Y986742D02*
X-783265Y986721D01*
G01X-783319Y986760D02*
X-783289Y986742D01*
G01X-783353Y986773D02*
X-783319Y986760D01*
G01X-783390Y986781D02*
X-783353Y986773D01*
G01X-783428Y986783D02*
X-783390Y986781D01*
G01X-781267Y986671D02*
X-781263Y986643D01*
G01X-781278Y986697D02*
X-781267Y986671D01*
G01X-781296Y986721D02*
X-781278Y986697D01*
G01X-781321Y986742D02*
X-781296Y986721D01*
G01X-781351Y986760D02*
X-781321Y986742D01*
G01X-781385Y986773D02*
X-781351Y986760D01*
G01X-781421Y986781D02*
X-781385Y986773D01*
G01X-781460Y986783D02*
X-781421Y986781D01*
G01X-779298Y986671D02*
X-779294Y986643D01*
G01X-779309Y986697D02*
X-779298Y986671D01*
G01X-779328Y986721D02*
X-779309Y986697D01*
G01X-779352Y986742D02*
X-779328Y986721D01*
G01X-779382Y986760D02*
X-779352Y986742D01*
G01X-779416Y986773D02*
X-779382Y986760D01*
G01X-779453Y986781D02*
X-779416Y986773D01*
G01X-779491Y986783D02*
X-779453Y986781D01*
G01X-777330Y986671D02*
X-777326Y986643D01*
G01X-777341Y986697D02*
X-777330Y986671D01*
G01X-777359Y986721D02*
X-777341Y986697D01*
G01X-777384Y986742D02*
X-777359Y986721D01*
G01X-777414Y986760D02*
X-777384Y986742D01*
G01X-777448Y986773D02*
X-777414Y986760D01*
G01X-777484Y986781D02*
X-777448Y986773D01*
G01X-777523Y986783D02*
X-777484Y986781D01*
G01X-775361Y986671D02*
X-775357Y986643D01*
G01X-775372Y986697D02*
X-775361Y986671D01*
G01X-775391Y986721D02*
X-775372Y986697D01*
G01X-775415Y986742D02*
X-775391Y986721D01*
G01X-775445Y986760D02*
X-775415Y986742D01*
G01X-775479Y986773D02*
X-775445Y986760D01*
G01X-775516Y986781D02*
X-775479Y986773D01*
G01X-775554Y986783D02*
X-775516Y986781D01*
G01X-773393Y986671D02*
X-773389Y986643D01*
G01X-773404Y986697D02*
X-773393Y986671D01*
G01X-773422Y986721D02*
X-773404Y986697D01*
G01X-773446Y986742D02*
X-773422Y986721D01*
G01X-773477Y986760D02*
X-773446Y986742D01*
G01X-773511Y986773D02*
X-773477Y986760D01*
G01X-773547Y986781D02*
X-773511Y986773D01*
G01X-773586Y986783D02*
X-773547Y986781D01*
G01X-763550Y986671D02*
X-763546Y986643D01*
G01X-763561Y986697D02*
X-763550Y986671D01*
G01X-763580Y986721D02*
X-763561Y986697D01*
G01X-763604Y986742D02*
X-763580Y986721D01*
G01X-763634Y986760D02*
X-763604Y986742D01*
G01X-763668Y986773D02*
X-763634Y986760D01*
G01X-763705Y986781D02*
X-763668Y986773D01*
G01X-763743Y986783D02*
X-763705Y986781D01*
G01X-761582Y986671D02*
X-761578Y986643D01*
G01X-761593Y986697D02*
X-761582Y986671D01*
G01X-761611Y986721D02*
X-761593Y986697D01*
G01X-761635Y986742D02*
X-761611Y986721D01*
G01X-761666Y986760D02*
X-761635Y986742D01*
G01X-761700Y986773D02*
X-761666Y986760D01*
G01X-761736Y986781D02*
X-761700Y986773D01*
G01X-761775Y986783D02*
X-761736Y986781D01*
G01X-759613Y986671D02*
X-759609Y986643D01*
G01X-759624Y986697D02*
X-759613Y986671D01*
G01X-759643Y986721D02*
X-759624Y986697D01*
G01X-759667Y986742D02*
X-759643Y986721D01*
G01X-759697Y986760D02*
X-759667Y986742D01*
G01X-759731Y986773D02*
X-759697Y986760D01*
G01X-759768Y986781D02*
X-759731Y986773D01*
G01X-759806Y986783D02*
X-759768Y986781D01*
G01X-757645Y986671D02*
X-757641Y986643D01*
G01X-757656Y986697D02*
X-757645Y986671D01*
G01X-757674Y986721D02*
X-757656Y986697D01*
G01X-757698Y986742D02*
X-757674Y986721D01*
G01X-757729Y986760D02*
X-757698Y986742D01*
G01X-757763Y986773D02*
X-757729Y986760D01*
G01X-757799Y986781D02*
X-757763Y986773D01*
G01X-757838Y986783D02*
X-757799Y986781D01*
G01X-793081Y986438D02*
X-793074Y986362D01*
G01X-793100Y986501D02*
X-793081Y986438D01*
G01X-793128Y986552D02*
X-793100Y986501D01*
G01X-791113Y986438D02*
X-791105Y986362D01*
G01X-791132Y986501D02*
X-791113Y986438D01*
G01X-791159Y986552D02*
X-791132Y986501D01*
G01X-791192Y986591D02*
X-791159Y986552D01*
G01X-791227Y986618D02*
X-791192Y986591D01*
G01X-791264Y986634D02*
X-791227Y986618D01*
G01X-791302Y986639D02*
X-791264Y986634D01*
G01X-789144Y986438D02*
X-789137Y986362D01*
G01X-789163Y986501D02*
X-789144Y986438D01*
G01X-789191Y986552D02*
X-789163Y986501D01*
G01X-789223Y986591D02*
X-789191Y986552D01*
G01X-789259Y986618D02*
X-789223Y986591D01*
G01X-789295Y986634D02*
X-789259Y986618D01*
G01X-789334Y986639D02*
X-789295Y986634D01*
G01X-787176Y986438D02*
X-787168Y986362D01*
G01X-787195Y986501D02*
X-787176Y986438D01*
G01X-787222Y986552D02*
X-787195Y986501D01*
G01X-787255Y986591D02*
X-787222Y986552D01*
G01X-787290Y986618D02*
X-787255Y986591D01*
G01X-787327Y986634D02*
X-787290Y986618D01*
G01X-787365Y986639D02*
X-787327Y986634D01*
G01X-785207Y986438D02*
X-785200Y986362D01*
G01X-785226Y986501D02*
X-785207Y986438D01*
G01X-785254Y986552D02*
X-785226Y986501D01*
G01X-785286Y986591D02*
X-785254Y986552D01*
G01X-785322Y986618D02*
X-785286Y986591D01*
G01X-785358Y986634D02*
X-785322Y986618D01*
G01X-785397Y986639D02*
X-785358Y986634D01*
G01X-783239Y986438D02*
X-783231Y986362D01*
G01X-783258Y986501D02*
X-783239Y986438D01*
G01X-783285Y986552D02*
X-783258Y986501D01*
G01X-783318Y986591D02*
X-783285Y986552D01*
G01X-783353Y986618D02*
X-783318Y986591D01*
G01X-783390Y986634D02*
X-783353Y986618D01*
G01X-783428Y986639D02*
X-783390Y986634D01*
G01X-781270Y986438D02*
X-781263Y986362D01*
G01X-781289Y986501D02*
X-781270Y986438D01*
G01X-781317Y986552D02*
X-781289Y986501D01*
G01X-781349Y986591D02*
X-781317Y986552D01*
G01X-781384Y986618D02*
X-781349Y986591D01*
G01X-781421Y986634D02*
X-781384Y986618D01*
G01X-781460Y986639D02*
X-781421Y986634D01*
G01X-779302Y986438D02*
X-779294Y986362D01*
G01X-779321Y986501D02*
X-779302Y986438D01*
G01X-779348Y986552D02*
X-779321Y986501D01*
G01X-779381Y986591D02*
X-779348Y986552D01*
G01X-779416Y986618D02*
X-779381Y986591D01*
G01X-779453Y986634D02*
X-779416Y986618D01*
G01X-779491Y986639D02*
X-779453Y986634D01*
G01X-777333Y986438D02*
X-777326Y986362D01*
G01X-777352Y986501D02*
X-777333Y986438D01*
G01X-777380Y986552D02*
X-777352Y986501D01*
G01X-777412Y986591D02*
X-777380Y986552D01*
G01X-777447Y986618D02*
X-777412Y986591D01*
G01X-777484Y986634D02*
X-777447Y986618D01*
G01X-777523Y986639D02*
X-777484Y986634D01*
G01X-775365Y986438D02*
X-775357Y986362D01*
G01X-775384Y986501D02*
X-775365Y986438D01*
G01X-775411Y986552D02*
X-775384Y986501D01*
G01X-775444Y986591D02*
X-775411Y986552D01*
G01X-775479Y986618D02*
X-775444Y986591D01*
G01X-775516Y986634D02*
X-775479Y986618D01*
G01X-775554Y986639D02*
X-775516Y986634D01*
G01X-773396Y986438D02*
X-773389Y986362D01*
G01X-773415Y986501D02*
X-773396Y986438D01*
G01X-773443Y986552D02*
X-773415Y986501D01*
G01X-773475Y986591D02*
X-773443Y986552D01*
G01X-773510Y986618D02*
X-773475Y986591D01*
G01X-773547Y986634D02*
X-773510Y986618D01*
G01X-773586Y986639D02*
X-773547Y986634D01*
G01X-763554Y986438D02*
X-763546Y986362D01*
G01X-763573Y986501D02*
X-763554Y986438D01*
G01X-763600Y986552D02*
X-763573Y986501D01*
G01X-763633Y986591D02*
X-763600Y986552D01*
G01X-763668Y986618D02*
X-763633Y986591D01*
G01X-763705Y986634D02*
X-763668Y986618D01*
G01X-763743Y986639D02*
X-763705Y986634D01*
G01X-761585Y986438D02*
X-761578Y986362D01*
G01X-761604Y986501D02*
X-761585Y986438D01*
G01X-761632Y986552D02*
X-761604Y986501D01*
G01X-761664Y986591D02*
X-761632Y986552D01*
G01X-761699Y986618D02*
X-761664Y986591D01*
G01X-761736Y986634D02*
X-761699Y986618D01*
G01X-761775Y986639D02*
X-761736Y986634D01*
G01X-759617Y986438D02*
X-759609Y986362D01*
G01X-759636Y986501D02*
X-759617Y986438D01*
G01X-759663Y986552D02*
X-759636Y986501D01*
G01X-759696Y986591D02*
X-759663Y986552D01*
G01X-759731Y986618D02*
X-759696Y986591D01*
G01X-759768Y986634D02*
X-759731Y986618D01*
G01X-759806Y986639D02*
X-759768Y986634D01*
G01X-757648Y986438D02*
X-757641Y986362D01*
G01X-757667Y986501D02*
X-757648Y986438D01*
G01X-757695Y986552D02*
X-757667Y986501D01*
G01X-757727Y986591D02*
X-757695Y986552D01*
G01X-757762Y986618D02*
X-757727Y986591D01*
G01X-757799Y986634D02*
X-757762Y986618D01*
G01X-757838Y986639D02*
X-757799Y986634D01*
G01X-791656Y986781D02*
X-791617Y986783D01*
G01X-791693Y986773D02*
X-791656Y986781D01*
G01X-791727Y986760D02*
X-791693Y986773D01*
G01X-791756Y986742D02*
X-791727Y986760D01*
G01X-791781Y986721D02*
X-791756Y986742D01*
G01X-791799Y986697D02*
X-791781Y986721D01*
G01X-791810Y986671D02*
X-791799Y986697D01*
G01X-791814Y986643D02*
X-791810Y986671D01*
G01X-789688Y986781D02*
X-789649Y986783D01*
G01X-789724Y986773D02*
X-789688Y986781D01*
G01X-789758Y986760D02*
X-789724Y986773D01*
G01X-789788Y986742D02*
X-789758Y986760D01*
G01X-789813Y986721D02*
X-789788Y986742D01*
G01X-789831Y986697D02*
X-789813Y986721D01*
G01X-789842Y986671D02*
X-789831Y986697D01*
G01X-789846Y986643D02*
X-789842Y986671D01*
G01X-787719Y986781D02*
X-787680Y986783D01*
G01X-787756Y986773D02*
X-787719Y986781D01*
G01X-787790Y986760D02*
X-787756Y986773D01*
G01X-787819Y986742D02*
X-787790Y986760D01*
G01X-787844Y986721D02*
X-787819Y986742D01*
G01X-787862Y986697D02*
X-787844Y986721D01*
G01X-787873Y986671D02*
X-787862Y986697D01*
G01X-787877Y986643D02*
X-787873Y986671D01*
G01X-791656Y986634D02*
X-791617Y986639D01*
G01X-791692Y986618D02*
X-791656Y986634D01*
G01X-791728Y986591D02*
X-791692Y986618D01*
G01X-791760Y986552D02*
X-791728Y986591D01*
G01X-791788Y986501D02*
X-791760Y986552D01*
G01X-791807Y986438D02*
X-791788Y986501D01*
G01X-791814Y986362D02*
X-791807Y986438D01*
G01X-789687Y986634D02*
X-789649Y986639D01*
G01X-789724Y986618D02*
X-789687Y986634D01*
G01X-789759Y986591D02*
X-789724Y986618D01*
G01X-789792Y986552D02*
X-789759Y986591D01*
G01X-789819Y986501D02*
X-789792Y986552D01*
G01X-789838Y986438D02*
X-789819Y986501D01*
G01X-789846Y986362D02*
X-789838Y986438D01*
G01X-787719Y986634D02*
X-787680Y986639D01*
G01X-787755Y986618D02*
X-787719Y986634D01*
G01X-787791Y986591D02*
X-787755Y986618D01*
G01X-787823Y986552D02*
X-787791Y986591D01*
G01X-787851Y986501D02*
X-787823Y986552D01*
G01X-787870Y986438D02*
X-787851Y986501D01*
G01X-787877Y986362D02*
X-787870Y986438D01*
G01X-785750Y986634D02*
X-785712Y986639D01*
G01X-785787Y986618D02*
X-785750Y986634D01*
G01X-785822Y986591D02*
X-785787Y986618D01*
G01X-785855Y986552D02*
X-785822Y986591D01*
G01X-785882Y986501D02*
X-785855Y986552D01*
G01X-785901Y986438D02*
X-785882Y986501D01*
G01X-785909Y986362D02*
X-785901Y986438D01*
G01X-783782Y986634D02*
X-783743Y986639D01*
G01X-783818Y986618D02*
X-783782Y986634D01*
G01X-783854Y986591D02*
X-783818Y986618D01*
G01X-783886Y986552D02*
X-783854Y986591D01*
G01X-783914Y986501D02*
X-783886Y986552D01*
G01X-783933Y986438D02*
X-783914Y986501D01*
G01X-783940Y986362D02*
X-783933Y986438D01*
G01X-781813Y986634D02*
X-781775Y986639D01*
G01X-781850Y986618D02*
X-781813Y986634D01*
G01X-781885Y986591D02*
X-781850Y986618D01*
G01X-781918Y986552D02*
X-781885Y986591D01*
G01X-781945Y986501D02*
X-781918Y986552D01*
G01X-781964Y986438D02*
X-781945Y986501D01*
G01X-781972Y986362D02*
X-781964Y986438D01*
G01X-779845Y986634D02*
X-779806Y986639D01*
G01X-779881Y986618D02*
X-779845Y986634D01*
G01X-779917Y986591D02*
X-779881Y986618D01*
G01X-779949Y986552D02*
X-779917Y986591D01*
G01X-779977Y986501D02*
X-779949Y986552D01*
G01X-779996Y986438D02*
X-779977Y986501D01*
G01X-780003Y986362D02*
X-779996Y986438D01*
G01X-777876Y986634D02*
X-777838Y986639D01*
G01X-777913Y986618D02*
X-777876Y986634D01*
G01X-777948Y986591D02*
X-777913Y986618D01*
G01X-777981Y986552D02*
X-777948Y986591D01*
G01X-778008Y986501D02*
X-777981Y986552D01*
G01X-778027Y986438D02*
X-778008Y986501D01*
G01X-778035Y986362D02*
X-778027Y986438D01*
G01X-775908Y986634D02*
X-775869Y986639D01*
G01X-775944Y986618D02*
X-775908Y986634D01*
G01X-775980Y986591D02*
X-775944Y986618D01*
G01X-776012Y986552D02*
X-775980Y986591D01*
G01X-776040Y986501D02*
X-776012Y986552D01*
G01X-776059Y986438D02*
X-776040Y986501D01*
G01X-776066Y986362D02*
X-776059Y986438D01*
G01X-773939Y986634D02*
X-773901Y986639D01*
G01X-773976Y986618D02*
X-773939Y986634D01*
G01X-774011Y986591D02*
X-773976Y986618D01*
G01X-774044Y986552D02*
X-774011Y986591D01*
G01X-774071Y986501D02*
X-774044Y986552D01*
G01X-774090Y986438D02*
X-774071Y986501D01*
G01X-774098Y986362D02*
X-774090Y986438D01*
G01X-764097Y986634D02*
X-764058Y986639D01*
G01X-764133Y986618D02*
X-764097Y986634D01*
G01X-764169Y986591D02*
X-764133Y986618D01*
G01X-764201Y986552D02*
X-764169Y986591D01*
G01X-764228Y986501D02*
X-764201Y986552D01*
G01X-764248Y986438D02*
X-764228Y986501D01*
G01X-764255Y986362D02*
X-764248Y986438D01*
G01X-762128Y986634D02*
X-762090Y986639D01*
G01X-762165Y986618D02*
X-762128Y986634D01*
G01X-762200Y986591D02*
X-762165Y986618D01*
G01X-762233Y986552D02*
X-762200Y986591D01*
G01X-762260Y986501D02*
X-762233Y986552D01*
G01X-762279Y986438D02*
X-762260Y986501D01*
G01X-762286Y986362D02*
X-762279Y986438D01*
G01X-760159Y986634D02*
X-760121Y986639D01*
G01X-760196Y986618D02*
X-760159Y986634D01*
G01X-760232Y986591D02*
X-760196Y986618D01*
G01X-760264Y986552D02*
X-760232Y986591D01*
G01X-760291Y986501D02*
X-760264Y986552D01*
G01X-760311Y986438D02*
X-760291Y986501D01*
G01X-760318Y986362D02*
X-760311Y986438D01*
G01X-758191Y986634D02*
X-758153Y986639D01*
G01X-758228Y986618D02*
X-758191Y986634D01*
G01X-758263Y986591D02*
X-758228Y986618D01*
G01X-758296Y986552D02*
X-758263Y986591D01*
G01X-758323Y986501D02*
X-758296Y986552D01*
G01X-758342Y986438D02*
X-758323Y986501D01*
G01X-758349Y986362D02*
X-758342Y986438D01*
G01X-785751Y986781D02*
X-785712Y986783D01*
G01X-785787Y986773D02*
X-785751Y986781D01*
G01X-785821Y986760D02*
X-785787Y986773D01*
G01X-785851Y986742D02*
X-785821Y986760D01*
G01X-785876Y986721D02*
X-785851Y986742D01*
G01X-785894Y986697D02*
X-785876Y986721D01*
G01X-785905Y986671D02*
X-785894Y986697D01*
G01X-785909Y986643D02*
X-785905Y986671D01*
G01X-783782Y986781D02*
X-783743Y986783D01*
G01X-783819Y986773D02*
X-783782Y986781D01*
G01X-783853Y986760D02*
X-783819Y986773D01*
G01X-783882Y986742D02*
X-783853Y986760D01*
G01X-783907Y986721D02*
X-783882Y986742D01*
G01X-783925Y986697D02*
X-783907Y986721D01*
G01X-783936Y986671D02*
X-783925Y986697D01*
G01X-783940Y986643D02*
X-783936Y986671D01*
G01X-781814Y986781D02*
X-781775Y986783D01*
G01X-781850Y986773D02*
X-781814Y986781D01*
G01X-781884Y986760D02*
X-781850Y986773D01*
G01X-781914Y986742D02*
X-781884Y986760D01*
G01X-781939Y986721D02*
X-781914Y986742D01*
G01X-781957Y986697D02*
X-781939Y986721D01*
G01X-781968Y986671D02*
X-781957Y986697D01*
G01X-781972Y986643D02*
X-781968Y986671D01*
G01X-779845Y986781D02*
X-779806Y986783D01*
G01X-779882Y986773D02*
X-779845Y986781D01*
G01X-779916Y986760D02*
X-779882Y986773D01*
G01X-779945Y986742D02*
X-779916Y986760D01*
G01X-779970Y986721D02*
X-779945Y986742D01*
G01X-779988Y986697D02*
X-779970Y986721D01*
G01X-779999Y986671D02*
X-779988Y986697D01*
G01X-780003Y986643D02*
X-779999Y986671D01*
G01X-777877Y986781D02*
X-777838Y986783D01*
G01X-777913Y986773D02*
X-777877Y986781D01*
G01X-777947Y986760D02*
X-777913Y986773D01*
G01X-777977Y986742D02*
X-777947Y986760D01*
G01X-778002Y986721D02*
X-777977Y986742D01*
G01X-778020Y986697D02*
X-778002Y986721D01*
G01X-778031Y986671D02*
X-778020Y986697D01*
G01X-778035Y986643D02*
X-778031Y986671D01*
G01X-775908Y986781D02*
X-775869Y986783D01*
G01X-775945Y986773D02*
X-775908Y986781D01*
G01X-775979Y986760D02*
X-775945Y986773D01*
G01X-776008Y986742D02*
X-775979Y986760D01*
G01X-776033Y986721D02*
X-776008Y986742D01*
G01X-776051Y986697D02*
X-776033Y986721D01*
G01X-776062Y986671D02*
X-776051Y986697D01*
G01X-776066Y986643D02*
X-776062Y986671D01*
G01X-773940Y986781D02*
X-773901Y986783D01*
G01X-773976Y986773D02*
X-773940Y986781D01*
G01X-774010Y986760D02*
X-773976Y986773D01*
G01X-774040Y986742D02*
X-774010Y986760D01*
G01X-774065Y986721D02*
X-774040Y986742D01*
G01X-774083Y986697D02*
X-774065Y986721D01*
G01X-774094Y986671D02*
X-774083Y986697D01*
G01X-774098Y986643D02*
X-774094Y986671D01*
G01X-764097Y986781D02*
X-764058Y986783D01*
G01X-764134Y986773D02*
X-764097Y986781D01*
G01X-764168Y986760D02*
X-764134Y986773D01*
G01X-764197Y986742D02*
X-764168Y986760D01*
G01X-764222Y986721D02*
X-764197Y986742D01*
G01X-764240Y986697D02*
X-764222Y986721D01*
G01X-764251Y986671D02*
X-764240Y986697D01*
G01X-764255Y986643D02*
X-764251Y986671D01*
G01X-762129Y986781D02*
X-762090Y986783D01*
G01X-762165Y986773D02*
X-762129Y986781D01*
G01X-762199Y986760D02*
X-762165Y986773D01*
G01X-762229Y986742D02*
X-762199Y986760D01*
G01X-762254Y986721D02*
X-762229Y986742D01*
G01X-762272Y986697D02*
X-762254Y986721D01*
G01X-762283Y986671D02*
X-762272Y986697D01*
G01X-762286Y986643D02*
X-762283Y986671D01*
G01X-760160Y986781D02*
X-760121Y986783D01*
G01X-760197Y986773D02*
X-760160Y986781D01*
G01X-760231Y986760D02*
X-760197Y986773D01*
G01X-760260Y986742D02*
X-760231Y986760D01*
G01X-760285Y986721D02*
X-760260Y986742D01*
G01X-760303Y986697D02*
X-760285Y986721D01*
G01X-760314Y986671D02*
X-760303Y986697D01*
G01X-760318Y986643D02*
X-760314Y986671D01*
G01X-758192Y986781D02*
X-758153Y986783D01*
G01X-758228Y986773D02*
X-758192Y986781D01*
G01X-758262Y986760D02*
X-758228Y986773D01*
G01X-758292Y986742D02*
X-758262Y986760D01*
G01X-758317Y986721D02*
X-758292Y986742D01*
G01X-758335Y986697D02*
X-758317Y986721D01*
G01X-758346Y986671D02*
X-758335Y986697D01*
G01X-758349Y986643D02*
X-758346Y986671D01*
G01X-753763Y980653D02*
G03X-752582Y979472I1181J0D01*
G01X-752090Y983606D02*
G03I-1968J0D01*
G01X-751302D02*
G03I-2756J0D01*
G01X-750909D02*
G03I-3149J0D01*
G01Y973960D02*
G03X-750121Y974747I0J788D01*
G01X-715279Y945810D02*
G03I-6889J0D01*
G01X-703468D02*
G03I-18700J0D01*
G01X-771479Y981637D02*
G03X-767149I2165J0D01*
G01X-757798Y972582D02*
G03X-757601Y972779I0J197D01*
G01X-758389D02*
G03X-758192Y972582I197J0D01*
G01X-759767D02*
G03X-759570Y972779I0J197D01*
G01X-760357D02*
G03X-760160Y972582I197J0D01*
G01X-761735D02*
G03X-761538Y972779I0J197D01*
G01X-762326D02*
G03X-762129Y972582I197J0D01*
G01X-763704D02*
G03X-763507Y972779I0J197D01*
G01X-764294D02*
G03X-764098Y972582I197J0D01*
G01X-773546D02*
G03X-773349Y972779I0J197D01*
G01X-774137D02*
G03X-773940Y972582I197J0D01*
G01X-775515D02*
G03X-775318Y972779I0J197D01*
G01X-776105D02*
G03X-775909Y972582I197J0D01*
G01X-777483D02*
G03X-777286Y972779I0J197D01*
G01X-778074D02*
G03X-777877Y972582I197J0D01*
G01X-779452D02*
G03X-779255Y972779I0J197D01*
G01X-780042D02*
G03X-779846Y972582I197J0D01*
G01X-781420D02*
G03X-781223Y972779I0J197D01*
G01X-782011D02*
G03X-781814Y972582I197J0D01*
G01X-783389D02*
G03X-783192Y972779I0J197D01*
G01X-783979D02*
G03X-783783Y972582I197J0D01*
G01X-785357D02*
G03X-785160Y972779I0J197D01*
G01X-785948D02*
G03X-785751Y972582I197J0D01*
G01X-787326D02*
G03X-787129Y972779I0J197D01*
G01X-787916D02*
G03X-787720Y972582I197J0D01*
G01X-789294D02*
G03X-789098Y972779I0J196D01*
G01X-789885D02*
G03X-789688Y972582I197J0D01*
G01X-791263D02*
G03X-791066Y972779I0J197D01*
G01X-791853D02*
G03X-791657Y972582I197J0D01*
G01X-793231D02*
G03X-793035Y972779I0J196D01*
G01X-756710Y983923D02*
X-756617Y985583D01*
G01X-756625Y985767D02*
X-756670Y984973D01*
G01X-758679Y983923D02*
X-758586Y985583D01*
G01X-758594Y985767D02*
X-758638Y984973D01*
G01X-760647Y983923D02*
X-760554Y985583D01*
G01X-760562Y985767D02*
X-760607Y984973D01*
G01X-756625Y985767D02*
X-756617Y985924D01*
G01X-758594Y985767D02*
X-758586Y985924D01*
G01X-760562Y985767D02*
X-760554Y985924D01*
G01X-756710Y983923D02*
X-756670Y984973D01*
G01X-758679Y983923D02*
X-758638Y984973D01*
G01X-760647Y983923D02*
X-760607Y984973D01*
G01X-762616Y983923D02*
X-762575Y984973D01*
G01X-750121Y1005259D02*
Y973960D01*
G01X-750318Y1006736D02*
Y995909D01*
G01X-752582Y983409D02*
Y979472D01*
G01X-753763Y990495D02*
Y980653D01*
G01X-754846Y980965D02*
Y973960D01*
G01X-755042Y995909D02*
Y1006736D01*
G01X-756617Y987940D02*
Y985583D01*
G01X-757405D02*
Y987940D01*
G01Y971598D02*
Y977700D01*
G01X-757601Y975100D02*
Y972779D01*
G01X-757641Y986643D02*
Y982464D01*
G01X-757838Y986783D02*
Y986639D01*
G01X-757995Y999944D02*
Y996007D01*
G01X-758153Y986639D02*
Y986783D01*
G01X-758349Y986643D02*
Y982464D01*
G01X-758389Y972779D02*
Y975100D01*
G01X-758586Y977700D02*
Y971598D01*
G01Y987940D02*
Y985583D01*
G01X-759373D02*
Y987940D01*
G01Y971598D02*
Y977700D01*
G01X-759570Y975100D02*
Y972779D01*
G01X-759609Y986643D02*
Y982464D01*
G01X-759806Y986783D02*
Y986639D01*
G01X-759964Y999944D02*
Y996007D01*
G01X-760121Y986639D02*
Y986783D01*
G01X-760318Y986643D02*
Y982464D01*
G01X-760357Y972779D02*
Y975100D01*
G01X-760554Y977700D02*
Y971598D01*
G01Y987940D02*
Y985583D01*
G01X-761342D02*
Y987940D01*
G01Y977700D02*
Y971598D01*
G01X-761538Y975100D02*
Y972779D01*
G01X-761578Y986643D02*
Y982464D01*
G01X-761775Y986783D02*
Y986639D01*
G01X-762090D02*
Y986783D01*
G01X-762286Y986643D02*
Y982464D01*
G01X-762326Y972779D02*
Y975100D01*
G01X-762523Y971598D02*
Y977700D01*
G01Y987940D02*
Y985583D01*
G01X-763310D02*
Y987940D01*
G01Y977700D02*
Y971598D01*
G01X-763507Y975100D02*
Y972779D01*
G01X-763546Y986643D02*
Y982464D01*
G01X-763743Y986783D02*
Y986639D01*
G01X-764058D02*
Y986783D01*
G01X-764255Y986643D02*
Y982464D01*
G01X-764294Y972779D02*
Y975100D01*
G01X-764491Y971598D02*
Y977700D01*
G01Y987940D02*
Y985583D01*
G01X-765279D02*
Y987940D01*
G01X-767149Y981637D02*
Y990495D01*
G01X-757311Y983923D02*
X-757352Y984973D01*
G01X-759280Y983923D02*
X-759320Y984973D01*
G01X-761248Y983923D02*
X-761289Y984973D01*
G01X-763217Y983923D02*
X-763257Y984973D01*
G01X-765185Y983923D02*
X-765226Y984973D01*
G01X-757405Y985924D02*
X-757397Y985767D01*
G01X-759373Y985924D02*
X-759365Y985767D01*
G01X-761342Y985924D02*
X-761334Y985767D01*
G01X-763310Y985924D02*
X-763302Y985767D01*
G01X-765279Y985924D02*
X-765271Y985767D01*
G01X-775121Y985924D02*
X-775113Y985767D01*
G01X-757311Y983923D02*
X-757405Y985583D01*
G01X-759280Y983923D02*
X-759373Y985583D01*
G01X-761248Y983923D02*
X-761342Y985583D01*
G01X-763217Y983923D02*
X-763310Y985583D01*
G01X-765185Y983923D02*
X-765279Y985583D01*
G01X-775028Y983923D02*
X-775121Y985583D01*
G01X-757352Y984973D02*
X-757397Y985767D01*
G01X-759320Y984973D02*
X-759365Y985767D01*
G01X-761289Y984973D02*
X-761334Y985767D01*
G01X-763257Y984973D02*
X-763302Y985767D01*
G01X-765226Y984973D02*
X-765271Y985767D01*
G01X-775068Y984973D02*
X-775113Y985767D01*
G01X-762616Y983923D02*
X-762523Y985583D01*
G01X-762531Y985767D02*
X-762575Y984973D01*
G01X-764584Y983923D02*
X-764491Y985583D01*
G01X-764499Y985767D02*
X-764544Y984973D01*
G01X-774427Y983923D02*
X-774334Y985583D01*
G01X-774342Y985767D02*
X-774386Y984973D01*
G01X-776396Y983923D02*
X-776302Y985583D01*
G01X-776310Y985767D02*
X-776355Y984973D01*
G01X-778364Y983923D02*
X-778271Y985583D01*
G01X-778279Y985767D02*
X-778323Y984973D01*
G01X-780333Y983923D02*
X-780239Y985583D01*
G01X-780247Y985767D02*
X-780292Y984973D01*
G01X-782301Y983923D02*
X-782208Y985583D01*
G01X-782216Y985767D02*
X-782261Y984973D01*
G01X-784270Y983923D02*
X-784176Y985583D01*
G01X-784184Y985767D02*
X-784229Y984973D01*
G01X-786238Y983923D02*
X-786145Y985583D01*
G01X-786153Y985767D02*
X-786198Y984973D01*
G01X-788207Y983923D02*
X-788113Y985583D01*
G01X-788121Y985767D02*
X-788166Y984973D01*
G01X-790175Y983923D02*
X-790082Y985583D01*
G01X-790090Y985767D02*
X-790135Y984973D01*
G01X-792144Y983923D02*
X-792050Y985583D01*
G01X-792058Y985767D02*
X-792103Y984973D01*
G01X-762531Y985767D02*
X-762523Y985924D01*
G01X-764499Y985767D02*
X-764491Y985924D01*
G01X-774342Y985767D02*
X-774334Y985924D01*
G01X-776310Y985767D02*
X-776302Y985924D01*
G01X-778279Y985767D02*
X-778271Y985924D01*
G01X-780247Y985767D02*
X-780239Y985924D01*
G01X-782216Y985767D02*
X-782208Y985924D01*
G01X-784184Y985767D02*
X-784176Y985924D01*
G01X-786153Y985767D02*
X-786145Y985924D01*
G01X-788121Y985767D02*
X-788113Y985924D01*
G01X-790090Y985767D02*
X-790082Y985924D01*
G01X-792058Y985767D02*
X-792050Y985924D01*
G01X-764584Y983923D02*
X-764544Y984973D01*
G01X-774427Y983923D02*
X-774386Y984973D01*
G01X-776396Y983923D02*
X-776355Y984973D01*
G01X-778364Y983923D02*
X-778323Y984973D01*
G01X-780333Y983923D02*
X-780292Y984973D01*
G01X-782301Y983923D02*
X-782261Y984973D01*
G01X-784270Y983923D02*
X-784229Y984973D01*
G01X-786238Y983923D02*
X-786198Y984973D01*
G01X-788207Y983923D02*
X-788166Y984973D01*
G01X-790175Y983923D02*
X-790135Y984973D01*
G01X-792144Y983923D02*
X-792103Y984973D01*
G01X-771479Y990495D02*
Y981637D01*
G01X-773153Y971598D02*
Y977700D01*
G01X-773349Y975100D02*
Y972779D01*
G01X-773389Y986643D02*
Y982464D01*
G01X-773586Y986783D02*
Y986639D01*
G01X-773901D02*
Y986783D01*
G01X-774098Y986643D02*
Y982464D01*
G01X-774137Y972779D02*
Y975100D01*
G01X-774334Y977700D02*
Y971598D01*
G01Y987940D02*
Y985583D01*
G01X-775121D02*
Y987940D01*
G01Y971598D02*
Y977700D01*
G01X-775318Y975100D02*
Y972779D01*
G01X-775357Y986643D02*
Y982464D01*
G01X-775554Y986783D02*
Y986639D01*
G01X-775869D02*
Y986783D01*
G01X-776066Y986643D02*
Y982464D01*
G01X-776105Y972779D02*
Y975100D01*
G01X-776302Y977700D02*
Y971598D01*
G01Y987940D02*
Y985583D01*
G01X-777090D02*
Y987940D01*
G01Y977700D02*
Y971598D01*
G01X-777286Y975100D02*
Y972779D01*
G01X-777326Y986643D02*
Y982464D01*
G01X-777523Y986783D02*
Y986639D01*
G01X-777838D02*
Y986783D01*
G01X-778035Y986643D02*
Y982464D01*
G01X-778074Y972779D02*
Y975100D01*
G01X-778271Y971598D02*
Y977700D01*
G01Y987940D02*
Y985583D01*
G01X-779058D02*
Y987940D01*
G01Y977700D02*
Y971598D01*
G01X-779255Y975100D02*
Y972779D01*
G01X-779294Y986643D02*
Y982464D01*
G01X-779491Y986783D02*
Y986639D01*
G01X-779806D02*
Y986783D01*
G01X-780003Y986643D02*
Y982464D01*
G01X-780042Y972779D02*
Y975100D01*
G01X-780239Y971598D02*
Y977700D01*
G01Y987940D02*
Y985583D01*
G01X-781027D02*
Y987940D01*
G01Y971598D02*
Y977700D01*
G01X-781223Y975100D02*
Y972779D01*
G01X-781263Y986643D02*
Y982464D01*
G01X-781460Y986783D02*
Y986639D01*
G01X-781775D02*
Y986783D01*
G01X-781972Y986643D02*
Y982464D01*
G01X-782011Y972779D02*
Y975100D01*
G01X-782208Y977700D02*
Y971598D01*
G01Y987940D02*
Y985583D01*
G01X-782995D02*
Y987940D01*
G01Y971598D02*
Y977700D01*
G01X-783192Y975100D02*
Y972779D01*
G01X-783231Y986643D02*
Y982464D01*
G01X-783428Y986783D02*
Y986639D01*
G01X-783743D02*
Y986783D01*
G01X-783940Y986643D02*
Y982464D01*
G01X-783979Y972779D02*
Y975100D01*
G01X-784176Y977700D02*
Y971598D01*
G01Y987940D02*
Y985583D01*
G01X-784964D02*
Y987940D01*
G01Y971598D02*
Y977700D01*
G01X-785160Y975100D02*
Y972779D01*
G01X-785200Y986643D02*
Y982464D01*
G01X-785397Y986783D02*
Y986639D01*
G01X-785712D02*
Y986783D01*
G01X-785909Y986643D02*
Y982464D01*
G01X-785948Y972779D02*
Y975100D01*
G01X-786145Y977700D02*
Y971598D01*
G01Y987940D02*
Y985583D01*
G01X-786932D02*
Y987940D01*
G01Y977700D02*
Y971598D01*
G01X-787129Y975100D02*
Y972779D01*
G01X-787168Y986643D02*
Y982464D01*
G01X-787365Y986783D02*
Y986639D01*
G01X-787680D02*
Y986783D01*
G01X-787877Y986643D02*
Y982464D01*
G01X-787916Y972779D02*
Y975100D01*
G01X-788113Y971598D02*
Y977700D01*
G01Y987940D02*
Y985583D01*
G01X-788901D02*
Y987940D01*
G01Y977700D02*
Y971598D01*
G01X-789098Y975100D02*
Y972779D01*
G01X-789137Y986643D02*
Y982464D01*
G01X-789334Y986783D02*
Y986639D01*
G01X-789649D02*
Y986783D01*
G01X-789846Y986643D02*
Y982464D01*
G01X-789885Y972779D02*
Y975100D01*
G01X-790082Y971598D02*
Y977700D01*
G01Y987940D02*
Y985583D01*
G01X-790869D02*
Y987940D01*
G01Y971598D02*
Y977700D01*
G01X-791066Y975100D02*
Y972779D01*
G01X-791105Y986643D02*
Y982464D01*
G01X-791302Y986783D02*
Y986639D01*
G01X-791617D02*
Y986783D01*
G01X-791814Y986643D02*
Y982464D01*
G01X-791853Y972779D02*
Y975100D01*
G01X-792050Y977700D02*
Y971598D01*
G01Y987940D02*
Y985583D01*
G01X-792838D02*
Y987940D01*
G01Y977700D02*
Y971598D01*
G01X-793035Y975100D02*
Y972779D01*
G01X-793074Y986643D02*
Y982464D01*
G01X-775028Y983923D02*
X-775068Y984973D01*
G01X-776996Y983923D02*
X-777037Y984973D01*
G01X-778965Y983923D02*
X-779005Y984973D01*
G01X-780933Y983923D02*
X-780974Y984973D01*
G01X-782902Y983923D02*
X-782942Y984973D01*
G01X-784870Y983923D02*
X-784911Y984973D01*
G01X-786839Y983923D02*
X-786879Y984973D01*
G01X-788807Y983923D02*
X-788848Y984973D01*
G01X-790776Y983923D02*
X-790816Y984973D01*
G01X-792744Y983923D02*
X-792785Y984973D01*
G01X-777090Y985924D02*
X-777082Y985767D01*
G01X-779058Y985924D02*
X-779050Y985767D01*
G01X-781027Y985924D02*
X-781019Y985767D01*
G01X-782995Y985924D02*
X-782987Y985767D01*
G01X-784964Y985924D02*
X-784956Y985767D01*
G01X-786932Y985924D02*
X-786924Y985767D01*
G01X-788901Y985924D02*
X-788893Y985767D01*
G01X-790869Y985924D02*
X-790861Y985767D01*
G01X-792838Y985924D02*
X-792830Y985767D01*
G01X-776996Y983923D02*
X-777090Y985583D01*
G01X-778965Y983923D02*
X-779058Y985583D01*
G01X-780933Y983923D02*
X-781027Y985583D01*
G01X-782902Y983923D02*
X-782995Y985583D01*
G01X-784870Y983923D02*
X-784964Y985583D01*
G01X-786839Y983923D02*
X-786932Y985583D01*
G01X-788807Y983923D02*
X-788901Y985583D01*
G01X-790776Y983923D02*
X-790869Y985583D01*
G01X-792744Y983923D02*
X-792838Y985583D01*
G01X-777037Y984973D02*
X-777082Y985767D01*
G01X-779005Y984973D02*
X-779050Y985767D01*
G01X-780974Y984973D02*
X-781019Y985767D01*
G01X-782942Y984973D02*
X-782987Y985767D01*
G01X-784911Y984973D02*
X-784956Y985767D01*
G01X-786879Y984973D02*
X-786924Y985767D01*
G01X-788848Y984973D02*
X-788893Y985767D01*
G01X-790816Y984973D02*
X-790861Y985767D01*
G01X-792785Y984973D02*
X-792830Y985767D01*
G01X-759964Y996007D02*
X-757995D01*
G01X-750318Y995909D02*
X-755042D01*
G01X-753763Y990495D02*
X-767149D01*
G01X-792050Y987940D02*
X-792838D01*
G01X-790082D02*
X-790869D01*
G01X-788113D02*
X-788901D01*
G01X-786145D02*
X-786932D01*
G01X-784176D02*
X-784964D01*
G01X-782208D02*
X-782995D01*
G01X-780239D02*
X-781027D01*
G01X-778271D02*
X-779058D01*
G01X-774334D02*
X-775121D01*
G01X-776302D02*
X-777090D01*
G01X-764491D02*
X-765279D01*
G01X-762523D02*
X-763310D01*
G01X-760554D02*
X-761342D01*
G01X-758586D02*
X-759373D01*
G01X-756617D02*
X-757405D01*
G01X-792050Y987257D02*
X-792838D01*
G01X-790082D02*
X-790869D01*
G01X-788113D02*
X-788901D01*
G01X-786145D02*
X-786932D01*
G01X-784176D02*
X-784964D01*
G01X-782208D02*
X-782995D01*
G01X-780239D02*
X-781027D01*
G01X-778271D02*
X-779058D01*
G01X-774334D02*
X-775121D01*
G01X-776302D02*
X-777090D01*
G01X-764491D02*
X-765279D01*
G01X-762523D02*
X-763310D01*
G01X-760554D02*
X-761342D01*
G01X-758586D02*
X-759373D01*
G01X-756617D02*
X-757405D01*
G01X-792050Y987195D02*
X-792838D01*
G01X-790082D02*
X-790869D01*
G01X-788113D02*
X-788901D01*
G01X-786145D02*
X-786932D01*
G01X-784176D02*
X-784964D01*
G01X-782208D02*
X-782995D01*
G01X-780239D02*
X-781027D01*
G01X-778271D02*
X-779058D01*
G01X-774334D02*
X-775121D01*
G01X-776302D02*
X-777090D01*
G01X-764491D02*
X-765279D01*
G01X-762523D02*
X-763310D01*
G01X-760554D02*
X-761342D01*
G01X-758586D02*
X-759373D01*
G01X-756617D02*
X-757405D01*
G01Y986868D02*
X-756617D01*
G01X-759373D02*
X-758586D01*
G01X-763310D02*
X-762523D01*
G01X-761342D02*
X-760554D01*
G01X-765279D02*
X-764491D01*
G01X-775121D02*
X-774334D01*
G01X-777090D02*
X-776302D01*
G01X-781027D02*
X-780239D01*
G01X-779058D02*
X-778271D01*
G01X-782995D02*
X-782208D01*
G01X-786932D02*
X-786145D01*
G01X-784964D02*
X-784176D01*
G01X-790869D02*
X-790082D01*
G01X-788901D02*
X-788113D01*
G01X-792838D02*
X-792050D01*
G01X-760121Y986783D02*
X-759806D01*
G01X-758153D02*
X-757838D01*
G01X-764058D02*
X-763743D01*
G01X-762090D02*
X-761775D01*
G01X-773901D02*
X-773586D01*
G01X-777838D02*
X-777523D01*
G01X-775869D02*
X-775554D01*
G01X-779806D02*
X-779491D01*
G01X-783743D02*
X-783428D01*
G01X-781775D02*
X-781460D01*
G01X-787680D02*
X-787365D01*
G01X-785712D02*
X-785397D01*
G01X-789649D02*
X-789334D01*
G01X-791617D02*
X-791302D01*
G01X-760121Y986639D02*
X-759806D01*
G01X-758153D02*
X-757838D01*
G01X-764058D02*
X-763743D01*
G01X-762090D02*
X-761775D01*
G01X-773901D02*
X-773586D01*
G01X-777838D02*
X-777523D01*
G01X-775869D02*
X-775554D01*
G01X-779806D02*
X-779491D01*
G01X-783743D02*
X-783428D01*
G01X-781775D02*
X-781460D01*
G01X-787680D02*
X-787365D01*
G01X-785712D02*
X-785397D01*
G01X-789649D02*
X-789334D01*
G01X-791617D02*
X-791302D01*
G01X-791105Y986259D02*
X-791814D01*
G01X-789137D02*
X-789846D01*
G01X-787168D02*
X-787877D01*
G01X-785200D02*
X-785909D01*
G01X-783231D02*
X-783940D01*
G01X-781263D02*
X-781972D01*
G01X-779294D02*
X-780003D01*
G01X-777326D02*
X-778035D01*
G01X-775357D02*
X-776066D01*
G01X-773389D02*
X-774098D01*
G01X-763546D02*
X-764255D01*
G01X-761578D02*
X-762286D01*
G01X-759609D02*
X-760318D01*
G01X-757641D02*
X-758349D01*
G01X-760318Y986223D02*
X-759609D01*
G01X-758349D02*
X-757641D01*
G01X-764255D02*
X-763546D01*
G01X-762286D02*
X-761578D01*
G01X-774098D02*
X-773389D01*
G01X-776066D02*
X-775357D01*
G01X-780003D02*
X-779294D01*
G01X-778035D02*
X-777326D01*
G01X-783940D02*
X-783231D01*
G01X-781972D02*
X-781263D01*
G01X-785909D02*
X-785200D01*
G01X-789846D02*
X-789137D01*
G01X-787877D02*
X-787168D01*
G01X-791814D02*
X-791105D01*
G01X-767149Y986165D02*
X-753763D01*
G01X-791105Y985891D02*
X-791814D01*
G01X-789137D02*
X-789846D01*
G01X-787168D02*
X-787877D01*
G01X-785200D02*
X-785909D01*
G01X-783231D02*
X-783940D01*
G01X-781263D02*
X-781972D01*
G01X-779294D02*
X-780003D01*
G01X-777326D02*
X-778035D01*
G01X-775357D02*
X-776066D01*
G01X-773389D02*
X-774098D01*
G01X-763546D02*
X-764255D01*
G01X-761578D02*
X-762286D01*
G01X-759609D02*
X-760318D01*
G01X-757641D02*
X-758349D01*
G01X-792058Y985767D02*
X-792830D01*
G01X-790090D02*
X-790861D01*
G01X-788121D02*
X-788893D01*
G01X-786153D02*
X-786924D01*
G01X-784184D02*
X-784956D01*
G01X-782216D02*
X-782987D01*
G01X-780247D02*
X-781019D01*
G01X-778279D02*
X-779050D01*
G01X-774342D02*
X-775113D01*
G01X-776310D02*
X-777082D01*
G01X-764499D02*
X-765271D01*
G01X-762531D02*
X-763302D01*
G01X-760562D02*
X-761334D01*
G01X-758594D02*
X-759365D01*
G01X-756625D02*
X-757397D01*
G01Y985433D02*
X-756625D01*
G01X-759365D02*
X-758594D01*
G01X-763302D02*
X-762531D01*
G01X-761334D02*
X-760562D01*
G01X-765271D02*
X-764499D01*
G01X-775113D02*
X-774342D01*
G01X-777082D02*
X-776310D01*
G01X-781019D02*
X-780247D01*
G01X-779050D02*
X-778279D01*
G01X-782987D02*
X-782216D01*
G01X-786924D02*
X-786153D01*
G01X-784956D02*
X-784184D01*
G01X-790861D02*
X-790090D01*
G01X-788893D02*
X-788121D01*
G01X-792830D02*
X-792058D01*
G01X-760318Y985043D02*
X-759609D01*
G01X-758349D02*
X-757641D01*
G01X-764255D02*
X-763546D01*
G01X-762286D02*
X-761578D01*
G01X-774098D02*
X-773389D01*
G01X-776066D02*
X-775357D01*
G01X-780003D02*
X-779294D01*
G01X-778035D02*
X-777326D01*
G01X-783940D02*
X-783231D01*
G01X-781972D02*
X-781263D01*
G01X-785909D02*
X-785200D01*
G01X-789846D02*
X-789137D01*
G01X-787877D02*
X-787168D01*
G01X-791814D02*
X-791105D01*
G01X-792103Y984973D02*
X-792785D01*
G01X-790135D02*
X-790816D01*
G01X-788166D02*
X-788848D01*
G01X-786198D02*
X-786879D01*
G01X-784229D02*
X-784911D01*
G01X-782261D02*
X-782942D01*
G01X-780292D02*
X-780974D01*
G01X-778323D02*
X-779005D01*
G01X-774386D02*
X-775068D01*
G01X-776355D02*
X-777037D01*
G01X-764544D02*
X-765226D01*
G01X-762575D02*
X-763257D01*
G01X-760607D02*
X-761289D01*
G01X-758638D02*
X-759320D01*
G01X-756670D02*
X-757352D01*
G01X-791105Y984866D02*
X-791814D01*
G01X-789137D02*
X-789846D01*
G01X-787168D02*
X-787877D01*
G01X-785200D02*
X-785909D01*
G01X-783231D02*
X-783940D01*
G01X-781263D02*
X-781972D01*
G01X-779294D02*
X-780003D01*
G01X-777326D02*
X-778035D01*
G01X-775357D02*
X-776066D01*
G01X-773389D02*
X-774098D01*
G01X-763546D02*
X-764255D01*
G01X-761578D02*
X-762286D01*
G01X-759609D02*
X-760318D01*
G01X-757641D02*
X-758349D01*
G01X-792144Y983923D02*
X-792744D01*
G01X-790175D02*
X-790776D01*
G01X-788207D02*
X-788807D01*
G01X-786238D02*
X-786839D01*
G01X-784270D02*
X-784870D01*
G01X-782301D02*
X-782902D01*
G01X-780333D02*
X-780933D01*
G01X-778364D02*
X-778965D01*
G01X-774427D02*
X-775028D01*
G01X-776396D02*
X-776996D01*
G01X-764584D02*
X-765185D01*
G01X-762616D02*
X-763217D01*
G01X-760647D02*
X-761248D01*
G01X-758679D02*
X-759280D01*
G01X-756710D02*
X-757311D01*
G01X-791105Y983724D02*
X-791814D01*
G01X-789137D02*
X-789846D01*
G01X-787168D02*
X-787877D01*
G01X-785200D02*
X-785909D01*
G01X-783231D02*
X-783940D01*
G01X-781263D02*
X-781972D01*
G01X-779294D02*
X-780003D01*
G01X-777326D02*
X-778035D01*
G01X-775357D02*
X-776066D01*
G01X-773389D02*
X-774098D01*
G01X-763546D02*
X-764255D01*
G01X-761578D02*
X-762286D01*
G01X-759609D02*
X-760318D01*
G01X-757641D02*
X-758349D01*
G01X-750121Y983606D02*
X-751302D01*
G01X-791105Y982464D02*
X-791814D01*
G01X-789137D02*
X-789846D01*
G01X-787168D02*
X-787877D01*
G01X-785200D02*
X-785909D01*
G01X-783231D02*
X-783940D01*
G01X-781263D02*
X-781972D01*
G01X-779294D02*
X-780003D01*
G01X-777326D02*
X-778035D01*
G01X-775357D02*
X-776066D01*
G01X-773389D02*
X-774098D01*
G01X-763546D02*
X-764255D01*
G01X-761578D02*
X-762286D01*
G01X-759609D02*
X-760318D01*
G01X-757641D02*
X-758349D01*
G01X-750121Y979472D02*
X-752582D01*
G01X-762523Y977700D02*
X-761342D01*
G01X-764491D02*
X-763310D01*
G01X-778271D02*
X-777090D01*
G01X-780239D02*
X-779058D01*
G01X-788113D02*
X-786932D01*
G01X-790082D02*
X-788901D01*
G01X-790869D02*
X-792050D01*
G01X-784964D02*
X-786145D01*
G01X-782995D02*
X-784176D01*
G01X-781027D02*
X-782208D01*
G01X-775121D02*
X-776302D01*
G01X-773153D02*
X-774334D01*
G01X-757405D02*
X-758586D01*
G01X-759373D02*
X-760554D01*
G01X-791066Y975100D02*
X-791853D01*
G01X-787129D02*
X-787916D01*
G01X-789098D02*
X-789885D01*
G01X-785160D02*
X-785948D01*
G01X-781223D02*
X-782011D01*
G01X-783192D02*
X-783979D01*
G01X-777286D02*
X-778074D01*
G01X-779255D02*
X-780042D01*
G01X-775318D02*
X-776105D01*
G01X-773349D02*
X-774137D01*
G01X-761538D02*
X-762326D01*
G01X-763507D02*
X-764294D01*
G01X-757601D02*
X-758389D01*
G01X-759570D02*
X-760357D01*
G01X-758389Y974551D02*
X-757601D01*
G01X-760357D02*
X-759570D01*
G01X-762326D02*
X-761538D01*
G01X-764294D02*
X-763507D01*
G01X-774137D02*
X-773349D01*
G01X-776105D02*
X-775318D01*
G01X-778074D02*
X-777286D01*
G01X-780042D02*
X-779255D01*
G01X-782011D02*
X-781223D01*
G01X-783979D02*
X-783192D01*
G01X-785948D02*
X-785160D01*
G01X-787916D02*
X-787129D01*
G01X-789885D02*
X-789098D01*
G01X-791853D02*
X-791066D01*
G01X-791263Y972582D02*
X-791657D01*
G01X-789294D02*
X-789688D01*
G01X-785357D02*
X-785751D01*
G01X-787326D02*
X-787720D01*
G01X-781420D02*
X-781814D01*
G01X-783389D02*
X-783783D01*
G01X-777483D02*
X-777877D01*
G01X-779452D02*
X-779846D01*
G01X-775515D02*
X-775909D01*
G01X-773546D02*
X-773940D01*
G01X-761735D02*
X-762129D01*
G01X-763704D02*
X-764098D01*
G01X-757798D02*
X-758192D01*
G01X-759767D02*
X-760160D01*
G01X-758586Y971598D02*
X-757405D01*
G01X-760554D02*
X-759373D01*
G01X-774334D02*
X-773153D01*
G01X-776302D02*
X-775121D01*
G01X-784176D02*
X-782995D01*
G01X-782208D02*
X-781027D01*
G01X-786145D02*
X-784964D01*
G01X-792050D02*
X-790869D01*
G01X-786932D02*
X-788113D01*
G01X-788901D02*
X-790082D01*
G01X-777090D02*
X-778271D01*
G01X-779058D02*
X-780239D01*
G01X-761342D02*
X-762523D01*
G01X-763310D02*
X-764491D01*
G01X-703468Y1079669D02*
G03I-18700J0D01*
G01X-753468Y998566D02*
G03X-752680I394J0D01*
G01Y1004078D02*
G03X-753468I-394J0D01*
G01X-750121Y1005259D02*
G03X-750909Y1006047I-788J0D01*
G01X-751499Y1005259D02*
G03X-752286Y1006047I-788J0D01*
G01Y996598D02*
G03X-751499Y997385I0J787D01*
G01X-757208Y1004552D02*
G03X-757405Y1004355I0J-197D01*
G01X-756617D02*
G03X-756814Y1004552I-197J0D01*
G01X-759176D02*
G03X-759373Y1004355I0J-197D01*
G01X-758586D02*
G03X-758783Y1004552I-197J0D01*
G01X-761145D02*
G03X-761342Y1004355I0J-197D01*
G01X-760554D02*
G03X-760751Y1004552I-197J0D01*
G01X-763113D02*
G03X-763310Y1004355I0J-197D01*
G01X-762523D02*
G03X-762720Y1004552I-197J0D01*
G01X-765082D02*
G03X-765279Y1004355I0J-197D01*
G01X-764491D02*
G03X-764688Y1004552I-197J0D01*
G01X-774924D02*
G03X-775121Y1004355I0J-197D01*
G01X-774334D02*
G03X-774531Y1004552I-197J0D01*
G01X-776893D02*
G03X-777090Y1004355I0J-197D01*
G01X-776302D02*
G03X-776499Y1004552I-197J0D01*
G01X-778861D02*
G03X-779058Y1004355I0J-197D01*
G01X-778271D02*
G03X-778468Y1004552I-197J0D01*
G01X-780830D02*
G03X-781027Y1004355I0J-197D01*
G01X-780239D02*
G03X-780436Y1004552I-197J0D01*
G01X-782798D02*
G03X-782995Y1004355I0J-197D01*
G01X-782208D02*
G03X-782405Y1004552I-197J0D01*
G01X-784767D02*
G03X-784964Y1004355I0J-197D01*
G01X-784176D02*
G03X-784373Y1004552I-197J0D01*
G01X-786735D02*
G03X-786932Y1004355I0J-197D01*
G01X-786145D02*
G03X-786342Y1004552I-197J0D01*
G01X-788704D02*
G03X-788901Y1004355I0J-197D01*
G01X-788113D02*
G03X-788310Y1004552I-197J0D01*
G01X-790672D02*
G03X-790869Y1004355I0J-197D01*
G01X-790082D02*
G03X-790279Y1004552I-197J0D01*
G01X-792641D02*
G03X-792838Y1004355I0J-197D01*
G01X-792050D02*
G03X-792247Y1004552I-197J0D01*
G01X-732854Y1025914D02*
X-733018Y1026920D01*
G01X-737119Y1024742D02*
X-736955Y1023736D01*
G01X-732034Y1026082D02*
X-732198Y1026920D01*
G01X-737940Y1024574D02*
X-737776Y1023736D01*
G01X-732198Y1026920D02*
X-732362Y1027422D01*
G01X-737776Y1023736D02*
X-737611Y1023234D01*
G01X-724980Y1026249D02*
X-724652Y1025412D01*
G01X-765580Y1056960D02*
X-764924Y1055285D01*
G01X-725472Y1025412D02*
X-725636Y1025747D01*
G01X-728097Y1025412D02*
X-728261Y1025747D01*
G01X-732362Y1027422D02*
X-732690Y1028092D01*
G01X-737611Y1023234D02*
X-737283Y1022564D01*
G01X-766565Y1055285D02*
X-766893Y1055955D01*
G01X-771814Y1055285D02*
X-772142Y1055955D01*
G01X-781328Y1055285D02*
X-781657Y1055955D01*
G01X-733018Y1026920D02*
X-733674Y1027925D01*
G01X-736955Y1023736D02*
X-736299Y1022731D01*
G01X-725308Y1026585D02*
X-724980Y1026249D01*
G01X-725636Y1025747D02*
X-725800Y1025914D01*
G01X-727933Y1026585D02*
X-727441Y1026082D01*
G01X-728261Y1025747D02*
X-728425Y1025914D01*
G01X-732690Y1028092D02*
X-733182Y1028595D01*
G01X-766237Y1057630D02*
X-765580Y1056960D01*
G01X-722520Y1025579D02*
Y1021391D01*
G01Y1026752D02*
Y1026249D01*
G01X-723340Y1021391D02*
Y1026752D01*
G01X-724652Y1025412D02*
Y1021391D01*
G01X-725472D02*
Y1025412D01*
G01X-727277D02*
Y1021391D01*
G01X-728097D02*
Y1025412D01*
G01X-780344Y1056960D02*
X-779688Y1055285D01*
G01X-786578D02*
X-786906Y1055955D01*
G01X-766893D02*
X-767221Y1056290D01*
G01X-771486Y1057630D02*
X-770502Y1056625D01*
G01X-737283Y1022564D02*
X-736791Y1022061D01*
G01X-772142Y1055955D02*
X-772470Y1056290D01*
G01X-781000Y1057630D02*
X-780344Y1056960D01*
G01X-781657Y1055955D02*
X-781985Y1056290D01*
G01X-786250Y1057630D02*
X-785265Y1056625D01*
G01X-786906Y1055955D02*
X-787234Y1056290D01*
G01X-733674Y1027925D02*
X-734167Y1028260D01*
G01X-733018Y1023736D02*
X-732854Y1024742D01*
G01X-729902Y1025579D02*
Y1021391D01*
G01Y1026752D02*
Y1026249D01*
G01X-730722Y1021391D02*
Y1026752D01*
G01X-732034Y1024574D02*
Y1026082D01*
G01X-732854Y1024742D02*
Y1025914D01*
G01X-737119D02*
Y1024742D01*
G01X-737940Y1026082D02*
Y1024574D01*
G01X-739252Y1024742D02*
Y1024072D01*
G01Y1026752D02*
Y1026082D01*
G01X-741877D02*
Y1026752D01*
G01Y1024072D02*
Y1024742D01*
G01X-743189Y1029265D02*
Y1021391D01*
G01X-744173Y1026082D02*
Y1029265D01*
G01Y1021391D02*
Y1025077D01*
G01X-748766D02*
Y1021391D01*
G01Y1029265D02*
Y1026082D01*
G01X-749751Y1021391D02*
Y1029265D01*
G01X-751105Y999944D02*
Y1006047D01*
G01X-751499Y1005259D02*
Y997385D01*
G01X-752680Y1004078D02*
Y998566D01*
G01X-753271Y999944D02*
Y1006047D01*
G01X-753468Y998566D02*
Y1004078D01*
G01X-753861Y996598D02*
Y1006047D01*
G01X-754164Y1003094D02*
Y996598D01*
G01X-754452Y1006047D02*
Y1003094D01*
G01X-754649Y1013724D02*
Y1053094D01*
G01X-754884Y1006047D02*
Y1003094D01*
G01X-756420Y1001322D02*
Y1007425D01*
G01X-756617Y1004355D02*
Y1002034D01*
G01X-757405Y1004355D02*
Y1002034D01*
G01X-757601Y1007425D02*
Y1001322D01*
G01X-758389D02*
Y1007425D01*
G01X-758586Y1004355D02*
Y1002034D01*
G01X-759373Y1004355D02*
Y1002034D01*
G01X-759570Y1007425D02*
Y1001322D01*
G01X-760357D02*
Y1007425D01*
G01X-760554Y1004355D02*
Y1002034D01*
G01X-761342Y1004355D02*
Y1002034D01*
G01X-761538Y1007425D02*
Y1001322D01*
G01X-762326Y1007425D02*
Y1001322D01*
G01X-762523Y1004355D02*
Y1002034D01*
G01X-763310Y1004355D02*
Y1002034D01*
G01X-763507Y1001322D02*
Y1007425D01*
G01X-764294D02*
Y1001322D01*
G01X-764491Y1004355D02*
Y1002034D01*
G01X-764924Y1055285D02*
Y1047243D01*
G01X-765279Y1004355D02*
Y1002034D01*
G01X-765475Y1001322D02*
Y1007425D01*
G01X-766565Y1047243D02*
Y1055285D01*
G01X-736299Y1022731D02*
X-735807Y1022396D01*
G01X-733182Y1028595D02*
X-734003Y1029098D01*
G01X-736791Y1022061D02*
X-735971Y1021559D01*
G01X-767221Y1056290D02*
X-767877Y1056625D01*
G01X-772470Y1056290D02*
X-773126Y1056625D01*
G01X-721043Y1025914D02*
X-721371Y1026082D01*
G01X-781985Y1056290D02*
X-782641Y1056625D01*
G01X-725800Y1025914D02*
X-726129Y1026082D01*
G01X-787234Y1056290D02*
X-787890Y1056625D01*
G01X-728425Y1025914D02*
X-728753Y1026082D01*
G01X-732362Y1023234D02*
X-732198Y1023736D01*
G01D02*
X-732034Y1024574D01*
G01X-737776Y1026920D02*
X-737940Y1026082D01*
G01X-736955Y1026920D02*
X-737119Y1025914D01*
G01X-770174Y1055285D02*
Y1047243D01*
G01X-771814D02*
Y1055285D01*
G01X-774137Y1007425D02*
Y1001322D01*
G01X-774334Y1004355D02*
Y1002034D01*
G01X-775121Y1004355D02*
Y1002034D01*
G01X-775318Y1001322D02*
Y1007425D01*
G01X-775423Y1055620D02*
Y1047243D01*
G01Y1057965D02*
Y1056960D01*
G01X-776105Y1001322D02*
Y1007425D01*
G01X-776302Y1004355D02*
Y1002034D01*
G01X-777063Y1047243D02*
Y1057965D01*
G01X-777090Y1004355D02*
Y1002034D01*
G01X-777286Y1007425D02*
Y1001322D01*
G01X-778074D02*
Y1007425D01*
G01X-778271Y1004355D02*
Y1002034D01*
G01X-779058Y1004355D02*
Y1002034D01*
G01X-779255Y1007425D02*
Y1001322D01*
G01X-779688Y1055285D02*
Y1047243D01*
G01X-780042Y1001322D02*
Y1007425D01*
G01X-780239Y1004355D02*
Y1002034D01*
G01X-781027Y1004355D02*
Y1002034D01*
G01X-781223Y1007425D02*
Y1001322D01*
G01X-781328Y1047243D02*
Y1055285D01*
G01X-782011Y1001322D02*
Y1007425D01*
G01X-782208Y1004355D02*
Y1002034D01*
G01X-782995Y1004355D02*
Y1002034D01*
G01X-783192Y1007425D02*
Y1001322D01*
G01X-783979Y1007425D02*
Y1001322D01*
G01X-784176Y1004355D02*
Y1002034D01*
G01X-784937Y1055285D02*
Y1047243D01*
G01X-784964Y1004355D02*
Y1002034D01*
G01X-785160Y1001322D02*
Y1007425D01*
G01X-785948Y1001322D02*
Y1007425D01*
G01X-786145Y1004355D02*
Y1002034D01*
G01X-786578Y1047243D02*
Y1055285D01*
G01X-786932Y1004355D02*
Y1002034D01*
G01X-787129Y1007425D02*
Y1001322D01*
G01X-787916D02*
Y1007425D01*
G01X-788113Y1004355D02*
Y1002034D01*
G01X-788901Y1004355D02*
Y1002034D01*
G01X-789098Y1007425D02*
Y1001322D01*
G01X-789885Y1007425D02*
Y1001322D01*
G01X-790082Y1004355D02*
Y1002034D01*
G01X-790187Y1055620D02*
Y1047243D01*
G01Y1057965D02*
Y1056960D01*
G01X-790869Y1004355D02*
Y1002034D01*
G01X-791066Y1001322D02*
Y1007425D01*
G01X-791827Y1047243D02*
Y1057965D01*
G01X-791853Y1007425D02*
Y1001322D01*
G01X-792050Y1004355D02*
Y1002034D01*
G01X-792838Y1004355D02*
Y1002034D01*
G01X-793035Y1001322D02*
Y1007425D01*
G01X-767221Y1057965D02*
X-766237Y1057630D01*
G01X-772470Y1057965D02*
X-771486Y1057630D01*
G01X-781985Y1057965D02*
X-781000Y1057630D01*
G01X-787234Y1057965D02*
X-786250Y1057630D01*
G01X-725800Y1026752D02*
X-725308Y1026585D01*
G01X-728425Y1026752D02*
X-727933Y1026585D01*
G01X-727113Y1025747D02*
X-727277Y1025412D01*
G01X-732690Y1022564D02*
X-732362Y1023234D01*
G01X-737611Y1027422D02*
X-737776Y1026920D01*
G01X-734167Y1028260D02*
X-734987Y1028427D01*
G01X-735807Y1022396D02*
X-734987Y1022229D01*
G01X-737283Y1028092D02*
X-737611Y1027422D01*
G01X-734003Y1029098D02*
X-734987Y1029265D01*
G01X-735971Y1021559D02*
X-734987Y1021391D01*
G01X-733674Y1022731D02*
X-733018Y1023736D01*
G01X-736299Y1027925D02*
X-736955Y1026920D01*
G01X-769846Y1055955D02*
X-770174Y1055285D01*
G01X-784609Y1055955D02*
X-784937Y1055285D01*
G01X-768533Y1057965D02*
X-767221D01*
G01X-773783D02*
X-772470D01*
G01X-777063D02*
X-775423D01*
G01X-783297D02*
X-781985D01*
G01X-788546D02*
X-787234D01*
G01X-791827D02*
X-790187D01*
G01X-787890Y1056625D02*
X-788546D01*
G01X-782641D02*
X-783625D01*
G01X-773126D02*
X-773783D01*
G01X-767877D02*
X-768861D01*
G01X-754649Y1053094D02*
X-715279D01*
G01X-790187Y1047243D02*
X-791827D01*
G01X-784937D02*
X-786578D01*
G01X-779688D02*
X-781328D01*
G01X-775423D02*
X-777063D01*
G01X-770174D02*
X-771814D01*
G01X-764924D02*
X-766565D01*
G01X-744173Y1029265D02*
X-743189D01*
G01X-749751D02*
X-748766D01*
G01X-721699Y1026752D02*
X-721043D01*
G01X-723340D02*
X-722520D01*
G01X-726457D02*
X-725800D01*
G01X-729081D02*
X-728425D01*
G01X-730722D02*
X-729902D01*
G01X-741877D02*
X-739252D01*
G01X-748766Y1026082D02*
X-744173D01*
G01X-739252D02*
X-741877D01*
G01X-728753D02*
X-729081D01*
G01X-726129D02*
X-726621D01*
G01X-721371D02*
X-721699D01*
G01X-744173Y1025077D02*
X-748766D01*
G01X-741877Y1024742D02*
X-739252D01*
G01Y1024072D02*
X-741877D01*
G01X-748766Y1021391D02*
X-749751D01*
G01X-743189D02*
X-744173D01*
G01X-729902D02*
X-730722D01*
G01X-727277D02*
X-728097D01*
G01X-724652D02*
X-725472D01*
G01X-722520D02*
X-723340D01*
G01X-722192Y1025914D02*
X-722520Y1025579D01*
G01Y1026249D02*
X-722192Y1026585D01*
G01X-726949Y1025914D02*
X-727113Y1025747D01*
G01X-727441Y1026082D02*
X-726949Y1026585D01*
G01X-733182Y1022061D02*
X-732690Y1022564D01*
G01X-729573Y1025914D02*
X-729902Y1025579D01*
G01Y1026249D02*
X-729573Y1026585D01*
G01X-715279Y1013724D02*
X-754649D01*
G01X-763507Y1007425D02*
X-762326D01*
G01X-765475D02*
X-764294D01*
G01X-775318D02*
X-774137D01*
G01X-785160D02*
X-783979D01*
G01X-791066D02*
X-789885D01*
G01X-793035D02*
X-791853D01*
G01X-787916D02*
X-789098D01*
G01X-785948D02*
X-787129D01*
G01X-780042D02*
X-781223D01*
G01X-782011D02*
X-783192D01*
G01X-778074D02*
X-779255D01*
G01X-776105D02*
X-777286D01*
G01X-760357D02*
X-761538D01*
G01X-758389D02*
X-759570D01*
G01X-756420D02*
X-757601D01*
G01X-755042Y1006736D02*
X-750318D01*
G01X-755042Y1006047D02*
X-750909D01*
G01X-792247Y1004552D02*
X-792641D01*
G01X-788310D02*
X-788704D01*
G01X-790279D02*
X-790672D01*
G01X-784373D02*
X-784767D01*
G01X-786342D02*
X-786735D01*
G01X-782405D02*
X-782798D01*
G01X-778468D02*
X-778861D01*
G01X-780436D02*
X-780830D01*
G01X-774531D02*
X-774924D01*
G01X-776499D02*
X-776893D01*
G01X-764688D02*
X-765082D01*
G01X-762720D02*
X-763113D01*
G01X-758783D02*
X-759176D01*
G01X-760751D02*
X-761145D01*
G01X-756814D02*
X-757208D01*
G01X-792050Y1002583D02*
X-792838D01*
G01X-788113D02*
X-788901D01*
G01X-790082D02*
X-790869D01*
G01X-784176D02*
X-784964D01*
G01X-786145D02*
X-786932D01*
G01X-782208D02*
X-782995D01*
G01X-778271D02*
X-779058D01*
G01X-780239D02*
X-781027D01*
G01X-774334D02*
X-775121D01*
G01X-776302D02*
X-777090D01*
G01X-764491D02*
X-765279D01*
G01X-760554D02*
X-761342D01*
G01X-762523D02*
X-763310D01*
G01X-758586D02*
X-759373D01*
G01X-756617D02*
X-757405D01*
G01Y1002034D02*
X-756617D01*
G01X-759373D02*
X-758586D01*
G01X-761342D02*
X-760554D01*
G01X-763310D02*
X-762523D01*
G01X-765279D02*
X-764491D01*
G01X-775121D02*
X-774334D01*
G01X-777090D02*
X-776302D01*
G01X-779058D02*
X-778271D01*
G01X-781027D02*
X-780239D01*
G01X-782995D02*
X-782208D01*
G01X-784964D02*
X-784176D01*
G01X-786932D02*
X-786145D01*
G01X-788901D02*
X-788113D01*
G01X-790869D02*
X-790082D01*
G01X-792838D02*
X-792050D01*
G01X-757601Y1001322D02*
X-756420D01*
G01X-759570D02*
X-758389D01*
G01X-761538D02*
X-760357D01*
G01X-777286D02*
X-776105D01*
G01X-779255D02*
X-778074D01*
G01X-781223D02*
X-780042D01*
G01X-783192D02*
X-782011D01*
G01X-787129D02*
X-785948D01*
G01X-789098D02*
X-787916D01*
G01X-791853D02*
X-793035D01*
G01X-789885D02*
X-791066D01*
G01X-783979D02*
X-785160D01*
G01X-774137D02*
X-775318D01*
G01X-764294D02*
X-765475D01*
G01X-762326D02*
X-763507D01*
G01X-757995Y999944D02*
X-759964D01*
G01X-752680D02*
X-753271D01*
G01X-750121D02*
X-751499D01*
G01X-752286Y996598D02*
X-754164D01*
G01X-736791Y1028595D02*
X-737283Y1028092D01*
G01X-734987Y1029265D02*
X-735971Y1029098D01*
G01X-734987Y1021391D02*
X-734003Y1021559D01*
G01X-734987Y1028427D02*
X-735807Y1028260D01*
G01X-734987Y1022229D02*
X-734167Y1022396D01*
G01X-769517Y1056290D02*
X-769846Y1055955D01*
G01X-770502Y1056625D02*
X-769517Y1057630D01*
G01X-774767Y1056290D02*
X-775423Y1055620D01*
G01Y1056960D02*
X-774767Y1057630D01*
G01X-784281Y1056290D02*
X-784609Y1055955D01*
G01X-785265Y1056625D02*
X-784281Y1057630D01*
G01X-789531Y1056290D02*
X-790187Y1055620D01*
G01Y1056960D02*
X-789531Y1057630D01*
G01X-734003Y1021559D02*
X-733182Y1022061D01*
G01X-735971Y1029098D02*
X-736791Y1028595D01*
G01X-734167Y1022396D02*
X-733674Y1022731D01*
G01X-735807Y1028260D02*
X-736299Y1027925D01*
G01X-726621Y1026082D02*
X-726949Y1025914D01*
G01X-721699Y1026082D02*
X-722192Y1025914D01*
G01Y1026585D02*
X-721699Y1026752D01*
G01X-726949Y1026585D02*
X-726457Y1026752D01*
G01X-729081Y1026082D02*
X-729573Y1025914D01*
G01Y1026585D02*
X-729081Y1026752D01*
G01X-768861Y1056625D02*
X-769517Y1056290D01*
G01X-783625Y1056625D02*
X-784281Y1056290D01*
G01X-769517Y1057630D02*
X-768533Y1057965D01*
G01X-773783Y1056625D02*
X-774767Y1056290D01*
G01Y1057630D02*
X-773783Y1057965D01*
G01X-784281Y1057630D02*
X-783297Y1057965D01*
G01X-788546Y1056625D02*
X-789531Y1056290D01*
G01Y1057630D02*
X-788546Y1057965D01*
G01X-751696Y1103291D02*
X-637916D01*
G01X-755633D02*
G03X-751696Y1107228I0J3937D01*
G01X-715279Y1079669D02*
G03I-6889J0D01*
G01X-751696Y1107228D02*
Y1233212D01*
G01Y1107228D02*
Y1233212D01*
G01X-715279Y1213527D02*
G03I-6889J0D01*
G01X-703468D02*
G03I-18700J0D01*
G01X-722168Y1217464D02*
Y1272188D01*
G01X-751696Y1237149D02*
Y1272188D01*
G01X-747759Y1237149D02*
G03X-751696Y1233212I0J-3937D01*
G01X-747759Y1237149D02*
G03X-751696Y1233212I0J-3937D01*
G01X-695074Y1237149D02*
X-747759D01*
G01X-695074D02*
X-747759D01*
G01X-711928Y-512081D02*
X-625635Y-613474D01*
G01X-678773Y-529335D02*
G03X-674836Y-525398I0J3937D01*
G01X-678773Y-529335D02*
G03X-674836Y-525398I0J3937D01*
G01D02*
Y194145D01*
G01Y-525398D02*
Y194145D01*
G01X-694521Y233602D02*
Y-529335D01*
G01D02*
X-678773D01*
G01X-708441Y-245474D02*
Y-225789D01*
G01X-710901Y-236260D02*
Y-245474D01*
G01Y-225789D02*
Y-233747D01*
G01X-708441Y-225789D02*
X-710901D01*
G01Y-245474D02*
X-708441D01*
G01X-686290Y-11634D02*
X-686038Y-12375D01*
G01X-686290Y-15585D02*
X-686038Y-16325D01*
G01X-685029Y-11634D02*
X-685281Y-11141D01*
G01X-685029Y-15585D02*
X-685281Y-15091D01*
G01X-678221Y-9413D02*
Y-8178D01*
G01Y-13363D02*
Y-12128D01*
G01Y-17313D02*
Y-16078D01*
G01X-685281Y-11141D02*
Y-10647D01*
G01Y-15091D02*
Y-14350D01*
G01X-686290Y-14597D02*
Y-15585D01*
G01Y-10647D02*
Y-11634D01*
G01Y-8178D02*
Y-9413D01*
G01X-684777Y-11881D02*
X-685029Y-11634D01*
G01X-686038Y-12375D02*
X-685281Y-13116D01*
G01X-684777Y-15832D02*
X-685029Y-15585D01*
G01X-686038Y-16325D02*
X-685533Y-16819D01*
G01X-686038Y-13856D02*
X-686290Y-14597D01*
G01X-685281Y-10647D02*
X-685029Y-9906D01*
G01X-686038D02*
X-686290Y-10647D01*
G01X-685281Y-14350D02*
X-685029Y-13856D01*
G01X-684273Y-12128D02*
X-684777Y-11881D01*
G01X-684273Y-16078D02*
X-684777Y-15832D01*
G01X-685533Y-16819D02*
X-684273Y-17313D01*
G01X-685029Y-13856D02*
X-684777Y-13610D01*
G01X-685281Y-13116D02*
X-686038Y-13856D01*
G01X-685029Y-9906D02*
X-684525Y-9413D01*
G01X-685533D02*
X-686038Y-9906D01*
G01X-684525Y-9413D02*
X-678221D01*
G01X-686290D02*
X-685533D01*
G01X-678221Y-12128D02*
X-684273D01*
G01Y-13363D02*
X-678221D01*
G01Y-16078D02*
X-684273D01*
G01Y-17313D02*
X-678221D01*
G01X-684777Y-13610D02*
X-684273Y-13363D01*
G01X-678474Y10832D02*
X-678221Y9351D01*
G01X-689820Y7869D02*
X-690072Y9351D01*
G01X-679734Y10585D02*
X-679482Y9351D01*
G01X-688559Y8116D02*
X-688811Y9351D01*
G01X-686290Y-525D02*
X-686038Y-1265D01*
G01X-686290Y-4475D02*
X-686038Y-5216D01*
G01X-685029Y-525D02*
X-685281Y-31D01*
G01X-685029Y-4475D02*
X-685281Y-3981D01*
G01X-679230Y12066D02*
X-678474Y10832D01*
G01X-689063Y6635D02*
X-689820Y7869D01*
G01X-680238Y11326D02*
X-679734Y10585D01*
G01X-688055Y7376D02*
X-688559Y8116D01*
G01X-678221Y30089D02*
Y31570D01*
G01Y21695D02*
Y23176D01*
G01Y1697D02*
Y2932D01*
G01Y-2253D02*
Y-1019D01*
G01Y-6203D02*
Y-4969D01*
G01X-682256Y15770D02*
Y19720D01*
G01X-683264D02*
Y15770D01*
G01X-683768Y23176D02*
Y30089D01*
G01X-685281Y15770D02*
Y19720D01*
G01Y-31D02*
Y463D01*
G01Y-3981D02*
Y-3240D01*
G01Y30089D02*
Y23176D01*
G01X-686290Y-3487D02*
Y-4475D01*
G01Y463D02*
Y-525D01*
G01Y2932D02*
Y1697D01*
G01Y19720D02*
Y15770D01*
G01X-690072Y23176D02*
Y21695D01*
G01Y31570D02*
Y30089D01*
G01X-679986Y12807D02*
X-679230Y12066D01*
G01X-688307Y5894D02*
X-689063Y6635D01*
G01X-684777Y-772D02*
X-685029Y-525D01*
G01X-686038Y-1265D02*
X-685281Y-2006D01*
G01X-684777Y-4722D02*
X-685029Y-4475D01*
G01X-686038Y-5216D02*
X-685533Y-5709D01*
G01X-679482Y9351D02*
X-679734Y8116D01*
G01X-688811Y9351D02*
X-688559Y10585D01*
G01X-678221Y9351D02*
X-678474Y7869D01*
G01X-690072Y9351D02*
X-689820Y10832D01*
G01X-681751Y12313D02*
X-680238Y11326D01*
G01X-686542Y6388D02*
X-688055Y7376D01*
G01X-686038Y-2747D02*
X-686290Y-3487D01*
G01X-685281Y463D02*
X-685029Y1203D01*
G01X-686038D02*
X-686290Y463D01*
G01X-680995Y13301D02*
X-679986Y12807D01*
G01X-687298Y5400D02*
X-688307Y5894D01*
G01X-684273Y-1019D02*
X-684777Y-772D01*
G01X-684273Y-4969D02*
X-684777Y-4722D01*
G01X-685281Y-3240D02*
X-685029Y-2747D01*
G01X-685533Y-5709D02*
X-684273Y-6203D01*
G01X-681751Y13548D02*
X-680995Y13301D01*
G01X-679734Y8116D02*
X-680238Y7376D01*
G01X-678474Y7869D02*
X-679230Y6635D01*
G01X-689820Y10832D02*
X-689063Y12066D01*
G01X-686542Y5154D02*
X-687298Y5400D01*
G01X-683012Y13794D02*
X-681751Y13548D01*
G01X-688559Y10585D02*
X-688055Y11326D01*
G01X-685281Y4907D02*
X-686542Y5154D01*
G01X-683264Y12560D02*
X-681751Y12313D01*
G01X-685029Y6141D02*
X-686542Y6388D01*
G01X-685029Y-2747D02*
X-684777Y-2500D01*
G01X-685281Y-2006D02*
X-686038Y-2747D01*
G01X-679230Y6635D02*
X-679986Y5894D01*
G01X-685029Y1203D02*
X-684525Y1697D01*
G01X-685533D02*
X-686038Y1203D01*
G01X-678221Y31570D02*
X-690072D01*
G01X-683768Y30089D02*
X-678221D01*
G01X-690072D02*
X-685281D01*
G01Y23176D02*
X-690072D01*
G01X-678221D02*
X-683768D01*
G01X-690072Y21695D02*
X-678221D01*
G01X-685281Y19720D02*
X-686290D01*
G01X-682256D02*
X-683264D01*
G01X-689063Y12066D02*
X-688307Y12807D01*
G01X-683264Y15770D02*
X-682256D01*
G01X-686290D02*
X-685281D01*
G01Y13794D02*
X-683012D01*
G01X-685029Y12560D02*
X-683264D01*
G01Y6141D02*
X-685029D01*
G01X-683012Y4907D02*
X-685281D01*
G01X-678221Y2932D02*
X-686290D01*
G01X-684525Y1697D02*
X-678221D01*
G01X-686290D02*
X-685533D01*
G01X-678221Y-1019D02*
X-684273D01*
G01Y-2253D02*
X-678221D01*
G01Y-4969D02*
X-684273D01*
G01Y-6203D02*
X-678221D01*
G01Y-8178D02*
X-686290D01*
G01X-680238Y7376D02*
X-681751Y6388D01*
G01X-688055Y11326D02*
X-686542Y12313D01*
G01D02*
X-685029Y12560D01*
G01X-681751Y6388D02*
X-683264Y6141D01*
G01X-686542Y13548D02*
X-685281Y13794D01*
G01X-681751Y5154D02*
X-683012Y4907D01*
G01X-684777Y-2500D02*
X-684273Y-2253D01*
G01X-679986Y5894D02*
X-680995Y5400D01*
G01X-688307Y12807D02*
X-687298Y13301D01*
G01X-680995Y5400D02*
X-681751Y5154D01*
G01X-687298Y13301D02*
X-686542Y13548D01*
G01X-674836Y194145D02*
G03X-675251Y195906I-3937J2D01*
G01X-674836Y194145D02*
G03X-675251Y195906I-3937J2D01*
G01X-693432Y232268D02*
X-675251Y195905D01*
G01X-693432Y232268D02*
X-675251Y195905D01*
G01X-693433Y232268D02*
G03X-694521Y233602I-3521J-1761D01*
G01X-693433Y232268D02*
G03X-696954Y234444I-3521J-1761D01*
G01X-652792Y414002D02*
X-366676D01*
G01X-655941D02*
X-652792D01*
G01X-711153Y489753D02*
X-655941Y414002D01*
G01X-716033Y499930D02*
X-648097Y445283D01*
G01X-672956Y473369D02*
Y432110D01*
G01X-676893Y473369D02*
G03X-672956Y477306I0J3937D01*
G01X-676893Y473369D02*
G03X-672956Y477306I0J3937D01*
G01D02*
Y1196849D01*
G01Y477306D02*
Y1196849D01*
G01X-692641Y1236307D02*
Y473369D01*
G01X-710357Y504865D02*
X-637916D01*
G01X-716844Y705804D02*
X-717008Y705469D01*
G01X-710948Y736165D02*
Y696795D01*
G01X-714384Y705469D02*
Y701449D01*
G01X-715204D02*
Y705469D01*
G01X-717008D02*
Y701449D01*
G01X-717829D02*
Y705469D01*
G01X-719633Y705637D02*
Y701449D01*
G01Y706810D02*
Y706307D01*
G01X-720453Y701449D02*
Y706810D01*
G01X-716680Y705972D02*
X-716844Y705804D01*
G01X-717172Y706139D02*
X-716680Y706642D01*
G01X-719305Y705972D02*
X-719633Y705637D01*
G01Y706307D02*
X-719305Y706642D01*
G01X-714712Y706307D02*
X-714384Y705469D01*
G01X-715204D02*
X-715368Y705804D01*
G01X-717829Y705469D02*
X-717993Y705804D01*
G01X-716352Y706139D02*
X-716680Y705972D01*
G01Y706642D02*
X-716188Y706810D01*
G01X-718813Y706139D02*
X-719305Y705972D01*
G01Y706642D02*
X-718813Y706810D01*
G01X-715040Y706642D02*
X-714712Y706307D01*
G01X-715368Y705804D02*
X-715532Y705972D01*
G01X-717665Y706642D02*
X-717172Y706139D01*
G01X-717993Y705804D02*
X-718157Y705972D01*
G01X-715532D02*
X-715860Y706139D01*
G01X-718157Y705972D02*
X-718485Y706139D01*
G01X-715532Y706810D02*
X-715040Y706642D01*
G01X-718157Y706810D02*
X-717665Y706642D01*
G01X-716188Y706810D02*
X-715532D01*
G01X-718813D02*
X-718157D01*
G01X-720453D02*
X-719633D01*
G01X-718485Y706139D02*
X-718813D01*
G01X-715860D02*
X-716352D01*
G01X-719633Y701449D02*
X-720453D01*
G01X-717008D02*
X-717829D01*
G01X-714384D02*
X-715204D01*
G01X-681383Y919573D02*
X-681102Y918748D01*
G01X-682224D02*
X-682505Y919573D01*
G01X-681383Y915176D02*
X-681102Y914352D01*
G01X-681383Y907208D02*
X-681102Y906384D01*
G01Y901987D02*
Y900888D01*
G01Y906384D02*
Y905285D01*
G01Y909131D02*
Y907758D01*
G01Y914352D02*
Y913253D01*
G01Y918748D02*
Y917649D01*
G01Y921496D02*
Y920122D01*
G01X-682224Y918199D02*
Y918748D01*
G01Y913802D02*
Y914627D01*
G01Y905834D02*
Y906384D01*
G01Y901438D02*
Y902262D01*
G01Y906384D02*
X-682505Y907208D01*
G01X-681383Y902812D02*
X-681102Y901987D01*
G01X-682224Y914627D02*
X-682505Y915176D01*
G01X-682224Y902262D02*
X-682505Y902812D01*
G01X-681102Y900888D02*
X-681383Y900064D01*
G01X-681102Y905285D02*
X-681383Y904460D01*
G01X-681102Y913253D02*
X-681383Y912429D01*
G01X-681102Y917649D02*
X-681383Y916825D01*
G01X-690082Y920122D02*
Y921496D01*
G01Y915726D02*
Y917100D01*
G01Y911330D02*
Y912703D01*
G01Y907758D02*
Y909131D01*
G01Y903361D02*
Y904735D01*
G01Y898965D02*
Y900339D01*
G01X-682505Y900888D02*
X-682224Y901438D01*
G01X-682505Y905285D02*
X-682224Y905834D01*
G01X-682505Y913253D02*
X-682224Y913802D01*
G01X-682505Y917649D02*
X-682224Y918199D01*
G01X-681944Y920122D02*
X-681383Y919573D01*
G01X-682505D02*
X-683066Y920122D01*
G01X-688959Y925618D02*
X-688117Y924793D01*
G01X-682224Y916001D02*
X-681383Y915176D01*
G01X-682505D02*
X-682786Y915451D01*
G01X-681944Y907758D02*
X-681383Y907208D01*
G01X-682505D02*
X-683066Y907758D01*
G01X-682224Y903636D02*
X-681383Y902812D01*
G01X-682505D02*
X-682786Y903086D01*
G01X-688117Y924793D02*
X-686995Y924244D01*
G01X-682786Y915451D02*
X-683347Y915726D01*
G01X-681383Y900064D02*
X-681944Y899514D01*
G01X-682786Y900614D02*
X-682505Y900888D01*
G01X-681383Y904460D02*
X-682224Y903636D01*
G01X-682786Y905010D02*
X-682505Y905285D01*
G01X-681383Y912429D02*
X-681944Y911879D01*
G01X-682786Y912978D02*
X-682505Y913253D01*
G01X-681383Y916825D02*
X-682224Y916001D01*
G01X-682786Y917374D02*
X-682505Y917649D01*
G01X-678857Y924793D02*
X-678015Y925618D01*
G01X-682786Y903086D02*
X-683347Y903361D01*
G01X-686995Y924244D02*
X-686153Y923969D01*
G01D02*
X-684750Y923694D01*
G01X-683347Y900339D02*
X-682786Y900614D01*
G01X-683347Y904735D02*
X-682786Y905010D01*
G01X-683347Y912703D02*
X-682786Y912978D01*
G01X-683347Y917100D02*
X-682786Y917374D01*
G01X-679980Y924244D02*
X-678857Y924793D01*
G01X-681944Y899514D02*
X-683347Y898965D01*
G01X-681944Y911879D02*
X-683347Y911330D01*
G01X-684750Y923694D02*
X-682224D01*
G01X-690082Y921496D02*
X-681102D01*
G01X-683066Y920122D02*
X-690082D01*
G01X-681102D02*
X-681944D01*
G01X-690082Y917100D02*
X-683347D01*
G01Y915726D02*
X-690082D01*
G01Y912703D02*
X-683347D01*
G01Y911330D02*
X-690082D01*
G01Y909131D02*
X-681102D01*
G01X-683066Y907758D02*
X-690082D01*
G01X-681102D02*
X-681944D01*
G01X-690082Y904735D02*
X-683347D01*
G01Y903361D02*
X-690082D01*
G01Y900339D02*
X-683347D01*
G01Y898965D02*
X-690082D01*
G01X-680821Y923969D02*
X-679980Y924244D01*
G01X-682224Y923694D02*
X-680821Y923969D01*
G01X-718231Y945810D02*
X-637916D01*
G01X-676893Y928640D02*
X-677173Y930289D01*
G01X-690082Y928640D02*
X-689801Y926991D01*
G01X-678296Y928640D02*
X-678576Y930014D01*
G01X-688679Y928640D02*
X-688398Y927266D01*
G01X-676893Y944027D02*
Y942379D01*
G01Y953369D02*
Y951721D01*
G01X-681102Y940180D02*
Y935784D01*
G01X-682224D02*
Y940180D01*
G01Y951721D02*
Y944027D01*
G01X-683908D02*
Y951721D01*
G01X-684469Y940180D02*
Y935784D01*
G01X-685592D02*
Y940180D01*
G01X-677173Y930289D02*
X-678015Y931663D01*
G01X-689801Y926991D02*
X-688959Y925618D01*
G01X-678576Y930014D02*
X-679138Y930838D01*
G01X-688398Y927266D02*
X-687837Y926442D01*
G01X-678576Y927266D02*
X-678296Y928640D01*
G01X-688398Y930014D02*
X-688679Y928640D01*
G01X-677173Y926991D02*
X-676893Y928640D01*
G01X-689801Y930289D02*
X-690082Y928640D01*
G01Y951721D02*
Y953369D01*
G01Y942379D02*
Y944027D01*
G01X-678015Y931663D02*
X-678857Y932487D01*
G01X-679138Y926442D02*
X-678576Y927266D01*
G01X-678015Y925618D02*
X-677173Y926991D01*
G01X-688959Y931663D02*
X-689801Y930289D01*
G01X-679138Y930838D02*
X-680821Y931937D01*
G01X-687837Y926442D02*
X-686153Y925343D01*
G01X-687837Y930838D02*
X-688398Y930014D01*
G01X-678857Y932487D02*
X-679980Y933036D01*
G01X-688117Y932487D02*
X-688959Y931663D01*
G01X-679980Y933036D02*
X-680821Y933311D01*
G01D02*
X-682224Y933586D01*
G01X-680821Y925343D02*
X-679138Y926442D01*
G01X-686153Y931937D02*
X-687837Y930838D01*
G01X-680821Y931937D02*
X-682505Y932212D01*
G01X-686153Y925343D02*
X-684469Y925068D01*
G01X-690082Y953369D02*
X-676893D01*
G01X-683908Y951721D02*
X-690082D01*
G01X-676893D02*
X-682224D01*
G01Y944027D02*
X-676893D01*
G01X-690082D02*
X-683908D01*
G01X-676893Y942379D02*
X-690082D01*
G01X-682224Y940180D02*
X-681102D01*
G01X-685592D02*
X-684469D01*
G01X-686995Y933036D02*
X-688117Y932487D01*
G01X-684469Y935784D02*
X-685592D01*
G01X-681102D02*
X-682224D01*
G01Y933586D02*
X-684750D01*
G01X-682505Y932212D02*
X-684469D01*
G01Y925068D02*
X-682505D01*
G01X-686153Y933311D02*
X-686995Y933036D01*
G01X-684469Y932212D02*
X-686153Y931937D01*
G01X-682505Y925068D02*
X-680821Y925343D01*
G01X-684750Y933586D02*
X-686153Y933311D01*
G01X-717598Y1026249D02*
X-717270Y1025412D01*
G01X-718090D02*
X-718255Y1025747D01*
G01X-720715Y1025412D02*
X-720879Y1025747D01*
G01X-717926Y1026585D02*
X-717598Y1026249D01*
G01X-718255Y1025747D02*
X-718419Y1025914D01*
G01X-720551Y1026585D02*
X-720059Y1026082D01*
G01X-720879Y1025747D02*
X-721043Y1025914D01*
G01X-714019Y1003330D02*
Y1062837D01*
G01X-715279Y1053094D02*
Y1013724D01*
G01X-717270Y1025412D02*
Y1021391D01*
G01X-718090D02*
Y1025412D01*
G01X-719895D02*
Y1021391D01*
G01X-720715D02*
Y1025412D01*
G01X-718419Y1025914D02*
X-718747Y1026082D01*
G01X-718419Y1026752D02*
X-717926Y1026585D01*
G01X-721043Y1026752D02*
X-720551Y1026585D01*
G01X-719731Y1025747D02*
X-719895Y1025412D01*
G01X-719075Y1026752D02*
X-718419D01*
G01X-718747Y1026082D02*
X-719239D01*
G01X-719895Y1021391D02*
X-720715D01*
G01X-717270D02*
X-718090D01*
G01X-719567Y1025914D02*
X-719731Y1025747D01*
G01X-720059Y1026082D02*
X-719567Y1026585D01*
G01X-719239Y1026082D02*
X-719567Y1025914D01*
G01Y1026585D02*
X-719075Y1026752D01*
G01X-718231Y1079669D02*
X-637916D01*
G01X-714019Y1096500D02*
Y1196695D01*
G01X-672956Y1196849D02*
G03X-673372Y1198610I-3937J0D01*
G01X-672956Y1196849D02*
G03X-673372Y1198610I-3937J0D01*
G01X-673371D02*
X-691553Y1234973D01*
G01D02*
X-673371Y1198610D01*
G01X-718231Y1213527D02*
X-635637D01*
G01X-691553Y1234973D02*
G03X-695074Y1237149I-3521J-1761D01*
G01X-691553Y1234973D02*
G03X-695074Y1237149I-3521J-1761D01*
G01X-714019Y1230359D02*
Y1237149D01*
G01X-579314Y-714465D02*
Y-733402D01*
G01X-622486Y-613474D02*
X-336370D01*
G01X-625635D02*
X-622486D01*
G01X-644948Y445283D02*
X-545919D01*
G01X-648097D02*
X-644948D01*
G01X-639037Y616661D02*
X-627226D01*
G01X-639037D02*
X-627226D01*
G01X-639037D02*
X-627226D01*
G01X-579314Y1463291D02*
Y1444354D01*
G01X-359645Y-714465D02*
Y-733402D01*
G01Y1463291D02*
Y1444354D01*
G01X-139975Y-714465D02*
Y-733402D01*
G01Y1463291D02*
Y1444354D01*
G01X3691Y0D02*
X-52513D01*
G01X21873Y763780D02*
X-52513D01*
G01X34426Y32177D02*
X34548Y32097D01*
G01X34329Y32291D02*
X34426Y32177D01*
G01X60620Y26877D02*
X60748Y26646D01*
G01X60498Y27137D02*
X60620Y26877D01*
G01X60399Y27433D02*
X60498Y27137D01*
G01X60623Y26882D02*
X60748Y26646D01*
G01X60496Y27132D02*
X60623Y26882D01*
G01X60399Y27433D02*
X60496Y27132D01*
G01X33154Y30468D02*
X33157Y30540D01*
G01X33154Y30355D02*
Y30468D01*
G01X33157Y30212D02*
X33154Y30355D01*
G01X35799Y30975D02*
X35827Y30698D01*
G01X35717Y31236D02*
X35799Y30975D01*
G01X35586Y31476D02*
X35717Y31236D01*
G01X35411Y31685D02*
X35586Y31476D01*
G01X35197Y31855D02*
X35411Y31685D01*
G01X34953Y31980D02*
X35197Y31855D01*
G01X34679Y32056D02*
X34953Y31980D01*
G01X35042Y31942D02*
X34548Y32097D01*
G01X35368Y31725D02*
X35042Y31942D01*
G01X35619Y31426D02*
X35368Y31725D01*
G01X35776Y31069D02*
X35619Y31426D01*
G01X35827Y30698D02*
X35776Y31069D01*
G01X34271Y32425D02*
X34329Y32291D01*
G01X34252Y32561D02*
X34271Y32425D01*
G01X60718Y30137D02*
X60723Y30023D01*
G01X60714Y30246D02*
X60718Y30137D01*
G01X59812Y31843D02*
X59810Y32030D01*
G01Y31679D02*
X59812Y31843D01*
G01X50059Y15313D02*
X50028Y15552D01*
G01X50157Y15077D02*
X50059Y15313D01*
G01X50327Y14861D02*
X50157Y15077D01*
G01X50539Y14703D02*
X50327Y14861D01*
G01X50772Y14606D02*
X50539Y14703D01*
G01X51056Y14567D02*
X50772Y14606D01*
G01X35718Y31078D02*
X35799Y30894D01*
G01X35583Y31251D02*
X35718Y31078D01*
G01X35406Y31398D02*
X35583Y31251D01*
G01X35187Y31520D02*
X35406Y31398D01*
G01X34943Y31607D02*
X35187Y31520D01*
G01X34679Y31658D02*
X34943Y31607D01*
G01X32701Y30922D02*
X32678Y31076D01*
G01X32770Y30782D02*
X32701Y30922D01*
G01X32879Y30669D02*
X32770Y30782D01*
G01X33014Y30595D02*
X32879Y30669D01*
G01X33164Y30565D02*
X33014Y30595D01*
G01X61332Y30212D02*
X61325Y30054D01*
G01X61335Y30354D02*
X61332Y30212D01*
G01X60718Y30521D02*
X60723Y30535D01*
G01X60714Y30483D02*
X60718Y30521D01*
G01X60713Y30422D02*
X60714Y30483D01*
G01X61332Y30540D02*
X61325Y30565D01*
G01X61335Y30468D02*
X61332Y30540D01*
G01X61335Y30355D02*
Y30468D01*
G01X61332Y30212D02*
X61335Y30355D01*
G01X61325Y30054D02*
X61332Y30212D01*
G01X50038Y15416D02*
X50028Y15552D01*
G01X50068Y15283D02*
X50038Y15416D01*
G01X50117Y15154D02*
X50068Y15283D01*
G01X50185Y15032D02*
X50117Y15154D01*
G01X50272Y14919D02*
X50185Y15032D01*
G01X50375Y14817D02*
X50272Y14919D01*
G01X50493Y14730D02*
X50375Y14817D01*
G01X50623Y14660D02*
X50493Y14730D01*
G01X50763Y14609D02*
X50623Y14660D01*
G01X50908Y14578D02*
X50763Y14609D01*
G01X51056Y14567D02*
X50908Y14578D01*
G01X61613Y30671D02*
X61478Y30596D01*
G01X61720Y30784D02*
X61613Y30671D01*
G01X61788Y30923D02*
X61720Y30784D01*
G01X61811Y31076D02*
X61788Y30923D01*
G01X60568Y30502D02*
X60723Y30535D01*
G01X60433Y30427D02*
X60568Y30502D01*
G01X60329Y30317D02*
X60433Y30427D01*
G01X60261Y30178D02*
X60329Y30317D01*
G01X60237Y30023D02*
X60261Y30178D01*
G01X33157Y30212D02*
X33164Y30054D01*
G01X33154Y30355D02*
X33157Y30212D01*
G01X33154Y30468D02*
Y30355D01*
G01X33157Y30540D02*
X33154Y30468D01*
G01X33164Y30565D02*
X33157Y30540D01*
G01X44451Y15416D02*
X44461Y15552D01*
G01X44421Y15283D02*
X44451Y15416D01*
G01X44372Y15154D02*
X44421Y15283D01*
G01X44304Y15032D02*
X44372Y15154D01*
G01X44217Y14919D02*
X44304Y15032D01*
G01X44114Y14817D02*
X44217Y14919D01*
G01X43996Y14730D02*
X44114Y14817D01*
G01X43866Y14660D02*
X43996Y14730D01*
G01X43726Y14609D02*
X43866Y14660D01*
G01X43580Y14578D02*
X43726Y14609D01*
G01X43432Y14567D02*
X43580Y14578D01*
G01X60240Y26646D02*
X60237D01*
G01X60251Y26645D02*
X60240Y26646D01*
G01X60268D02*
X60251Y26645D01*
G01X33866Y26882D02*
X33741Y26646D01*
G01X33992Y27131D02*
X33866Y26882D01*
G01X34090Y27433D02*
X33992Y27131D01*
G01X33869Y26877D02*
X33741Y26646D01*
G01X33991Y27138D02*
X33869Y26877D01*
G01X34090Y27433D02*
X33991Y27138D01*
G01X44429Y15313D02*
X44461Y15552D01*
G01X44331Y15077D02*
X44429Y15313D01*
G01X44162Y14861D02*
X44331Y15077D01*
G01X43950Y14703D02*
X44162Y14861D01*
G01X43716Y14606D02*
X43950Y14703D01*
G01X43432Y14567D02*
X43716Y14606D01*
G01X60252Y30147D02*
X60237Y30023D01*
G01X60299Y30268D02*
X60252Y30147D01*
G01X60377Y30375D02*
X60299Y30268D01*
G01X60480Y30459D02*
X60377Y30375D01*
G01X60599Y30513D02*
X60480Y30459D01*
G01X60723Y30535D02*
X60599Y30513D01*
G01X34196Y30446D02*
X34130Y30378D01*
G01X34240Y30493D02*
X34196Y30446D01*
G01X34252Y30510D02*
X34240Y30493D01*
G01D02*
X34195Y30444D01*
G01X34252Y30509D02*
X34240Y30493D01*
G01X34238Y30490D02*
X34253Y30510D01*
G01X34179Y30427D02*
X34238Y30490D01*
G01X34029Y30277D02*
X34130Y30378D01*
G01X33915Y30167D02*
X34029Y30277D01*
G01X51933Y15062D02*
X52033Y15302D01*
G01X51774Y14858D02*
X51933Y15062D01*
G01X51562Y14699D02*
X51774Y14858D01*
G01X59067Y31005D02*
X59041Y30698D01*
G01X59140Y31295D02*
X59067Y31005D01*
G01X59258Y31555D02*
X59140Y31295D01*
G01X59416Y31773D02*
X59258Y31555D01*
G01X59604Y31937D02*
X59416Y31773D01*
G01X59810Y32039D02*
X59604Y31937D01*
G01X58711Y31064D02*
X58662Y30698D01*
G01X58868Y31423D02*
X58711Y31064D01*
G01X59121Y31725D02*
X58868Y31423D01*
G01X59452Y31944D02*
X59121Y31725D01*
G01X59810Y32056D02*
X59452Y31944D01*
G01X60723Y30535D02*
G03X60237Y30023I26J-511D01*
G01X61325Y30565D02*
G03X61811Y31076I-26J511D01*
G01X39770Y22080D02*
G03X54561I7395J88629D01*
G01X39750Y21845D02*
G03X54581I7415J88864D01*
G01X59810Y32056D02*
G03X60237Y32561I-85J505D01*
G01X32678Y31076D02*
G03X33164Y30565I512J0D01*
G01X34252Y32561D02*
G03X34679Y32056I512J0D01*
G01X59810D02*
G03X58662Y30698I229J-1358D01*
G01X35827D02*
G03X34679Y32056I-1377J0D01*
G01X50197Y19292D02*
G03X48229Y21260I-1968J0D01*
G01X46260D02*
G03X44292Y19292I0J-1968D01*
G01X39207Y22157D02*
G03X39775Y22079I1001J5180D01*
G01X54557D02*
G03X55125Y22157I-433J5258D01*
G01X54576Y21843D02*
G03X55170Y21925I-456J5493D01*
G01X39162D02*
G03X39755Y21843I1050J5411D01*
G01X45197Y22835D02*
G03X45346Y22794I1955J6812D01*
G01X48986D02*
G03X49120Y22831I-1819J6849D01*
G01X34252Y16536D02*
G03X34646Y16142I394J0D01*
G01X59843D02*
G03X60237Y16536I0J394D01*
G01X41069Y2508D02*
G03X42052Y1575I983J51D01*
G01X52437D02*
G03X53420Y2508I0J984D01*
G01X38862Y12993D02*
G03X40232Y14226I0J1378D01*
G01X37170D02*
G03X38541Y12993I1370J145D01*
G01X55791D02*
G03X57161Y14226I0J1378D01*
G01X54099D02*
G03X55470Y12993I1370J145D01*
G01X32678Y16536D02*
G03X34646Y14567I1969J0D01*
G01X59843D02*
G03X61811Y16536I0J1968D01*
G01X0Y3937D02*
G03X3937Y0I3937J0D01*
G01X56356Y21567D02*
X56515Y21621D01*
G01X46252Y20865D02*
X46411Y20919D01*
G01X41438Y20865D02*
X41596Y20919D01*
G01X33535Y34729D02*
X33964Y34875D01*
G01X59719Y16221D02*
X59877Y16281D01*
G01X58334Y16221D02*
X58491Y16281D01*
G01X59562Y18018D02*
X59404Y17958D01*
G01X54491Y16221D02*
X54649Y16281D01*
G01X58176Y18018D02*
X58019Y17958D01*
G01X53106Y16221D02*
X53263Y16281D01*
G01X59562Y19036D02*
X59404Y18976D01*
G01X51720Y16221D02*
X51877Y16281D01*
G01X58176Y19036D02*
X58019Y18976D01*
G01X54334Y18018D02*
X54176Y17958D01*
G01X52948Y18018D02*
X52791Y17958D01*
G01X54334Y19036D02*
X54176Y18976D01*
G01X51531Y18018D02*
X51373Y17958D01*
G01X52948Y19036D02*
X52791Y18976D01*
G01X41862Y16520D02*
X42020Y16580D01*
G01X40476Y16221D02*
X40634Y16281D01*
G01X36886Y16221D02*
X37043Y16281D01*
G01X40319Y18018D02*
X40161Y17958D01*
G01X41705Y18736D02*
X41547Y18676D01*
G01X34146Y16281D02*
X33989Y16221D01*
G01X40319Y19036D02*
X40161Y18976D01*
G01X51319Y14601D02*
X51564Y14700D01*
G01X54794Y16142D02*
X54218Y15891D01*
G01X53946Y15771D02*
X53953Y15775D01*
G01X53947Y15772D02*
X54474Y16003D01*
G01X37541Y16002D02*
X37865Y16142D01*
G01D02*
X37289Y15891D01*
G01X37525Y15995D02*
X37018Y15772D01*
G01X53947D02*
X53951Y15774D01*
G01X37018Y15772D02*
X37022Y15774D01*
G01X51846Y16580D02*
X51720Y16520D01*
G01X51405Y17658D02*
X51531Y17718D01*
G01X42020Y16281D02*
X41894Y16221D01*
G01X37012Y16640D02*
X36886Y16580D01*
G01X34114Y16640D02*
X33989Y16580D01*
G01X36697Y19036D02*
X36571Y18976D01*
G01X34295Y16357D02*
X32892Y15643D01*
G01X57097Y19460D02*
X57309Y19568D01*
G01X54981D02*
X54769Y19460D01*
G01X56304Y21891D02*
X56092Y21783D01*
G01X53553D02*
X53764Y21891D01*
G01X49109Y19568D02*
X48897Y19460D01*
G01X46463Y20649D02*
X46675Y20757D01*
G01X47733Y21783D02*
X47945Y21891D01*
G01X55260Y26293D02*
X55578Y26455D01*
G01X38581Y19568D02*
X38369Y19460D01*
G01X34251Y33047D02*
X33964Y32900D01*
G01Y33266D02*
X34108Y33339D01*
G01X32532Y36045D02*
X32819Y36191D01*
G01X59751Y16520D02*
X59845Y16580D01*
G01X58365Y16520D02*
X58460Y16580D01*
G01X59530Y17718D02*
X59436Y17658D01*
G01X58145Y17718D02*
X58050Y17658D01*
G01X59436Y18676D02*
X59530Y18736D01*
G01X58050Y18676D02*
X58145Y18736D01*
G01X54523Y16520D02*
X54617Y16580D01*
G01X53137Y16520D02*
X53231Y16580D01*
G01X54302Y17718D02*
X54208Y17658D01*
G01X52917Y17718D02*
X52822Y17658D01*
G01X54208Y18676D02*
X54302Y18736D01*
G01X52822Y18676D02*
X52917Y18736D01*
G01X49862Y17838D02*
X49956Y17898D01*
G01X40508Y16520D02*
X40602Y16580D01*
G01X41831Y17778D02*
X42020Y17898D01*
G01X40287Y17718D02*
X40193Y17658D01*
G01Y18676D02*
X40287Y18736D01*
G01X36603Y18617D02*
X36697Y18676D01*
G01X57203Y19892D02*
X57044Y19784D01*
G01X54716D02*
X54875Y19892D01*
G01X56198Y21459D02*
X56356Y21567D01*
G01X53817D02*
X53658Y21459D01*
G01X49003Y19892D02*
X48844Y19784D01*
G01X55657Y26049D02*
X55419Y25887D01*
G01X47839Y21459D02*
X47998Y21567D01*
G01X38475Y19892D02*
X38316Y19784D01*
G01X34466Y33193D02*
X34251Y33047D01*
G01X32890Y35825D02*
X32676Y35679D01*
G01X41861Y20757D02*
X41649Y20595D01*
G01X34394Y34802D02*
X34108Y34582D01*
G01X57404Y24914D02*
X55419Y23130D01*
G01X54784D02*
X57007Y25157D01*
G01X49988Y17598D02*
X50114Y17718D01*
G01X42146Y16401D02*
X42020Y16281D01*
G01Y16580D02*
X42083Y16640D01*
G01X41390Y18856D02*
X41516Y18976D01*
G01X37043Y16281D02*
X37169Y16401D01*
G01X34272D02*
X34146Y16281D01*
G01X36571Y18976D02*
X36445Y18856D01*
G01X33766Y30023D02*
X33940Y30191D01*
G01X34076Y30324D02*
X33918Y30169D01*
G01X34076Y30324D02*
X34197Y30445D01*
G01X57309Y19568D02*
X57520Y19784D01*
G01X55193D02*
X54981Y19568D01*
G01X56092Y21783D02*
X55880Y21567D01*
G01X53341D02*
X53553Y21783D01*
G01X49320Y19784D02*
X49109Y19568D01*
G01X54943Y25968D02*
X55260Y26293D01*
G01X47522Y21567D02*
X47733Y21783D01*
G01X46411Y20919D02*
X46516Y21027D01*
G01X41596Y20919D02*
X41702Y21027D01*
G01X38792Y19784D02*
X38581Y19568D01*
G01X34108Y33339D02*
X34251Y33485D01*
G01X33964Y34875D02*
X34108Y35021D01*
G01X32246Y35752D02*
X32532Y36045D01*
G01X59877Y16281D02*
X60034Y16460D01*
G01X58491Y16281D02*
X58648Y16460D01*
G01X59404Y18976D02*
X59247Y18796D01*
G01X58019Y18976D02*
X57861Y18796D01*
G01X54649Y16281D02*
X54806Y16460D01*
G01X53263Y16281D02*
X53420Y16460D01*
G01X51877Y16281D02*
X52035Y16460D01*
G01X54176Y18976D02*
X54019Y18796D01*
G01X52791Y18976D02*
X52633Y18796D01*
G01X51373Y17958D02*
X51216Y17778D01*
G01X34197Y30445D02*
X34241Y30494D01*
G01X40634Y16281D02*
X40791Y16460D01*
G01X40161Y18976D02*
X40004Y18796D01*
G01X60080Y34290D02*
X61298Y35679D01*
G01X59579Y34290D02*
X61298Y36264D01*
G01X38292Y25887D02*
X37815Y25320D01*
G01Y25968D02*
X38292Y26536D01*
G01X59845Y16580D02*
X59940Y16700D01*
G01X59436Y17658D02*
X59341Y17539D01*
G01X58460Y16580D02*
X58554Y16700D01*
G01X59404Y17958D02*
X59215Y17718D01*
G01X59341Y18557D02*
X59436Y18676D01*
G01X58050Y17658D02*
X57956Y17539D01*
G01X58019Y17958D02*
X57830Y17718D01*
G01X57956Y18557D02*
X58050Y18676D01*
G01X54617Y16580D02*
X54712Y16700D01*
G01X54208Y17658D02*
X54113Y17539D01*
G01X53231Y16580D02*
X53326Y16700D01*
G01X54176Y17958D02*
X53987Y17718D01*
G01X54113Y18557D02*
X54208Y18676D01*
G01X52822Y17658D02*
X52728Y17539D01*
G01X51940Y16700D02*
X51846Y16580D01*
G01X52791Y17958D02*
X52602Y17718D01*
G01X52728Y18557D02*
X52822Y18676D01*
G01X42240Y16520D02*
X42146Y16401D01*
G01X40602Y16580D02*
X40697Y16700D01*
G01X41547Y18676D02*
X41453Y18557D01*
G01X40193Y17658D02*
X40098Y17539D01*
G01X40161Y17958D02*
X39972Y17718D01*
G01X40098Y18557D02*
X40193Y18676D01*
G01X37106Y16760D02*
X37012Y16640D01*
G01X36508Y18497D02*
X36603Y18617D01*
G01X34209Y16760D02*
X34114Y16640D01*
G01X32819Y27433D02*
X32740Y27334D01*
G01X42020Y20973D02*
X41861Y20757D01*
G01X46675D02*
X46834Y20973D01*
G01X51279Y17479D02*
X51405Y17658D01*
G01X42209Y17838D02*
X42083Y17658D01*
G01X57309Y20054D02*
X57203Y19892D01*
G01X57563Y25157D02*
X57404Y24914D01*
G01X53658Y21459D02*
X53553Y21297D01*
G01X55419Y25887D02*
X55260Y25644D01*
G01X49109Y20054D02*
X49003Y19892D01*
G01X47733Y21297D02*
X47839Y21459D01*
G01X38581Y20054D02*
X38475Y19892D01*
G01X34609Y33412D02*
X34466Y33193D01*
G01X34537Y35021D02*
X34394Y34802D01*
G01X32676Y35679D02*
X32532Y35460D01*
G01X57985Y27559D02*
X57304Y26378D01*
G01X40269Y27559D02*
X39587Y26378D01*
G01X59341Y17539D02*
X59278Y17419D01*
G01X57956Y17539D02*
X57893Y17419D01*
G01X54113Y17539D02*
X54050Y17419D01*
G01X52728Y17539D02*
X52665Y17419D01*
G01X33964Y32900D02*
X33678Y32827D01*
G01X32742Y27336D02*
X32693Y27249D01*
G01X49956Y17898D02*
X50019Y18018D01*
G01X42996Y17598D02*
X42775Y17179D01*
G01X42083Y16640D02*
X42146Y16760D01*
G01X42020Y17898D02*
X42083Y18018D01*
G01X41264Y18617D02*
X41390Y18856D01*
G01X40098Y17539D02*
X40035Y17419D01*
G01X37169Y16401D02*
X37295Y16640D01*
G01X36445Y18856D02*
X36319Y18617D01*
G01X34398Y16640D02*
X34272Y16401D01*
G01X42775Y17658D02*
X43468Y19036D01*
G01X43720D02*
X43153Y17898D01*
G01X57520Y19784D02*
X57626Y20000D01*
G01X57007Y25157D02*
X57166Y25482D01*
G01X53235Y21351D02*
X53341Y21567D01*
G01X49426Y20000D02*
X49320Y19784D01*
G01X47416Y21351D02*
X47522Y21567D01*
G01X38898Y20000D02*
X38792Y19784D01*
G01X34251Y33485D02*
X34322Y33632D01*
G01X34108Y35021D02*
X34251Y35314D01*
G01X57008Y22525D02*
X55124Y22158D01*
G01X55169Y21926D02*
X57008Y22284D01*
G01X33248Y35899D02*
X32890Y35825D01*
G01X33606Y33193D02*
X33964Y33266D01*
G01X56054Y26130D02*
X55657Y26049D01*
G01X47945Y21891D02*
X48209Y21945D01*
G01X41649Y20595D02*
X41385Y20541D01*
G01X38369Y19460D02*
X38105Y19406D01*
G01X53764Y21891D02*
X54029Y21945D01*
G01X48897Y19460D02*
X48632Y19406D01*
G01X54769Y19460D02*
X54505Y19406D01*
G01X56833D02*
X57097Y19460D01*
G01X48324Y22673D02*
X48925Y22796D01*
G01X61478Y30596D02*
X61325Y30565D01*
G01X38316Y19784D02*
X38105Y19730D01*
G01X47998Y21567D02*
X48209Y21621D01*
G01X54029D02*
X53817Y21567D01*
G01X56515Y21945D02*
X56304Y21891D01*
G01X48844Y19784D02*
X48632Y19730D01*
G01X54505D02*
X54716Y19784D01*
G01X57044D02*
X56833Y19730D01*
G01X41516Y18976D02*
X41736Y19036D01*
G01X60034Y16460D02*
X60129Y16700D01*
G01X58648Y16460D02*
X58743Y16700D01*
G01X59247Y18796D02*
X59152Y18557D01*
G01X57861Y18796D02*
X57767Y18557D01*
G01X54806Y16460D02*
X54901Y16700D01*
G01X53420Y16460D02*
X53515Y16700D01*
G01X54019Y18796D02*
X53924Y18557D01*
G01X52035Y16460D02*
X52129Y16700D01*
G01X52633Y18796D02*
X52539Y18557D01*
G01X50114Y17718D02*
X50208Y17958D01*
G01X40791Y16460D02*
X40886Y16700D01*
G01X40004Y18796D02*
X39909Y18557D01*
G01X50709Y22599D02*
X50591Y22284D01*
G01X59940Y16700D02*
X60003Y16880D01*
G01X59278Y18377D02*
X59341Y18557D01*
G01X58554Y16700D02*
X58617Y16880D01*
G01X57893Y18377D02*
X57956Y18557D01*
G01X54712Y16700D02*
X54775Y16880D01*
G01X54050Y18377D02*
X54113Y18557D01*
G01X53326Y16700D02*
X53389Y16880D01*
G01X52665Y18377D02*
X52728Y18557D01*
G01X52003Y16880D02*
X51940Y16700D01*
G01X56145Y21297D02*
X56198Y21459D01*
G01X47740Y22603D02*
X48351Y22677D01*
G01X51322Y14602D02*
X51056Y14567D01*
G01X32819Y36191D02*
X33320Y36264D01*
G01X55578Y26455D02*
X56134Y26536D01*
G01X42303Y16700D02*
X42240Y16520D01*
G01X42271Y18018D02*
X42209Y17838D01*
G01X41453Y18557D02*
X41390Y18377D01*
G01X40697Y16700D02*
X40760Y16880D01*
G01X40035Y18377D02*
X40098Y18557D01*
G01X37169Y16940D02*
X37106Y16760D01*
G01X34272Y16940D02*
X34209Y16760D01*
G01X54875Y19892D02*
X54928Y20054D01*
G01X46834Y20973D02*
X46887Y21135D01*
G01X46516Y21027D02*
X46569Y21189D01*
G01X42072Y21135D02*
X42020Y20973D01*
G01X41702Y21027D02*
X41755Y21189D01*
G01X34680Y33632D02*
X34609Y33412D01*
G01X48822Y18317D02*
X48413Y16820D01*
G01X48318Y16940D02*
X48728Y18437D01*
G01X42146Y16760D02*
X42177Y16880D01*
G01X42083Y18018D02*
X42146Y18257D01*
G01X57420Y18736D02*
X56790Y16221D01*
G01X56601D02*
X57231Y18736D01*
G01X57642Y25482D02*
X57563Y25157D01*
G01X55880Y21567D02*
X55827Y21351D01*
G01X54863Y25644D02*
X54943Y25968D01*
G01X53553Y21297D02*
X53500Y21081D01*
G01X32678Y40355D02*
X34252D01*
G01X61811D02*
X60237D01*
G01X34252Y40150D02*
X32678D01*
G01X61811D02*
X60237D01*
G01X32678Y39174D02*
X34252D01*
G01X61811D02*
X60237D01*
G01X32678Y38969D02*
X34252D01*
G01X61811D02*
X60237D01*
G01X61298Y36264D02*
X61727D01*
G01X33320D02*
X33463D01*
G01X33535Y35899D02*
X33248D01*
G01X34252Y35622D02*
X32678D01*
G01X61811D02*
X60237D01*
G01X32532Y35460D02*
X32174D01*
G01X60237Y35005D02*
X61811D01*
G01X34252D02*
X32678D01*
G01X33248Y34729D02*
X33535D01*
G01Y34436D02*
X33248D01*
G01X61727Y34290D02*
X62443D01*
G01X61298D02*
X60080D01*
G01X34252Y34244D02*
X32678D01*
G01X61811D02*
X60237D01*
G01X62443Y33851D02*
X61727D01*
G01X61298D02*
X59579D01*
G01X32103Y33632D02*
X32461D01*
G01X60237Y33484D02*
X61811D01*
G01X32678D02*
X34252D01*
G01X33177Y33193D02*
X33606D01*
G01X60237Y32866D02*
X61811D01*
G01X34252D02*
X32678D01*
G01X33678Y32827D02*
X33105D01*
G01X61727D02*
X61298D01*
G01X34252Y30698D02*
X35827D01*
G01X60237D02*
X58662D01*
G01X32678Y30307D02*
X34252D01*
G01X61811D02*
X60237D01*
G01X61325Y30054D02*
X61811D01*
G01X33164D02*
X32678D01*
G01X60723Y30023D02*
X60237D01*
G01Y29741D02*
X61811D01*
G01X32678D02*
X34252D01*
G01X35748Y29134D02*
X43229D01*
G01X58583D02*
X51103D01*
G01Y28347D02*
X43229D01*
G01X40473Y28150D02*
X35748D01*
G01X58583D02*
X53859D01*
G01X50415Y28071D02*
X43917D01*
G01X32678Y27748D02*
X34252D01*
G01X61811D02*
X60237D01*
G01X59370Y27559D02*
X34961D01*
G01Y27433D02*
X32819D01*
G01X61670D02*
X59370D01*
G01X34221Y26646D02*
X33741D01*
G01D02*
X34221D01*
G01X60748D02*
X61811D01*
G01X33741D02*
X32678D01*
G01X34252D02*
X33741D01*
G01X60748D02*
X60237D01*
G01X60748D02*
X60268D01*
G01X56134Y26536D02*
X56451D01*
G01X38292D02*
X38768D01*
G01X39587Y26378D02*
X37028D01*
G01X57304D02*
X54744D01*
G01X56372Y26130D02*
X56054D01*
G01X54744Y26032D02*
X57304D01*
G01X39587D02*
X37028D01*
G01X55260Y25644D02*
X54863D01*
G01X49922Y25276D02*
X44410D01*
G01X39587Y25197D02*
X37028D01*
G01X57304D02*
X54744D01*
G01Y25191D02*
X57304D01*
G01X39587D02*
X37028D01*
G01X54744Y24356D02*
X57304D01*
G01X39587D02*
X37028D01*
G01X54744Y24010D02*
X57304D01*
G01X39587D02*
X37028D01*
G01X41654Y23544D02*
X36536D01*
G01X57796D02*
X52678D01*
G01X60237Y23496D02*
X61811D01*
G01X34252D02*
X32678D01*
G01X55419Y23130D02*
X57642D01*
G01X34249Y26646D02*
X34238Y26645D01*
G01X47152Y22580D02*
X47767Y22605D01*
G01X61325Y30565D02*
X60723Y30535D01*
G01X61325Y30054D02*
X60723Y30023D01*
G01X34249Y26646D02*
X34252D01*
G01X37295Y16640D02*
X37358Y16880D01*
G01X34461D02*
X34398Y16640D01*
G01X49162Y20270D02*
X49109Y20054D01*
G01X47680Y21081D02*
X47733Y21297D01*
G01X38634Y20270D02*
X38581Y20054D01*
G01X34609Y35314D02*
X34537Y35021D01*
G01X32174Y35460D02*
X32246Y35752D01*
G01X32694Y27251D02*
X32678Y27177D01*
G01X60633Y16161D02*
X60570Y15862D01*
G01X60444D02*
X60507Y16161D01*
G01X60129Y16700D02*
X60192Y16999D01*
G01X59152Y18557D02*
X59089Y18257D01*
G01X58743Y16700D02*
X58806Y16999D01*
G01X57767Y18557D02*
X57704Y18257D01*
G01X55971Y18736D02*
X56034Y19036D01*
G01X55405Y16161D02*
X55342Y15862D01*
G01X55908Y19036D02*
X55846Y18736D01*
G01X55216Y15862D02*
X55279Y16161D01*
G01X54901Y16700D02*
X54964Y16999D01*
G01X53924Y18557D02*
X53861Y18257D01*
G01X53515Y16700D02*
X53578Y16999D01*
G01X52539Y18557D02*
X52476Y18257D01*
G01X52129Y16700D02*
X52192Y16999D01*
G01X50743Y18736D02*
X50806Y19036D01*
G01X50680D02*
X50617Y18736D01*
G01X40886Y16700D02*
X40949Y16999D01*
G01X39909Y18557D02*
X39846Y18257D01*
G01X55245Y20054D02*
X55193Y19784D01*
G01X53182Y21081D02*
X53235Y21351D01*
G01X49479Y20270D02*
X49426Y20000D01*
G01X47363Y21081D02*
X47416Y21351D01*
G01X38951Y20270D02*
X38898Y20000D01*
G01X45295Y16580D02*
X45736Y19036D01*
G01X45925D02*
X45421Y16221D01*
G01X37610D02*
X38114Y19036D01*
G01X50463Y28347D02*
X49922Y25276D01*
G01X60003Y16880D02*
X60034Y17059D01*
G01X59278Y17419D02*
X59247Y17239D01*
G01Y18197D02*
X59278Y18377D01*
G01X58617Y16880D02*
X58648Y17059D01*
G01X57893Y17419D02*
X57861Y17239D01*
G01Y18197D02*
X57893Y18377D01*
G01X54775Y16880D02*
X54806Y17059D01*
G01X54050Y17419D02*
X54019Y17239D01*
G01Y18197D02*
X54050Y18377D01*
G01X53389Y16880D02*
X53420Y17059D01*
G01X52665Y17419D02*
X52633Y17239D01*
G01Y18197D02*
X52665Y18377D01*
G01X52035Y17059D02*
X52003Y16880D01*
G01X50208Y17958D02*
X50240Y18137D01*
G01X50019Y18018D02*
X50051Y18197D01*
G01X42334Y16880D02*
X42303Y16700D01*
G01X40760Y16880D02*
X40791Y17059D01*
G01X40035Y17419D02*
X40004Y17239D01*
G01Y18197D02*
X40035Y18377D01*
G01X34253Y30510D02*
X33164Y30565D01*
G01X33766Y30023D02*
X33164Y30054D01*
G01X46564Y22605D02*
X47179Y22580D01*
G01X34221Y26646D02*
X34238Y26645D01*
G01X52284Y22835D02*
X42048D01*
G01X45339Y22796D02*
X48993D01*
G01X38768Y22725D02*
X38292D01*
G01X57642D02*
X54784D01*
G01X55757Y22599D02*
X38575D01*
G01X53960Y22525D02*
X52733Y22524D01*
G01X49922Y22525D02*
X57008D01*
G01X46378D02*
X37323D01*
G01X49922D02*
X47953D01*
G01X49922Y22520D02*
X44410D01*
G01X50591Y22284D02*
X57008D01*
G01X43741D02*
X37323D01*
G01X50591D02*
X43741D01*
G01X55124Y22158D02*
X39207D01*
G01X39775Y22080D02*
X54556D01*
G01X54029Y21945D02*
X54505D01*
G01X52442D02*
X52759D01*
G01X49902D02*
X50378D01*
G01X51701D02*
X52018D01*
G01X48209D02*
X48632D01*
G01X42496D02*
X44506D01*
G01X40115D02*
X41385D01*
G01X39374D02*
X39692D01*
G01X36835D02*
X38105D01*
G01X46199D02*
X44929D01*
G01X56780D02*
X56515D01*
G01X55169Y21926D02*
X39162D01*
G01X39756Y21844D02*
X54576D01*
G01X41438Y21675D02*
X40432D01*
G01X46252D02*
X45247D01*
G01X44506D02*
X43660D01*
G01X43342D02*
X42496D01*
G01X56515Y21621D02*
X56833D01*
G01X48209D02*
X48632D01*
G01X37152D02*
X38105D01*
G01X54505D02*
X54029D01*
G01X57150Y21351D02*
X57467D01*
G01X55245Y21297D02*
X54928D01*
G01X48229Y21260D02*
X46260D01*
G01X45247Y20865D02*
X46252D01*
G01X40432D02*
X41438D01*
G01X56833D02*
X56515D01*
G01Y20541D02*
X56833D01*
G01X45247D02*
X46146D01*
G01X41385D02*
X40432D01*
G01X55986Y20108D02*
X55669D01*
G01X54928Y20054D02*
X55245D01*
G01X54029Y19730D02*
X54505D01*
G01X38105D02*
X37152D01*
G01X48632D02*
X48209D01*
G01X56833D02*
X56409D01*
G01Y19406D02*
X56833D01*
G01X46569D02*
X46940D01*
G01X44929D02*
X45247D01*
G01X38105D02*
X36835D01*
G01X40432D02*
X40115D01*
G01X39692D02*
X39374D01*
G01X43660D02*
X43342D01*
G01X48632D02*
X48209D01*
G01X50220D02*
X49902D01*
G01X52018D02*
X51542D01*
G01X54505D02*
X54029D01*
G01X52759D02*
X52442D01*
G01X44292Y19292D02*
X50197D01*
G01X60444Y19036D02*
X60570D01*
G01X56286D02*
X57420D01*
G01X55216D02*
X55342D01*
G01X46870D02*
X48066D01*
G01X45736D02*
X45925D01*
G01X44665D02*
X44854D01*
G01X42586D02*
X42775D01*
G01X43468D02*
X43720D01*
G01X41736D02*
X41799D01*
G01X38114D02*
X38366D01*
G01X34744D02*
X35941D01*
G01X33233D02*
X33989D01*
G01X36854D02*
X36697D01*
G01X40445D02*
X40319D01*
G01X52129D02*
X51058D01*
G01X50806D02*
X50680D01*
G01X49830D02*
X49074D01*
G01X54460D02*
X54334D01*
G01X53074D02*
X52948D01*
G01X58302D02*
X58176D01*
G01X56034D02*
X55908D01*
G01X59688D02*
X59562D01*
G01X59530Y18736D02*
X59719D01*
G01X58145D02*
X58334D01*
G01X54302D02*
X54491D01*
G01X52917D02*
X53106D01*
G01X51216D02*
X52129D01*
G01X40287D02*
X40476D01*
G01X35941D02*
X35437D01*
G01X35248D02*
X34744D01*
G01X41831D02*
X41705D01*
G01X48066D02*
X47563D01*
G01X47374D02*
X46870D01*
G01X49862D02*
X49263D01*
G01X57231D02*
X56286D01*
G01X36697Y18676D02*
X36886D01*
G01X33422D02*
X33989D01*
G01X57185Y18504D02*
X37766D01*
G01X59971Y18377D02*
X60129D01*
G01X58586D02*
X58743D01*
G01X54743D02*
X54901D01*
G01X53357D02*
X53515D01*
G01X40728D02*
X40886D01*
G01X37075D02*
X37264D01*
G01X41390D02*
X41232D01*
G01X32678Y18083D02*
X34252D01*
G01X61811D02*
X60237D01*
G01X40476Y18018D02*
X40319D01*
G01X51720D02*
X51531D01*
G01X54491D02*
X54334D01*
G01X53106D02*
X52948D01*
G01X58334D02*
X58176D01*
G01X59719D02*
X59562D01*
G01X49263Y17838D02*
X49862D01*
G01X36886D02*
X36697D01*
G01X41705Y17778D02*
X41831D01*
G01X51531Y17718D02*
X51720D01*
G01X40508D02*
X40287D01*
G01X54523D02*
X54302D01*
G01X53137D02*
X52917D01*
G01X58365D02*
X58145D01*
G01X59751D02*
X59530D01*
G01X46177Y17539D02*
X46618D01*
G01X43972D02*
X44413D01*
G01X39122D02*
X39563D01*
G01X41831D02*
X41705D01*
G01X51058Y17479D02*
X51279D01*
G01X49263D02*
X49799D01*
G01X36697D02*
X36886D01*
G01X39563Y17239D02*
X39122D01*
G01X44413D02*
X43972D01*
G01X46618D02*
X46177D01*
G01X38524Y17179D02*
X37957D01*
G01X36382Y16999D02*
X36193D01*
G01X38555Y16940D02*
X37925D01*
G01X51247D02*
X51058D01*
G01X41201Y16880D02*
X41358D01*
G01X33989Y16580D02*
X33422D01*
G01X36886D02*
X36634D01*
G01X32678Y16536D02*
X34252D01*
G01X61811D02*
X60237D01*
G01X59530Y16520D02*
X59751D01*
G01X58145D02*
X58365D01*
G01X54302D02*
X54523D01*
G01X52917D02*
X53137D01*
G01X41673D02*
X41862D01*
G01X40287D02*
X40508D01*
G01X51720D02*
X51531D01*
G01X59562Y16221D02*
X59719D01*
G01X58176D02*
X58334D01*
G01X54334D02*
X54491D01*
G01X52948D02*
X53106D01*
G01X51531D02*
X51720D01*
G01X49074D02*
X49263D01*
G01X50051D02*
X50271D01*
G01X40319D02*
X40476D01*
G01X36634D02*
X36886D01*
G01X35437D02*
X35248D01*
G01X33989D02*
X33233D01*
G01X38870D02*
X38681D01*
G01X37799D02*
X37610D01*
G01X41894D02*
X41642D01*
G01X45421D02*
X45169D01*
G01X42775D02*
X42586D01*
G01X43720D02*
X43468D01*
G01X47563D02*
X47374D01*
G01X56790D02*
X56601D01*
G01X34646Y16142D02*
X36536D01*
G01X59843D02*
X57796D01*
G01D02*
X36536D01*
G01X55908Y15862D02*
X56034D01*
G01X50680D02*
X50806D01*
G01X55342D02*
X55216D01*
G01X60570D02*
X60444D01*
G01X46260Y15552D02*
X42423D01*
G01X52066D02*
X48229D01*
G01X51056Y14567D02*
X59843D01*
G01X43432D02*
X34646D01*
G01X48229D02*
X46260D01*
G01D02*
X43432D01*
G01X51056D02*
X48229D01*
G01X54099Y14226D02*
X57161D01*
G01X37170D02*
X40232D01*
G01X55470Y12993D02*
X55791D01*
G01X38541D02*
X38862D01*
G01X53420Y2508D02*
X41069D01*
G01X52437Y1575D02*
X42052D01*
G01X3937Y0D02*
X116260D01*
G01X51374Y22525D02*
X49922Y22523D01*
G01X37925Y16940D02*
X37799Y16221D01*
G01X37957Y17179D02*
X38240Y18796D01*
G01X36477Y18317D02*
X36508Y18497D01*
G01X52066Y15552D02*
X52033Y15300D01*
G01X42303Y18257D02*
X42271Y18018D01*
G01X41232Y18377D02*
X41264Y18617D01*
G01X36319D02*
X36288Y18377D01*
G01X34303Y17179D02*
X34272Y16940D01*
G01X60696Y16700D02*
X60633Y16161D01*
G01X60507D02*
X60570Y16700D01*
G01X55908Y18197D02*
X55971Y18736D01*
G01X55846D02*
X55783Y18197D01*
G01X55468Y16700D02*
X55405Y16161D01*
G01X55279D02*
X55342Y16700D01*
G01X50680Y18197D02*
X50743Y18736D01*
G01X50617D02*
X50554Y18197D01*
G01X34492Y17179D02*
X34461Y16880D01*
G01X57161Y14226D02*
X57363Y16142D01*
G01X40232Y14226D02*
X40433Y16142D01*
G01X59215Y17838D02*
X59247Y18197D01*
G01X57830Y17838D02*
X57861Y18197D01*
G01X53987Y17838D02*
X54019Y18197D01*
G01X52602Y17838D02*
X52633Y18197D01*
G01X39972Y17838D02*
X40004Y18197D01*
G01X59089Y18257D02*
X59058Y17838D01*
G01X57704Y18257D02*
X57672Y17838D01*
G01X53861Y18257D02*
X53830Y17838D01*
G01X52476Y18257D02*
X52444Y17838D01*
G01X39846Y18257D02*
X39815Y17838D01*
G01X60727Y17239D02*
X60696Y16700D01*
G01X60570D02*
X60601Y17239D01*
G01X55877Y17658D02*
X55908Y18197D01*
G01X55783D02*
X55751Y17658D01*
G01X55499Y17239D02*
X55468Y16700D01*
G01X55342D02*
X55373Y17239D01*
G01X50649Y17658D02*
X50680Y18197D01*
G01X50554D02*
X50523Y17658D01*
G01X53420Y2508D02*
X54134Y16142D01*
G01X46007Y22673D02*
X45406Y22796D01*
G01X33893Y35825D02*
X33535Y35899D01*
G01X32819Y33266D02*
X33177Y33193D01*
G01X56769Y26049D02*
X56372Y26130D01*
G01X57044Y21891D02*
X56780Y21945D01*
G01X54505D02*
X54769Y21891D01*
G01X57097Y20811D02*
X56833Y20865D01*
G01X48632Y21945D02*
X48897Y21891D01*
G01X46463D02*
X46199Y21945D01*
G01X56145Y19460D02*
X56409Y19406D01*
G01X54029D02*
X53764Y19460D01*
G01X41385Y21945D02*
X41649Y21891D01*
G01X38105Y21945D02*
X38369Y21891D01*
G01X48209Y19406D02*
X47945Y19460D01*
G01X39207Y22158D02*
X37323Y22525D01*
G01X39162Y21926D02*
X37323Y22284D01*
G01X33964Y34363D02*
X33535Y34436D01*
G01X56451Y26536D02*
X56928Y26455D01*
G01X33463Y36264D02*
X33964Y36191D01*
G01X43167Y14602D02*
X43432Y14567D01*
G01X45981Y22677D02*
X46591Y22603D01*
G01X38575Y22599D02*
X38379Y16142D01*
G01X59810Y32056D02*
Y32030D01*
G01Y31947D02*
Y31818D01*
G01X59812Y31429D02*
X59810Y30916D01*
G01X60713Y30423D02*
Y30341D01*
G01X62443Y34290D02*
Y33851D01*
G01X61811Y31076D02*
Y38969D01*
G01Y16536D02*
Y30054D01*
G01Y40355D02*
Y38969D01*
G01Y30054D02*
Y31076D01*
G01X61727Y33851D02*
Y32827D01*
G01Y36264D02*
Y34290D01*
G01X61325Y27433D02*
Y30054D01*
G01X61298Y32827D02*
Y33851D01*
G01Y35679D02*
Y34290D01*
G01X60727Y17658D02*
Y17239D01*
G01X60723Y30023D02*
Y27433D01*
G01X60601Y17239D02*
Y17658D01*
G01X60237Y16536D02*
Y38969D01*
G01Y40355D02*
Y38969D01*
G01X60192Y16999D02*
Y17299D01*
G01X60034Y17059D02*
Y17239D01*
G01X59810Y30916D02*
Y32056D01*
G01Y27433D02*
Y30698D01*
G01Y32039D02*
Y30698D01*
G01X59579Y33851D02*
Y34290D01*
G01X59370Y27559D02*
Y16142D01*
G01X59247Y17239D02*
Y17059D01*
G01X59215Y17718D02*
Y17838D01*
G01X59058D02*
Y17419D01*
G01X58859Y16142D02*
Y14567D01*
G01X58806Y16999D02*
Y17299D01*
G01X58662Y30698D02*
Y27559D01*
G01X58648Y17059D02*
Y17239D01*
G01X58583Y29134D02*
Y27559D01*
G01X57861Y17239D02*
Y17059D01*
G01X57830Y17718D02*
Y17838D01*
G01X57796Y23544D02*
Y16142D01*
G01Y27231D02*
Y23544D01*
G01X57672Y17838D02*
Y17419D01*
G01X57642Y25644D02*
Y25482D01*
G01Y23130D02*
Y22725D01*
G01X57626Y20000D02*
Y20270D01*
G01X57481Y16142D02*
Y14567D01*
G01X57420Y19036D02*
Y18736D01*
G01X57309Y20216D02*
Y20054D01*
G01X57304Y24010D02*
Y26378D01*
G01X57185Y16142D02*
Y18504D01*
G01X57166Y25482D02*
Y25644D01*
G01X57008Y22525D02*
Y22284D01*
G01X56286Y18736D02*
Y19036D01*
G01X56145Y21189D02*
Y21297D01*
G01X55877Y17239D02*
Y17658D01*
G01X55827Y21351D02*
Y21135D01*
G01X55757Y23544D02*
Y22599D01*
G01X55751Y17658D02*
Y17239D01*
G01X55499Y17658D02*
Y17239D01*
G01X55373D02*
Y17658D01*
G01X54964Y16999D02*
Y17299D01*
G01X54806Y17059D02*
Y17239D01*
G01X54784Y22725D02*
Y23130D01*
G01X54744Y26378D02*
Y24010D01*
G01X54528Y14567D02*
Y16142D01*
G01X54019Y17239D02*
Y17059D01*
G01X53987Y17718D02*
Y17838D01*
G01X53937Y15773D02*
Y14567D01*
G01X53859Y29134D02*
Y28150D01*
G01X53830Y17838D02*
Y17419D01*
G01X53578Y16999D02*
Y17299D01*
G01X53500Y21081D02*
Y20270D01*
G01X53420Y17059D02*
Y17239D01*
G01X53182Y20270D02*
Y21081D01*
G01X53150Y16142D02*
Y14567D01*
G01X53071Y29134D02*
Y27559D01*
G01X52992Y16142D02*
Y14567D01*
G01X52759Y21945D02*
Y19406D01*
G01X52678Y23544D02*
Y22599D01*
G01X52633Y17239D02*
Y17059D01*
G01X52602Y17718D02*
Y17838D01*
G01X52444D02*
Y17419D01*
G01X52442Y19406D02*
Y21945D01*
G01X52284Y22835D02*
Y16142D01*
G01X52192Y16999D02*
Y17239D01*
G01X52166Y18504D02*
Y16142D01*
G01X52129Y18736D02*
Y19036D01*
G01X52066Y18504D02*
Y15552D01*
G01X52035Y17179D02*
Y17059D01*
G01X52018Y21945D02*
Y19406D01*
G01X51701Y19784D02*
Y21945D01*
G01X51216Y17778D02*
Y18736D01*
G01X51103Y29134D02*
Y28347D01*
G01X51058Y19036D02*
Y17479D01*
G01X50649Y17239D02*
Y17658D01*
G01X50523D02*
Y17239D01*
G01X50240Y18137D02*
Y18377D01*
G01X50220Y21621D02*
Y19406D01*
G01X50197Y14567D02*
Y16142D01*
G01Y19292D02*
Y18504D01*
G01X50051Y18197D02*
Y18377D01*
G01X50028Y18504D02*
Y15552D01*
G01X49922Y22284D02*
Y22525D01*
G01X49902Y19406D02*
Y21945D01*
G01X49863Y14567D02*
Y16142D01*
G01X49479Y21081D02*
Y20270D01*
G01X49263Y16221D02*
Y17479D01*
G01Y18736D02*
Y17838D01*
G01X49162Y21081D02*
Y20270D01*
G01X49074Y19036D02*
Y16221D01*
G01X48229Y18504D02*
Y14567D01*
G01X48066Y19036D02*
Y18736D01*
G01X47953Y22525D02*
Y22284D01*
G01X47680Y20270D02*
Y21081D01*
G01X47563Y18736D02*
Y16221D01*
G01X47374D02*
Y18736D01*
G01X47363Y20270D02*
Y21081D01*
G01X47166Y21926D02*
Y21844D01*
G01X46887Y21135D02*
Y21351D01*
G01X46870Y18736D02*
Y19036D01*
G01X46618Y17539D02*
Y17239D01*
G01X46569Y21189D02*
Y21351D01*
G01X46378Y22284D02*
Y22525D01*
G01X46260Y18504D02*
Y14567D01*
G01X46177Y17239D02*
Y17539D01*
G01X45247Y19406D02*
Y20541D01*
G01Y21675D02*
Y20865D01*
G01X44929Y21945D02*
Y19406D01*
G01X44626Y14567D02*
Y16142D01*
G01X44623Y14567D02*
Y16142D01*
G01X44506Y21945D02*
Y21675D01*
G01X44461Y18504D02*
Y15552D01*
G01X44413Y17539D02*
Y17239D01*
G01X44410Y22525D02*
Y22284D01*
G01X44292Y14567D02*
Y16142D01*
G01Y19292D02*
Y18504D01*
G01X43972Y17239D02*
Y17539D01*
G01X43660Y21675D02*
Y19406D01*
G01X43342D02*
Y21675D01*
G01X43229Y28347D02*
Y29134D01*
G01X42775Y19036D02*
Y17658D01*
G01Y17179D02*
Y16221D01*
G01X42586D02*
Y19036D01*
G01X42496Y21675D02*
Y21945D01*
G01X42423Y18504D02*
Y15552D01*
G01X42334Y17119D02*
Y16880D01*
G01X42323Y16142D02*
Y18504D01*
G01X42303Y18377D02*
Y18257D01*
G01X42177Y16880D02*
Y17119D01*
G01X42146Y18257D02*
Y18377D01*
G01X42072Y21351D02*
Y21135D01*
G01X42048Y22835D02*
Y16142D01*
G01X41755Y21189D02*
Y21351D01*
G01X41705Y17539D02*
Y17778D01*
G01X41654Y23544D02*
Y22599D01*
G01X41497Y16142D02*
Y14567D01*
G01X41339Y16142D02*
Y14567D01*
G01X41260Y29134D02*
Y27559D01*
G01X40949Y16999D02*
Y17299D01*
G01X40791Y17059D02*
Y17239D01*
G01X40552Y16142D02*
Y14567D01*
G01X40473Y29134D02*
Y28150D01*
G01X40432Y21675D02*
Y20865D01*
G01Y20541D02*
Y19406D01*
G01X40115D02*
Y21945D01*
G01X40004Y17239D02*
Y17059D01*
G01X39972Y17718D02*
Y17838D01*
G01X39961Y14567D02*
Y16142D01*
G01X39815Y17838D02*
Y17419D01*
G01X39692Y21945D02*
Y19406D01*
G01X39587Y24010D02*
Y26378D01*
G01X39563Y17539D02*
Y17239D01*
G01X39374Y19406D02*
Y21945D01*
G01X39122Y17239D02*
Y17539D01*
G01X38951Y21081D02*
Y20270D01*
G01X38768Y26536D02*
Y22725D01*
G01X38634Y21081D02*
Y20270D01*
G01X38583Y16142D02*
Y18504D01*
G01X38575Y23544D02*
Y22599D01*
G01X38292Y22725D02*
Y25887D01*
G01X37815Y25320D02*
Y25968D01*
G01X37766Y16142D02*
Y18504D01*
G01X37358Y16880D02*
Y17179D01*
G01X37323Y22525D02*
Y22284D01*
G01X37169Y17119D02*
Y16940D01*
G01X37152Y19730D02*
Y21621D01*
G01X37028Y26378D02*
Y24010D01*
G01X37008Y15773D02*
Y14567D01*
G01X36835Y19406D02*
Y21945D01*
G01X36536Y23544D02*
Y16142D01*
G01Y27231D02*
Y23544D01*
G01X36477Y18197D02*
Y18317D01*
G01X36288Y18377D02*
Y18137D01*
G01X35941Y19036D02*
Y18736D01*
G01X35827Y30698D02*
Y28150D01*
G01X35748Y29134D02*
Y27559D01*
G01X35630Y16142D02*
Y14567D01*
G01X35437Y18736D02*
Y16221D01*
G01X35248D02*
Y18736D01*
G01X34961Y27559D02*
Y16142D01*
G01X34744Y18736D02*
Y19036D01*
G01X34680Y33924D02*
Y33632D01*
G01X34679Y31658D02*
Y27433D01*
G01Y31658D02*
Y32056D01*
G01D02*
Y31658D01*
G01X34609Y35460D02*
Y35314D01*
G01X34492Y18078D02*
Y17179D01*
G01X34322Y33632D02*
Y33924D01*
G01X34303Y18078D02*
Y17179D01*
G01X34252Y16536D02*
Y38969D01*
G01Y40355D02*
Y38969D01*
G01X34251Y35314D02*
Y35460D01*
G01X33766Y30023D02*
Y27433D01*
G01X33422Y16580D02*
Y18676D01*
G01X33248Y34436D02*
Y34729D01*
G01X33233Y16221D02*
Y19036D01*
G01X33164Y30054D02*
Y27433D01*
G01X32678Y31076D02*
Y38969D01*
G01Y16536D02*
Y30054D01*
G01Y31076D02*
Y30054D01*
G01Y40355D02*
Y38969D01*
G01X59810Y31637D02*
X59812Y31429D01*
G01X59811Y31965D02*
X59810Y32039D01*
G01X60713Y30343D02*
X60714Y30244D01*
G01X55757Y22599D02*
X55953Y16142D01*
G01X60723Y30023D02*
X60718Y30137D01*
G01X60696Y18197D02*
X60727Y17658D01*
G01X60601D02*
X60570Y18197D01*
G01X55908Y16700D02*
X55877Y17239D01*
G01X55751D02*
X55783Y16700D01*
G01X55468Y18197D02*
X55499Y17658D01*
G01X55373D02*
X55342Y18197D01*
G01X50680Y16700D02*
X50649Y17239D01*
G01X50523D02*
X50554Y16700D01*
G01X59058Y17419D02*
X59089Y16999D01*
G01X57672Y17419D02*
X57704Y16999D01*
G01X53830Y17419D02*
X53861Y16999D01*
G01X60633Y18736D02*
X60696Y18197D01*
G01X60570D02*
X60507Y18736D01*
G01X55971Y16161D02*
X55908Y16700D01*
G01X55783D02*
X55846Y16161D01*
G01X55405Y18736D02*
X55468Y18197D01*
G01X55342D02*
X55279Y18736D01*
G01X50743Y16161D02*
X50680Y16700D01*
G01X50554D02*
X50617Y16161D01*
G01X42271Y18617D02*
X42303Y18377D01*
G01Y17359D02*
X42334Y17119D01*
G01X36288Y18137D02*
X36319Y17898D01*
G01X36193Y16999D02*
X36225Y16760D01*
G01X34272Y18317D02*
X34303Y18078D01*
G01X42423Y15552D02*
X42456Y15300D01*
G01X35799Y30894D02*
X35827Y30698D01*
G01X41503Y23450D02*
X41486Y23544D01*
G01X60129Y18377D02*
X60097Y18557D01*
G01X60034Y17239D02*
X60003Y17419D01*
G01X59247Y17059D02*
X59278Y16880D01*
G01X58743Y18377D02*
X58711Y18557D01*
G01X58648Y17239D02*
X58617Y17419D01*
G01X57861Y17059D02*
X57893Y16880D01*
G01X54901Y18377D02*
X54869Y18557D01*
G01X54806Y17239D02*
X54775Y17419D01*
G01X54019Y17059D02*
X54050Y16880D01*
G01X53515Y18377D02*
X53483Y18557D01*
G01X53420Y17239D02*
X53389Y17419D01*
G01X52633Y17059D02*
X52665Y16880D01*
G01X52003Y17359D02*
X52035Y17179D01*
G01X50240Y18377D02*
X50208Y18557D01*
G01X50051Y18377D02*
X50019Y18557D01*
G01X43868Y28347D02*
X44410Y25276D01*
G01X45169Y16221D02*
X44665Y19036D01*
G01X44854D02*
X45295Y16580D01*
G01X55193Y21567D02*
X55245Y21297D01*
G01X53235Y20000D02*
X53182Y20270D01*
G01X49426Y21351D02*
X49479Y21081D01*
G01X49799Y17479D02*
X50051Y16221D01*
G01X60570Y19036D02*
X60633Y18736D01*
G01X60507D02*
X60444Y19036D01*
G01X60192Y17299D02*
X60129Y17598D01*
G01X59089Y16999D02*
X59152Y16700D01*
G01X58806Y17299D02*
X58743Y17598D01*
G01X57704Y16999D02*
X57767Y16700D01*
G01X56034Y15862D02*
X55971Y16161D01*
G01X55342Y19036D02*
X55405Y18736D01*
G01X55846Y16161D02*
X55908Y15862D01*
G01X55279Y18736D02*
X55216Y19036D01*
G01X54964Y17299D02*
X54901Y17598D01*
G01X53861Y16999D02*
X53924Y16700D01*
G01X53578Y17299D02*
X53515Y17598D01*
G01X52476Y16999D02*
X52539Y16700D01*
G01X52192Y17239D02*
X52129Y17539D01*
G01X61795Y27251D02*
X61811Y27177D01*
G01X56833Y21621D02*
X56991Y21567D01*
G01X56515Y20865D02*
X56356Y20919D01*
G01X46411Y21621D02*
X46252Y21675D01*
G01X41596Y21621D02*
X41438Y21675D01*
G01X42020Y17479D02*
X41831Y17539D01*
G01X41799Y19036D02*
X42020Y18976D01*
G01X33105Y32827D02*
X32819Y32900D01*
G01X54716Y21567D02*
X54505Y21621D01*
G01X56833Y20541D02*
X57044Y20487D01*
G01X56304Y20595D02*
X56515Y20541D01*
G01X56409Y19730D02*
X56198Y19784D01*
G01X48632Y21621D02*
X48844Y21567D01*
G01X53817Y19784D02*
X54029Y19730D01*
G01X48209D02*
X47998Y19784D01*
G01X38105Y21621D02*
X38316Y21567D01*
G01X0Y723480D02*
Y3937D01*
G01X41069Y2508D02*
X40355Y16142D01*
G01X52444Y17419D02*
X52476Y16999D01*
G01X39815Y17419D02*
X39846Y16999D01*
G01X54099Y14226D02*
X53937Y15773D01*
G01X37170Y14226D02*
X37008Y15773D01*
G01X34461Y18377D02*
X34492Y18078D01*
G01X41232Y16700D02*
X41201Y16880D01*
G01X40886Y18377D02*
X40854Y18557D01*
G01X40791Y17239D02*
X40760Y17419D01*
G01X40004Y17059D02*
X40035Y16880D01*
G01X38240Y18796D02*
X38524Y17179D01*
G01X38681Y16221D02*
X38555Y16940D01*
G01X37264Y18377D02*
X37232Y18557D01*
G01X36508Y18018D02*
X36477Y18197D01*
G01X36414Y16820D02*
X36382Y16999D01*
G01X38366Y19036D02*
X38870Y16221D01*
G01X47416Y20000D02*
X47363Y20270D01*
G01X38898Y21351D02*
X38951Y21081D01*
G01X50271Y16221D02*
X49988Y17598D01*
G01X50806Y15862D02*
X50743Y16161D01*
G01X50617D02*
X50680Y15862D01*
G01X40949Y17299D02*
X40886Y17598D01*
G01X39846Y16999D02*
X39909Y16700D01*
G01X41502Y23456D02*
X41524Y23360D01*
G01X57563Y25968D02*
X57642Y25644D01*
G01X55827Y21135D02*
X55880Y20919D01*
G01X55669Y20108D02*
X55722Y19892D01*
G01X53500Y20270D02*
X53553Y20054D01*
G01X49109Y21297D02*
X49162Y21081D01*
G01X47733Y20054D02*
X47680Y20270D01*
G01X38581Y21297D02*
X38634Y21081D01*
G01X34537Y35752D02*
X34609Y35460D01*
G01Y34217D02*
X34680Y33924D01*
G01X51310Y16700D02*
X51247Y16940D01*
G01X51058D02*
X51121Y16700D01*
G01X42177Y17119D02*
X42114Y17359D01*
G01X41358Y16880D02*
X41390Y16760D01*
G01X37043Y18497D02*
X37075Y18377D01*
G01X37358Y17179D02*
X37295Y17419D01*
G01X34398Y18617D02*
X34461Y18377D01*
G01X41523Y23366D02*
X41549Y23277D01*
G01X36225Y16760D02*
X36319Y16460D01*
G01X57467Y21351D02*
X57414Y21513D01*
G01X56198Y21027D02*
X56145Y21189D01*
G01X56039Y19946D02*
X55986Y20108D01*
G01X54928Y21297D02*
X54875Y21459D01*
G01X46887Y21351D02*
X46834Y21513D01*
G01X46569Y21351D02*
X46516Y21513D01*
G01X42020D02*
X42072Y21351D01*
G01X41755D02*
X41702Y21513D01*
G01X43153Y17898D02*
X43720Y16221D01*
G01X43468D02*
X42996Y17598D01*
G01X59908Y18557D02*
X59971Y18377D01*
G01X59278Y16880D02*
X59341Y16700D01*
G01X58523Y18557D02*
X58586Y18377D01*
G01X57893Y16880D02*
X57956Y16700D01*
G01X54680Y18557D02*
X54743Y18377D01*
G01X54050Y16880D02*
X54113Y16700D01*
G01X53294Y18557D02*
X53357Y18377D01*
G01X52665Y16880D02*
X52728Y16700D01*
G01X51940Y17539D02*
X52003Y17359D01*
G01X42146Y18377D02*
X42083Y18557D01*
G01X42240Y17539D02*
X42303Y17359D01*
G01X46146Y20541D02*
X46569Y19406D01*
G01X60097Y18557D02*
X60003Y18796D01*
G01X58711Y18557D02*
X58617Y18796D01*
G01X59152Y16700D02*
X59247Y16460D01*
G01X57767Y16700D02*
X57861Y16460D01*
G01X54869Y18557D02*
X54775Y18796D01*
G01X53483Y18557D02*
X53389Y18796D01*
G01X53924Y16700D02*
X54019Y16460D01*
G01X52539Y16700D02*
X52633Y16460D01*
G01X52129Y17539D02*
X52035Y17778D01*
G01X51121Y16700D02*
X51216Y16460D01*
G01X50208Y18557D02*
X50114Y18796D01*
G01X56928Y26455D02*
X57245Y26293D01*
G01X33964Y36191D02*
X34251Y36045D01*
G01X32676Y33339D02*
X32819Y33266D01*
G01X57309Y20703D02*
X57097Y20811D01*
G01X54769Y21891D02*
X54981Y21783D01*
G01X32819Y32900D02*
X32532Y33047D01*
G01X56092Y20703D02*
X56304Y20595D01*
G01X53764Y19460D02*
X53553Y19568D01*
G01X48897Y21891D02*
X49109Y21783D01*
G01X47945Y19460D02*
X47733Y19568D01*
G01X38369Y21891D02*
X38581Y21783D01*
G01X60194Y16357D02*
X61597Y15643D01*
G01X51720Y17718D02*
X51846Y17658D01*
G01X51531Y16520D02*
X51405Y16580D01*
G01X41642Y16221D02*
X41516Y16281D01*
G01X36886Y17479D02*
X37012Y17419D01*
G01X36571Y17539D02*
X36697Y17479D01*
G01X33989Y18676D02*
X34114Y18617D01*
G01X36634Y16580D02*
X36508Y16640D01*
G01X34108Y34582D02*
X34466Y34436D01*
G01X42925Y14700D02*
X43169Y14601D01*
G01X59845Y18976D02*
X59688Y19036D01*
G01X58460Y18976D02*
X58302Y19036D01*
G01X59877Y17958D02*
X59719Y18018D01*
G01X58491Y17958D02*
X58334Y18018D01*
G01X54617Y18976D02*
X54460Y19036D01*
G01X53231Y18976D02*
X53074Y19036D01*
G01X59404Y16281D02*
X59562Y16221D01*
G01X54649Y17958D02*
X54491Y18018D01*
G01X58019Y16281D02*
X58176Y16221D01*
G01X53263Y17958D02*
X53106Y18018D01*
G01X49988Y18976D02*
X49830Y19036D01*
G01X51877Y17958D02*
X51720Y18018D01*
G01X54176Y16281D02*
X54334Y16221D01*
G01X52791Y16281D02*
X52948Y16221D01*
G01X51373Y16281D02*
X51531Y16221D01*
G01X41988Y18676D02*
X41831Y18736D01*
G01X40602Y18976D02*
X40445Y19036D01*
G01X40634Y17958D02*
X40476Y18018D01*
G01X37012Y18976D02*
X36854Y19036D01*
G01X41516Y16580D02*
X41673Y16520D01*
G01X33989Y19036D02*
X34146Y18976D01*
G01X37043Y17778D02*
X36886Y17838D01*
G01X40161Y16281D02*
X40319Y16221D01*
G01X36477Y16281D02*
X36634Y16221D01*
G01X32174Y33412D02*
X32103Y33632D01*
G01X40665Y18557D02*
X40728Y18377D01*
G01X41295Y16520D02*
X41232Y16700D01*
G01X40035Y16880D02*
X40098Y16700D01*
G01X37106Y17299D02*
X37169Y17119D01*
G01X34209Y18497D02*
X34272Y18317D01*
G01X41549Y23278D02*
X41580Y23193D01*
G01X43622Y22599D02*
X43741Y22284D01*
G01X46940Y19406D02*
X46463Y20649D01*
G01X40854Y18557D02*
X40760Y18796D01*
G01X39909Y16700D02*
X40004Y16460D01*
G01X37232Y18557D02*
X37138Y18796D01*
G01X42556Y15061D02*
X42456Y15302D01*
G01X41578Y23198D02*
X41616Y23112D01*
G01X57097Y21459D02*
X57150Y21351D01*
G01X57626Y20270D02*
X57520Y20487D01*
G01X53341Y19784D02*
X53235Y20000D01*
G01X49320Y21567D02*
X49426Y21351D01*
G01X47522Y19784D02*
X47416Y20000D01*
G01X34322Y33924D02*
X34179Y34217D01*
G01X38792Y21567D02*
X38898Y21351D01*
G01X32461Y33632D02*
X32532Y33485D01*
G01X41613Y23117D02*
X41654Y23040D01*
G01X58617Y17419D02*
X58554Y17539D01*
G01X53389Y17419D02*
X53326Y17539D01*
G01X42146Y18856D02*
X42271Y18617D01*
G01X41390Y16760D02*
X41453Y16640D01*
G01X40760Y17419D02*
X40697Y17539D01*
G01X36980Y18617D02*
X37043Y18497D01*
G01X60129Y17598D02*
X60034Y17778D01*
G01X60003Y17419D02*
X59940Y17539D01*
G01X58743Y17598D02*
X58648Y17778D01*
G01X54901Y17598D02*
X54806Y17778D01*
G01X54775Y17419D02*
X54712Y17539D01*
G01X53515Y17598D02*
X53420Y17778D01*
G01X50019Y18557D02*
X49956Y18676D01*
G01X40886Y17598D02*
X40791Y17778D01*
G01X37295Y17419D02*
X37169Y17658D01*
G01X36319Y17898D02*
X36445Y17658D01*
G01X36508Y16640D02*
X36414Y16820D01*
G01X34272Y18856D02*
X34398Y18617D01*
G01X61747Y27336D02*
X61796Y27249D01*
G01X54063Y27559D02*
X54744Y26378D01*
G01X36346Y27559D02*
X37028Y26378D01*
G01X55722Y19892D02*
X55880Y19622D01*
G01X51542Y19406D02*
X50220Y21621D01*
G01X50378Y21945D02*
X51701Y19784D01*
G01X57166Y25644D02*
X57007Y25887D01*
G01X57203Y20378D02*
X57309Y20216D01*
G01X53553Y20054D02*
X53658Y19892D01*
G01X49003Y21459D02*
X49109Y21297D01*
G01X47839Y19892D02*
X47733Y20054D01*
G01X34251Y35460D02*
X34108Y35679D01*
G01X34466Y34436D02*
X34609Y34217D01*
G01X32318Y33193D02*
X32174Y33412D01*
G01X38475Y21459D02*
X38581Y21297D01*
G01X50114Y18796D02*
X49988Y18976D01*
G01X37138Y18796D02*
X37012Y18976D01*
G01X57414Y21513D02*
X57256Y21729D01*
G01X46834Y21513D02*
X46675Y21729D01*
G01X41861D02*
X42020Y21513D01*
G01X42556Y15061D02*
X42715Y14858D01*
G01X61670Y27433D02*
X61748Y27334D01*
G01X59814Y18676D02*
X59908Y18557D01*
G01X59940Y17539D02*
X59845Y17658D01*
G01X58428Y18676D02*
X58523Y18557D01*
G01X59341Y16700D02*
X59436Y16580D01*
G01X58554Y17539D02*
X58460Y17658D01*
G01X57956Y16700D02*
X58050Y16580D01*
G01X54586Y18676D02*
X54680Y18557D01*
G01X54712Y17539D02*
X54617Y17658D01*
G01X53200Y18676D02*
X53294Y18557D01*
G01X54113Y16700D02*
X54208Y16580D01*
G01X53326Y17539D02*
X53231Y17658D01*
G01X52728Y16700D02*
X52822Y16580D01*
G01X51846Y17658D02*
X51940Y17539D01*
G01X51405Y16580D02*
X51310Y16700D01*
G01X48728Y18437D02*
X48822Y18317D01*
G01X48413Y16820D02*
X48318Y16940D01*
G01X42083Y18557D02*
X41988Y18676D01*
G01X42114Y17359D02*
X42020Y17479D01*
G01X40571Y18676D02*
X40665Y18557D01*
G01X40697Y17539D02*
X40602Y17658D01*
G01X41390Y16401D02*
X41295Y16520D01*
G01X40098Y16700D02*
X40193Y16580D01*
G01X60003Y18796D02*
X59845Y18976D01*
G01X60034Y17778D02*
X59877Y17958D01*
G01X58617Y18796D02*
X58460Y18976D01*
G01X58648Y17778D02*
X58491Y17958D01*
G01X59247Y16460D02*
X59404Y16281D01*
G01X57861Y16460D02*
X58019Y16281D01*
G01X54775Y18796D02*
X54617Y18976D01*
G01X54806Y17778D02*
X54649Y17958D01*
G01X53389Y18796D02*
X53231Y18976D01*
G01X53420Y17778D02*
X53263Y17958D01*
G01X54019Y16460D02*
X54176Y16281D01*
G01X52035Y17778D02*
X51877Y17958D01*
G01X52633Y16460D02*
X52791Y16281D01*
G01X51216Y16460D02*
X51373Y16281D01*
G01X40760Y18796D02*
X40602Y18976D01*
G01X40791Y17778D02*
X40634Y17958D01*
G01X57245Y26293D02*
X57563Y25968D01*
G01X56991Y21567D02*
X57097Y21459D01*
G01X57520Y20487D02*
X57309Y20703D01*
G01X55880Y20919D02*
X56092Y20703D01*
G01X54981Y21783D02*
X55193Y21567D01*
G01X56198Y19784D02*
X56039Y19946D01*
G01X53553Y19568D02*
X53341Y19784D01*
G01X49109Y21783D02*
X49320Y21567D01*
G01X34251Y36045D02*
X34537Y35752D01*
G01X46516Y21513D02*
X46411Y21621D01*
G01X47733Y19568D02*
X47522Y19784D01*
G01X32532Y33485D02*
X32676Y33339D01*
G01X41702Y21513D02*
X41596Y21621D01*
G01X38581Y21783D02*
X38792Y21567D01*
G01X59041Y31647D02*
X59810Y30916D01*
G01X42020Y18976D02*
X42146Y18856D01*
G01X41453Y16640D02*
X41516Y16580D01*
G01Y16281D02*
X41390Y16401D01*
G01X37169Y17658D02*
X37043Y17778D01*
G01X36445Y17658D02*
X36571Y17539D01*
G01X34146Y18976D02*
X34272Y18856D01*
G01X57256Y21729D02*
X57044Y21891D01*
G01X46675Y21729D02*
X46463Y21891D01*
G01X41649D02*
X41861Y21729D01*
G01X42083Y17658D02*
X42240Y17539D01*
G01X42927Y14699D02*
X42715Y14858D01*
G01X57007Y25887D02*
X56769Y26049D01*
G01X57044Y20487D02*
X57203Y20378D01*
G01X56356Y20919D02*
X56198Y21027D01*
G01X34108Y35679D02*
X33893Y35825D01*
G01X54875Y21459D02*
X54716Y21567D01*
G01X34179Y34217D02*
X33964Y34363D01*
G01X53658Y19892D02*
X53817Y19784D01*
G01X32532Y33047D02*
X32318Y33193D01*
G01X48844Y21567D02*
X49003Y21459D01*
G01X47998Y19784D02*
X47839Y19892D01*
G01X38316Y21567D02*
X38475Y21459D01*
G01X59719Y18736D02*
X59814Y18676D01*
G01X58334Y18736D02*
X58428Y18676D01*
G01X59845Y17658D02*
X59751Y17718D01*
G01X58460Y17658D02*
X58365Y17718D01*
G01X59436Y16580D02*
X59530Y16520D01*
G01X58050Y16580D02*
X58145Y16520D01*
G01X54491Y18736D02*
X54586Y18676D01*
G01X53106Y18736D02*
X53200Y18676D01*
G01X54617Y17658D02*
X54523Y17718D01*
G01X53231Y17658D02*
X53137Y17718D01*
G01X54208Y16580D02*
X54302Y16520D01*
G01X49956Y18676D02*
X49862Y18736D01*
G01X52822Y16580D02*
X52917Y16520D01*
G01X40476Y18736D02*
X40571Y18676D01*
G01X40602Y17658D02*
X40508Y17718D01*
G01X40193Y16580D02*
X40287Y16520D01*
G01X36886Y18676D02*
X36980Y18617D01*
G01X36697Y17838D02*
X36603Y17898D01*
G01X55880Y19622D02*
X56145Y19460D01*
G01X37012Y17419D02*
X37106Y17299D01*
G01X36603Y17898D02*
X36508Y18018D01*
G01X34114Y18617D02*
X34209Y18497D01*
G01X40004Y16460D02*
X40161Y16281D01*
G01X36319Y16460D02*
X36477Y16281D01*
G01X77756Y98426D02*
G03I-6889J0D01*
G01Y472441D02*
G03I-6889J0D01*
G01X0Y723727D02*
Y807769D01*
G01X416Y725241D02*
G03X0Y723480I3521J-1761D01*
G01X22119Y763780D02*
G03X18597Y761604I0J-3938D01*
G01X57087Y740158D02*
G03I-7874J0D01*
G01X386150Y763780D02*
X22119D01*
G01X18597Y761604D02*
X416Y725241D01*
G01X79694Y-714465D02*
Y-733402D01*
G01X128071Y3937D02*
G03X132008Y0I3937J0D01*
G01X128071Y43308D02*
G03X120197I-3937J0D01*
G01X132008Y0D02*
X275709D01*
G01X128071Y3937D02*
Y43308D01*
G01X79961Y44458D02*
X79967Y44292D01*
G01X79943Y44618D02*
X79961Y44458D01*
G01X79914Y44762D02*
X79943Y44618D01*
G01X79875Y44881D02*
X79914Y44762D01*
G01X79828Y44974D02*
X79875Y44881D01*
G01X79776Y45034D02*
X79828Y44974D01*
G01X109016Y44125D02*
X109010Y44292D01*
G01X109034Y43966D02*
X109016Y44125D01*
G01X109064Y43822D02*
X109034Y43966D01*
G01X109102Y43702D02*
X109064Y43822D01*
G01X109149Y43609D02*
X109102Y43702D01*
G01X109201Y43549D02*
X109149Y43609D01*
G01X81312Y44974D02*
X81260Y45034D01*
G01X81359Y44880D02*
X81312Y44974D01*
G01X81398Y44758D02*
X81359Y44880D01*
G01X81427Y44616D02*
X81398Y44758D01*
G01X81445Y44457D02*
X81427Y44616D01*
G01X81451Y44292D02*
X81445Y44457D01*
G01X107665Y43610D02*
X107717Y43549D01*
G01X107618Y43703D02*
X107665Y43610D01*
G01X107579Y43825D02*
X107618Y43703D01*
G01X107550Y43967D02*
X107579Y43825D01*
G01X107532Y44127D02*
X107550Y43967D01*
G01X107526Y44292D02*
X107532Y44127D01*
G01X79828Y43610D02*
X79776Y43549D01*
G01X79875Y43703D02*
X79828Y43610D01*
G01X79914Y43825D02*
X79875Y43703D01*
G01X79943Y43967D02*
X79914Y43825D01*
G01X79961Y44127D02*
X79943Y43967D01*
G01X79967Y44292D02*
X79961Y44127D01*
G01X109149Y44974D02*
X109201Y45034D01*
G01X109102Y44880D02*
X109149Y44974D01*
G01X109063Y44758D02*
X109102Y44880D01*
G01X109034Y44616D02*
X109063Y44758D01*
G01X109016Y44457D02*
X109034Y44616D01*
G01X109010Y44292D02*
X109016Y44457D01*
G01X81445Y44125D02*
X81451Y44292D01*
G01X81427Y43966D02*
X81445Y44125D01*
G01X81397Y43822D02*
X81427Y43966D01*
G01X81359Y43702D02*
X81397Y43822D01*
G01X81312Y43609D02*
X81359Y43702D01*
G01X81260Y43549D02*
X81312Y43609D01*
G01X107532Y44458D02*
X107526Y44292D01*
G01X107550Y44618D02*
X107532Y44458D01*
G01X107580Y44762D02*
X107550Y44618D01*
G01X107618Y44881D02*
X107580Y44762D01*
G01X107665Y44974D02*
X107618Y44881D01*
G01X107717Y45034D02*
X107665Y44974D01*
G01X107834Y39784D02*
G03X107500Y39253I256J-532D01*
G01X107147Y41202D02*
G03X107481Y41733I-256J532D01*
G01X106693Y25985D02*
G03X107481Y26772I0J788D01*
G01X107834Y39784D02*
G03X109055Y41733I-945J1949D01*
G01X107147Y41202D02*
G03X105926Y39253I945J-1949D01*
G01X106693Y24410D02*
G03X109055Y26772I0J2362D01*
G01X99478Y1575D02*
G03X100459Y2489I0J983D01*
G01X88518D02*
G03X89499Y1575I981J69D01*
G01X116260Y0D02*
G03X120197Y3937I0J3937D01*
G01X81477Y39253D02*
G03X81143Y39784I-590J-1D01*
G01X81496Y41733D02*
G03X81830Y41202I590J1D01*
G01X81496Y26772D02*
G03X82284Y25985I787J0D01*
G01X79922Y41733D02*
G03X81144Y39784I2165J0D01*
G01X83052Y39253D02*
G03X81830Y41202I-2165J0D01*
G01X79922Y26772D02*
G03X82284Y24410I2362J0D01*
G01X85519Y34613D02*
X85657Y34660D01*
G01X85886Y34520D02*
X85702Y34379D01*
G01X109201Y45034D02*
X109999Y45670D01*
G01X108516D02*
X107717Y45034D01*
G01X80462Y42914D02*
X81260Y43549D01*
G01X79776D02*
X78978Y42914D01*
G01X85657Y34660D02*
X85748Y34754D01*
G01X86713Y35176D02*
X86437Y34848D01*
G01Y35223D02*
X86713Y35552D01*
G01X86024Y34707D02*
X85886Y34520D01*
G01X85702Y34379D02*
X85473Y34332D01*
G01X86070Y34848D02*
X86024Y34707D01*
G01X85748Y34754D02*
X85794Y34895D01*
G01X81496Y50197D02*
X79922D01*
G01X109055D02*
X107481D01*
G01X81496Y49016D02*
X79922D01*
G01X109055D02*
X107481D01*
G01X81496Y45670D02*
X77756D01*
G01X111221D02*
X107481D01*
G01Y45473D02*
X109055D01*
G01X79922D02*
X81496D01*
G01X79776Y45034D02*
X81260D01*
G01X109201D02*
X107717D01*
G01X81496Y44292D02*
X79922D01*
G01X109055D02*
X107481D01*
G01X79776Y43549D02*
X81260D01*
G01X109201D02*
X107717D01*
G01X81496Y42914D02*
X77756D01*
G01X111221D02*
X107481D01*
G01Y41733D02*
X109055D01*
G01X79922D02*
X81496D01*
G01X107481Y40389D02*
X109055D01*
G01X79922D02*
X81496D01*
G01X107481Y39764D02*
X109055D01*
G01X79922D02*
X81496D01*
G01X90552Y38977D02*
X83071D01*
G01X105906D02*
X98426D01*
G01Y38189D02*
X90552D01*
G01X87796Y37993D02*
X83071D01*
G01X105906D02*
X101181D01*
G01X107481Y37796D02*
X109055D01*
G01X79922D02*
X81496D01*
G01X107500Y37402D02*
X81477D01*
G01X79922Y36693D02*
X81496D01*
G01X109055D02*
X107481D01*
G01X87008Y36221D02*
X84252D01*
G01X104725D02*
X101969D01*
G01X87008Y35955D02*
X84252D01*
G01X104725D02*
X101969D01*
G01X86713Y35552D02*
X86989D01*
G01X84370D02*
X85473D01*
G01X85519Y35317D02*
X84646D01*
G01X87008Y35106D02*
X84252D01*
G01X104725D02*
X101969D01*
G01X87008Y35040D02*
X84252D01*
G01X104725D02*
X101969D01*
G01X87008Y34973D02*
X84252D01*
G01X104725D02*
X101969D01*
G01X84646Y34613D02*
X85519D01*
G01X85473Y34332D02*
X84646D01*
G01X87008Y34125D02*
X84252D01*
G01X104725D02*
X101969D01*
G01X87008Y33859D02*
X84252D01*
G01X104725D02*
X101969D01*
G01X81496Y33544D02*
X79922D01*
G01X109055D02*
X107481D01*
G01X84646Y33347D02*
X84370D01*
G01X86989D02*
X86713D01*
G01X107481Y29311D02*
X109055D01*
G01X79922D02*
X81496D01*
G01Y28130D02*
X79922D01*
G01X109055D02*
X107481D01*
G01Y26162D02*
X109055D01*
G01X79922D02*
X81496D01*
G01X106693Y25985D02*
X82284D01*
G01X106693Y24410D02*
X82284D01*
G01X100459Y2489D02*
X101378Y15355D01*
G01X120197Y3937D02*
Y429331D01*
G01X111221Y45670D02*
Y42914D01*
G01X111085Y45670D02*
Y42914D01*
G01X111062D02*
Y45670D01*
G01X109646D02*
Y42914D01*
G01X109588Y45670D02*
Y42914D01*
G01X109578D02*
Y45670D01*
G01X109057D02*
Y42914D01*
G01X109055Y50197D02*
Y26162D01*
G01X107560Y45670D02*
Y42914D01*
G01X107500Y39253D02*
Y37402D01*
G01X107481Y26162D02*
Y50197D01*
G01X88386Y22835D02*
X83662D01*
G01X105315D02*
X100591D01*
G01X101378Y15355D02*
X87599D01*
G01X100459Y2489D02*
X88518D01*
G01X99478Y1575D02*
X89499D01*
G01X106693Y37402D02*
Y25985D01*
G01X106103D02*
Y24410D01*
G01X105926Y39253D02*
Y37402D01*
G01X105906D02*
Y38977D01*
G01X105512Y37402D02*
Y25985D01*
G01X105315Y22835D02*
Y24410D01*
G01X104725Y33859D02*
Y36221D01*
G01X104528Y25985D02*
Y24410D01*
G01X104134Y35040D02*
Y33859D01*
G01X102559D02*
Y35040D01*
G01X101969Y36221D02*
Y33859D01*
G01X101772Y25985D02*
Y24410D01*
G01X101378Y15355D02*
Y25985D01*
G01X101181Y37993D02*
Y38977D01*
G01X100985Y25985D02*
Y24410D01*
G01X100591Y22835D02*
Y24410D01*
G01X100394Y37402D02*
Y38977D01*
G01Y25985D02*
Y24410D01*
G01X98426Y38977D02*
Y38189D01*
G01X97441Y25985D02*
Y24410D01*
G01X91536Y25985D02*
Y24410D01*
G01X90552Y38977D02*
Y38189D01*
G01X88583Y25985D02*
Y24410D01*
G01Y38977D02*
Y37402D01*
G01X88386Y22835D02*
Y24410D01*
G01X87992Y25985D02*
Y24410D01*
G01X87796Y37993D02*
Y38977D01*
G01X87599Y15355D02*
Y25985D01*
G01X87205D02*
Y24410D01*
G01X87008Y33859D02*
Y36221D01*
G01X86989Y35552D02*
Y33347D01*
G01X86713D02*
Y35176D01*
G01X86437Y34848D02*
Y35223D01*
G01X86418Y35040D02*
Y33859D01*
G01X86070Y35036D02*
Y34848D01*
G01X85794Y34895D02*
Y35036D01*
G01X84843Y35040D02*
Y33859D01*
G01X84646Y35317D02*
Y34613D01*
G01Y34332D02*
Y33347D01*
G01X84449Y25985D02*
Y24410D01*
G01X84370Y33347D02*
Y35552D01*
G01X84252Y33859D02*
Y36221D01*
G01X83662Y22835D02*
Y24410D01*
G01X83465Y37402D02*
Y25985D01*
G01X83071Y37402D02*
Y38977D01*
G01X83052Y39253D02*
Y37402D01*
G01X82874Y25985D02*
Y24410D01*
G01X82284Y37402D02*
Y25985D01*
G01X81496Y26162D02*
Y50197D01*
G01X81477Y39253D02*
Y37402D01*
G01X81417Y42914D02*
Y45670D01*
G01X79922Y26162D02*
Y50197D01*
G01X79920Y42914D02*
Y45670D01*
G01X79399D02*
Y42914D01*
G01X79389D02*
Y45670D01*
G01X79331D02*
Y42914D01*
G01X77915Y45670D02*
Y42914D01*
G01X77892D02*
Y45670D01*
G01X77756D02*
Y42914D01*
G01X85473Y35552D02*
X85702Y35505D01*
G01X88518Y2489D02*
X87599Y15355D01*
G01X86024Y35176D02*
X86070Y35036D01*
G01X85794D02*
X85748Y35176D01*
G01X85657Y35270D02*
X85519Y35317D01*
G01X85886Y35364D02*
X86024Y35176D01*
G01X85748D02*
X85657Y35270D01*
G01X109999Y42914D02*
X109201Y43549D01*
G01X107717D02*
X108516Y42914D01*
G01X81260Y45034D02*
X80462Y45670D01*
G01X78978D02*
X79776Y45034D01*
G01X85702Y35505D02*
X85886Y35364D01*
G01X128071Y74016D02*
Y425394D01*
G01X120197Y74016D02*
G03X128071I3937J0D01*
G01X83071Y245079D02*
G03Y231693I0J-6693D01*
G01X96457D02*
G03Y245079I0J6693D01*
G01D02*
X83071D01*
G01X96457Y231693D02*
X83071D01*
G01X96654Y413583D02*
G03I-6496J0D01*
G01X188504Y425394D02*
X128071D01*
G01X124134Y433268D02*
G03X120197Y429331I0J-3937D01*
G01X283583Y433268D02*
X124134D01*
G01X79694Y1463291D02*
Y1444354D01*
G01X199469Y-675095D02*
Y-419189D01*
G01Y-675095D02*
X1144351D01*
G01X143525Y-714465D02*
X533288D01*
G01X1144351Y-614831D02*
X199469D01*
G01Y-524579D02*
X1144351D01*
G01X199469Y-569705D02*
X730696D01*
G01X199469Y-479453D02*
X1144351D01*
G01X199469Y-419189D02*
X1144351D01*
G01X152497Y21054D02*
G03I-4291J0D01*
G01X188504Y425394D02*
G03Y433268I0J3937D01*
G01X150394Y533465D02*
X225197D01*
G01X150394Y608268D02*
Y533465D01*
G01X225197Y608268D02*
X150394D01*
G01X195198Y684856D02*
X195181Y684671D01*
G01X195253Y685044D02*
X195198Y684856D01*
G01X195351Y685228D02*
X195253Y685044D01*
G01X195491Y685394D02*
X195351Y685228D01*
G01X206253Y682536D02*
X206168Y682508D01*
G01X206334Y682569D02*
X206253Y682536D01*
G01X206413Y682607D02*
X206334Y682569D01*
G01X206489Y682650D02*
X206413Y682607D01*
G01X206562Y682697D02*
X206489Y682650D01*
G01X206628Y682745D02*
X206562Y682697D01*
G01X207132Y685510D02*
X207150Y685513D01*
G01X207112Y685500D02*
X207132Y685510D01*
G01X207089Y685484D02*
X207112Y685500D01*
G01X204855Y686044D02*
X205014Y686063D01*
G01X204704Y685987D02*
X204855Y686044D01*
G01X204571Y685896D02*
X204704Y685987D01*
G01X208795Y686044D02*
X208954Y686063D01*
G01X208644Y685987D02*
X208795Y686044D01*
G01X208511Y685896D02*
X208644Y685987D01*
G01X204983Y685510D02*
X205014Y685513D01*
G01X204954Y685500D02*
X204983Y685510D01*
G01X204928Y685484D02*
X204954Y685500D01*
G01X210193Y682536D02*
X210108Y682508D01*
G01X210274Y682569D02*
X210193Y682536D01*
G01X210353Y682607D02*
X210274Y682569D01*
G01X210429Y682650D02*
X210353Y682607D01*
G01X210502Y682697D02*
X210429Y682650D01*
G01X210568Y682745D02*
X210502Y682697D01*
G01X203449Y677307D02*
X203534Y677336D01*
G01X203368Y677274D02*
X203449Y677307D01*
G01X203289Y677236D02*
X203368Y677274D01*
G01X203213Y677194D02*
X203289Y677236D01*
G01X203140Y677146D02*
X203213Y677194D01*
G01X203074Y677098D02*
X203140Y677146D01*
G01X207389Y677307D02*
X207474Y677336D01*
G01X207308Y677274D02*
X207389Y677307D01*
G01X207229Y677236D02*
X207308Y677274D01*
G01X207153Y677194D02*
X207229Y677236D01*
G01X207080Y677146D02*
X207153Y677194D01*
G01X207014Y677098D02*
X207080Y677146D01*
G01X211329Y677307D02*
X211414Y677336D01*
G01X211248Y677274D02*
X211329Y677307D01*
G01X211169Y677236D02*
X211248Y677274D01*
G01X211093Y677194D02*
X211169Y677236D01*
G01X211020Y677146D02*
X211093Y677194D01*
G01X210954Y677098D02*
X211020Y677146D01*
G01X211072Y685510D02*
X211090Y685513D01*
G01X211052Y685500D02*
X211072Y685510D01*
G01X211029Y685484D02*
X211052Y685500D01*
G01X202571Y674333D02*
X202553Y674330D01*
G01X202590Y674343D02*
X202571Y674333D01*
G01X202613Y674360D02*
X202590Y674343D01*
G01X206511Y674333D02*
X206493Y674330D01*
G01X206530Y674343D02*
X206511Y674333D01*
G01X206553Y674360D02*
X206530Y674343D01*
G01X210451Y674333D02*
X210433Y674330D01*
G01X210470Y674343D02*
X210451Y674333D01*
G01X210493Y674360D02*
X210470Y674343D01*
G01X204848Y673799D02*
X204688Y673780D01*
G01X204998Y673856D02*
X204848Y673799D01*
G01X205131Y673948D02*
X204998Y673856D01*
G01X208788Y673799D02*
X208628Y673780D01*
G01X208938Y673856D02*
X208788Y673799D01*
G01X209071Y673948D02*
X208938Y673856D01*
G01X208923Y685510D02*
X208954Y685513D01*
G01X208894Y685500D02*
X208923Y685510D01*
G01X208868Y685484D02*
X208894Y685500D01*
G01X204719Y674333D02*
X204688Y674330D01*
G01X204748Y674343D02*
X204719Y674333D01*
G01X204774Y674360D02*
X204748Y674343D01*
G01X208659Y674333D02*
X208628Y674330D01*
G01X208688Y674343D02*
X208659Y674333D01*
G01X208714Y674360D02*
X208688Y674343D01*
G01X206253Y682255D02*
X206168Y682232D01*
G01X206334Y682282D02*
X206253Y682255D01*
G01X206413Y682313D02*
X206334Y682282D01*
G01X206489Y682348D02*
X206413Y682313D01*
G01X206562Y682386D02*
X206489Y682348D01*
G01X206628Y682426D02*
X206562Y682386D01*
G01X210193Y682255D02*
X210108Y682232D01*
G01X210274Y682282D02*
X210193Y682255D01*
G01X210353Y682313D02*
X210274Y682282D01*
G01X210429Y682348D02*
X210353Y682313D01*
G01X210502Y682386D02*
X210429Y682348D01*
G01X210568Y682426D02*
X210502Y682386D01*
G01X203449Y677588D02*
X203534Y677612D01*
G01X203368Y677561D02*
X203449Y677588D01*
G01X203289Y677530D02*
X203368Y677561D01*
G01X203213Y677495D02*
X203289Y677530D01*
G01X203140Y677457D02*
X203213Y677495D01*
G01X203074Y677417D02*
X203140Y677457D01*
G01X207389Y677588D02*
X207474Y677612D01*
G01X207308Y677561D02*
X207389Y677588D01*
G01X207229Y677530D02*
X207308Y677561D01*
G01X207153Y677495D02*
X207229Y677530D01*
G01X207080Y677457D02*
X207153Y677495D01*
G01X207014Y677417D02*
X207080Y677457D01*
G01X211329Y677588D02*
X211414Y677612D01*
G01X211248Y677561D02*
X211329Y677588D01*
G01X211169Y677530D02*
X211248Y677561D01*
G01X211093Y677495D02*
X211169Y677530D01*
G01X211020Y677457D02*
X211093Y677495D01*
G01X210954Y677417D02*
X211020Y677457D01*
G01X206557Y682242D02*
X206628Y682294D01*
G01X206483Y682195D02*
X206557Y682242D01*
G01X206407Y682153D02*
X206483Y682195D01*
G01X206328Y682116D02*
X206407Y682153D01*
G01X206247Y682083D02*
X206328Y682116D01*
G01X206168Y682057D02*
X206247Y682083D01*
G01X210497Y682242D02*
X210568Y682294D01*
G01X210423Y682195D02*
X210497Y682242D01*
G01X210347Y682153D02*
X210423Y682195D01*
G01X210268Y682116D02*
X210347Y682153D01*
G01X210187Y682083D02*
X210268Y682116D01*
G01X210108Y682057D02*
X210187Y682083D01*
G01X203146Y677601D02*
X203074Y677549D01*
G01X203219Y677648D02*
X203146Y677601D01*
G01X203295Y677690D02*
X203219Y677648D01*
G01X203374Y677728D02*
X203295Y677690D01*
G01X203456Y677760D02*
X203374Y677728D01*
G01X203534Y677787D02*
X203456Y677760D01*
G01X207086Y677601D02*
X207014Y677549D01*
G01X207159Y677648D02*
X207086Y677601D01*
G01X207235Y677690D02*
X207159Y677648D01*
G01X207314Y677728D02*
X207235Y677690D01*
G01X207396Y677760D02*
X207314Y677728D01*
G01X207474Y677787D02*
X207396Y677760D01*
G01X211026Y677601D02*
X210954Y677549D01*
G01X211099Y677648D02*
X211026Y677601D01*
G01X211175Y677690D02*
X211099Y677648D01*
G01X211254Y677728D02*
X211175Y677690D01*
G01X211336Y677760D02*
X211254Y677728D01*
G01X211414Y677787D02*
X211336Y677760D01*
G01X202566Y674296D02*
X202596Y674339D01*
G01X202554Y674265D02*
X202566Y674296D01*
G01X202553Y674254D02*
X202554Y674265D01*
G01X207136Y685547D02*
X207107Y685504D01*
G01X207148Y685578D02*
X207136Y685547D01*
G01X207150Y685589D02*
X207148Y685578D01*
G01X206506Y674296D02*
X206536Y674339D01*
G01X206494Y674265D02*
X206506Y674296D01*
G01X206493Y674254D02*
X206494Y674265D01*
G01X211076Y685547D02*
X211047Y685504D01*
G01X211088Y685578D02*
X211076Y685547D01*
G01X211090Y685589D02*
X211088Y685578D01*
G01X210446Y674296D02*
X210476Y674339D01*
G01X210434Y674265D02*
X210446Y674296D01*
G01X210433Y674254D02*
X210434Y674265D01*
G01X204696Y673780D02*
X204699D01*
G01X204693D02*
X204696D01*
G01X204691Y673781D02*
X204693Y673780D01*
G01X204689Y673782D02*
X204691Y673781D01*
G01X204689Y673783D02*
Y673782D01*
G01X204688Y673784D02*
X204689Y673783D01*
G01X205007Y686063D02*
X205003D01*
G01X205009D02*
X205007D01*
G01X205011D02*
X205009D01*
G01X205013Y686062D02*
X205011Y686063D01*
G01X205014Y686061D02*
X205013Y686062D01*
G01X205014Y686060D02*
Y686061D01*
G01X208636Y673780D02*
X208639D01*
G01X208633D02*
X208636D01*
G01X208631Y673781D02*
X208633Y673780D01*
G01X208629Y673782D02*
X208631Y673781D01*
G01X208629Y673783D02*
Y673782D01*
G01X208628Y673784D02*
X208629Y673783D01*
G01X208947Y686063D02*
X208943D01*
G01X208949D02*
X208947D01*
G01X208951D02*
X208949D01*
G01X208953Y686062D02*
X208951Y686063D01*
G01X208954Y686061D02*
X208953Y686062D01*
G01X208954Y686060D02*
Y686061D01*
G01X205208Y674265D02*
X205210Y674254D01*
G01X205196Y674296D02*
X205208Y674265D01*
G01X205167Y674339D02*
X205196Y674296D01*
G01X209148Y674265D02*
X209150Y674254D01*
G01X209136Y674296D02*
X209148Y674265D01*
G01X209107Y674339D02*
X209136Y674296D01*
G01X204494Y685578D02*
X204493Y685589D01*
G01X204506Y685547D02*
X204494Y685578D01*
G01X204536Y685504D02*
X204506Y685547D01*
G01X208434Y685578D02*
X208433Y685589D01*
G01X208446Y685547D02*
X208434Y685578D01*
G01X208476Y685504D02*
X208446Y685547D01*
G01X195198Y674988D02*
X195181Y675173D01*
G01X195253Y674800D02*
X195198Y674988D01*
G01X195351Y674616D02*
X195253Y674800D01*
G01X195491Y674449D02*
X195351Y674616D01*
G01X204693Y674330D02*
X204699D01*
G01X204689Y674331D02*
X204693Y674330D01*
G01X204688Y674332D02*
X204689Y674331D01*
G01X208633Y674330D02*
X208639D01*
G01X208629Y674331D02*
X208633Y674330D01*
G01X208628Y674332D02*
X208629Y674331D01*
G01X205009Y685513D02*
X205003D01*
G01X205013Y685512D02*
X205009Y685513D01*
G01X205014Y685511D02*
X205013Y685512D01*
G01X208949Y685513D02*
X208943D01*
G01X208953Y685512D02*
X208949Y685513D01*
G01X208954Y685511D02*
X208953Y685512D01*
G01X204324Y674835D02*
X204242Y674857D01*
G01X204401Y674810D02*
X204324Y674835D01*
G01X204480Y674779D02*
X204401Y674810D01*
G01X204552Y674746D02*
X204480Y674779D01*
G01X204621Y674711D02*
X204552Y674746D01*
G01X204688Y674672D02*
X204621Y674711D01*
G01X204324Y677759D02*
X204242Y677787D01*
G01X204401Y677728D02*
X204324Y677759D01*
G01X204480Y677691D02*
X204401Y677728D01*
G01X204552Y677651D02*
X204480Y677691D01*
G01X204621Y677608D02*
X204552Y677651D01*
G01X204688Y677560D02*
X204621Y677608D01*
G01X208264Y677759D02*
X208182Y677787D01*
G01X208341Y677728D02*
X208264Y677759D01*
G01X208420Y677691D02*
X208341Y677728D01*
G01X208492Y677651D02*
X208420Y677691D01*
G01X208561Y677608D02*
X208492Y677651D01*
G01X208628Y677560D02*
X208561Y677608D01*
G01X205378Y682084D02*
X205460Y682057D01*
G01X205302Y682115D02*
X205378Y682084D01*
G01X205223Y682152D02*
X205302Y682115D01*
G01X205150Y682192D02*
X205223Y682152D01*
G01X205081Y682236D02*
X205150Y682192D01*
G01X205014Y682283D02*
X205081Y682236D01*
G01X212204Y677759D02*
X212122Y677787D01*
G01X209318Y682084D02*
X209400Y682057D01*
G01X209242Y682115D02*
X209318Y682084D01*
G01X209163Y682152D02*
X209242Y682115D01*
G01X209090Y682192D02*
X209163Y682152D01*
G01X209021Y682236D02*
X209090Y682192D01*
G01X208954Y682283D02*
X209021Y682236D01*
G01X195809Y673932D02*
X195955Y673922D01*
G01X195680Y673942D02*
X195809Y673932D01*
G01X195578Y673953D02*
X195680Y673942D01*
G01X195513Y673963D02*
X195578Y673953D01*
G01X195491Y673973D02*
X195513Y673963D01*
G01X208264Y674835D02*
X208182Y674857D01*
G01X208341Y674810D02*
X208264Y674835D01*
G01X208420Y674779D02*
X208341Y674810D01*
G01X208492Y674746D02*
X208420Y674779D01*
G01X208561Y674711D02*
X208492Y674746D01*
G01X208628Y674672D02*
X208561Y674711D01*
G01X212204Y674835D02*
X212122Y674857D01*
G01X205378Y685008D02*
X205460Y684986D01*
G01X205302Y685034D02*
X205378Y685008D01*
G01X205223Y685064D02*
X205302Y685034D01*
G01X205150Y685097D02*
X205223Y685064D01*
G01X205081Y685133D02*
X205150Y685097D01*
G01X205014Y685172D02*
X205081Y685133D01*
G01X209318Y685008D02*
X209400Y684986D01*
G01X209242Y685034D02*
X209318Y685008D01*
G01X209163Y685064D02*
X209242Y685034D01*
G01X209090Y685097D02*
X209163Y685064D01*
G01X209021Y685133D02*
X209090Y685097D01*
G01X208954Y685172D02*
X209021Y685133D01*
G01X204619Y677158D02*
X204688Y677109D01*
G01X204549Y677202D02*
X204619Y677158D01*
G01X204472Y677244D02*
X204549Y677202D01*
G01X204398Y677279D02*
X204472Y677244D01*
G01X204321Y677309D02*
X204398Y677279D01*
G01X204242Y677336D02*
X204321Y677309D01*
G01X208559Y677158D02*
X208628Y677109D01*
G01X208489Y677202D02*
X208559Y677158D01*
G01X208412Y677244D02*
X208489Y677202D01*
G01X208338Y677279D02*
X208412Y677244D01*
G01X208261Y677309D02*
X208338Y677279D01*
G01X208182Y677336D02*
X208261Y677309D01*
G01X212122Y677336D02*
X212201Y677309D01*
G01X205172Y674343D02*
X205149Y674360D01*
G01X205192Y674333D02*
X205172Y674343D01*
G01X205210Y674330D02*
X205192Y674333D01*
G01X209112Y674343D02*
X209089Y674360D01*
G01X209132Y674333D02*
X209112Y674343D01*
G01X209150Y674330D02*
X209132Y674333D01*
G01X195422Y673939D02*
X195914Y673922D01*
G01X195222Y673947D02*
X195422Y673939D01*
G01X195069Y673956D02*
X195222Y673947D01*
G01X194974Y673965D02*
X195069Y673956D01*
G01X194941Y673973D02*
X194974Y673965D01*
G01X204619Y677467D02*
X204688Y677426D01*
G01X204549Y677502D02*
X204619Y677467D01*
G01X204472Y677536D02*
X204549Y677502D01*
G01X204398Y677565D02*
X204472Y677536D01*
G01X204321Y677590D02*
X204398Y677565D01*
G01X204242Y677612D02*
X204321Y677590D01*
G01X208559Y677467D02*
X208628Y677426D01*
G01X208489Y677502D02*
X208559Y677467D01*
G01X208412Y677536D02*
X208489Y677502D01*
G01X208338Y677565D02*
X208412Y677536D01*
G01X208261Y677590D02*
X208338Y677565D01*
G01X208182Y677612D02*
X208261Y677590D01*
G01X212122Y677612D02*
X212201Y677590D01*
G01X205084Y682377D02*
X205014Y682417D01*
G01X205153Y682341D02*
X205084Y682377D01*
G01X205230Y682307D02*
X205153Y682341D01*
G01X205305Y682278D02*
X205230Y682307D01*
G01X205381Y682253D02*
X205305Y682278D01*
G01X205460Y682232D02*
X205381Y682253D01*
G01X209024Y682377D02*
X208954Y682417D01*
G01X209093Y682341D02*
X209024Y682377D01*
G01X209170Y682307D02*
X209093Y682341D01*
G01X209245Y682278D02*
X209170Y682307D01*
G01X209321Y682253D02*
X209245Y682278D01*
G01X209400Y682232D02*
X209321Y682253D01*
G01X205084Y682685D02*
X205014Y682734D01*
G01X205153Y682641D02*
X205084Y682685D01*
G01X205230Y682600D02*
X205153Y682641D01*
G01X205305Y682565D02*
X205230Y682600D01*
G01X205381Y682534D02*
X205305Y682565D01*
G01X205460Y682508D02*
X205381Y682534D01*
G01X209024Y682685D02*
X208954Y682734D01*
G01X209093Y682641D02*
X209024Y682685D01*
G01X209170Y682600D02*
X209093Y682641D01*
G01X209245Y682565D02*
X209170Y682600D01*
G01X209321Y682534D02*
X209245Y682565D01*
G01X209400Y682508D02*
X209321Y682534D01*
G01X203014Y674343D02*
X202988Y674360D01*
G01X203043Y674333D02*
X203014Y674343D01*
G01X203074Y674330D02*
X203043Y674333D01*
G01X206954Y674343D02*
X206928Y674360D01*
G01X206983Y674333D02*
X206954Y674343D01*
G01X207014Y674330D02*
X206983Y674333D01*
G01X210894Y674343D02*
X210868Y674360D01*
G01X210923Y674333D02*
X210894Y674343D01*
G01X210954Y674330D02*
X210923Y674333D01*
G01X206688Y685500D02*
X206714Y685484D01*
G01X206659Y685510D02*
X206688Y685500D01*
G01X206628Y685513D02*
X206659Y685510D01*
G01X210628Y685500D02*
X210654Y685484D01*
G01X210599Y685510D02*
X210628Y685500D01*
G01X210568Y685513D02*
X210599Y685510D01*
G01X202764Y673856D02*
X202631Y673948D01*
G01X202915Y673799D02*
X202764Y673856D01*
G01X203074Y673780D02*
X202915Y673799D01*
G01X206704Y673856D02*
X206571Y673948D01*
G01X206855Y673799D02*
X206704Y673856D01*
G01X207014Y673780D02*
X206855Y673799D01*
G01X210644Y673856D02*
X210511Y673948D01*
G01X210795Y673799D02*
X210644Y673856D01*
G01X210954Y673780D02*
X210795Y673799D01*
G01X206938Y685987D02*
X207071Y685896D01*
G01X206788Y686044D02*
X206938Y685987D01*
G01X206628Y686063D02*
X206788Y686044D01*
G01X210878Y685987D02*
X211011Y685896D01*
G01X210728Y686044D02*
X210878Y685987D01*
G01X210568Y686063D02*
X210728Y686044D01*
G01X204530Y685500D02*
X204553Y685484D01*
G01X204511Y685510D02*
X204530Y685500D01*
G01X204493Y685513D02*
X204511Y685510D01*
G01X208470Y685500D02*
X208493Y685484D01*
G01X208451Y685510D02*
X208470Y685500D01*
G01X208433Y685513D02*
X208451Y685510D01*
G01X195513Y685881D02*
X195491Y685870D01*
G01X195578Y685891D02*
X195513Y685881D01*
G01X195680Y685901D02*
X195578Y685891D01*
G01X195809Y685911D02*
X195680Y685901D01*
G01X195955Y685922D02*
X195809Y685911D01*
G01X210953Y674331D02*
X210954Y674332D01*
G01X210949Y674330D02*
X210953Y674331D01*
G01X210943Y674330D02*
X210949D01*
G01X207013Y674331D02*
X207014Y674332D01*
G01X207009Y674330D02*
X207013Y674331D01*
G01X207003Y674330D02*
X207009D01*
G01X203073Y674331D02*
X203074Y674332D01*
G01X203069Y674330D02*
X203073Y674331D01*
G01X203063Y674330D02*
X203069D01*
G01X210569Y685512D02*
X210568Y685511D01*
G01X210573Y685513D02*
X210569Y685512D01*
G01X210579Y685513D02*
X210573D01*
G01X206629Y685512D02*
X206628Y685511D01*
G01X206633Y685513D02*
X206629Y685512D01*
G01X206639Y685513D02*
X206633D01*
G01X194974Y685879D02*
X194941Y685870D01*
G01X195069Y685887D02*
X194974Y685879D01*
G01X195222Y685896D02*
X195069Y685887D01*
G01X195422Y685905D02*
X195222Y685896D01*
G01X210954Y673782D02*
Y673784D01*
G01X210953Y673781D02*
X210954Y673782D01*
G01X210951Y673781D02*
X210953D01*
G01X210949Y673780D02*
X210951Y673781D01*
G01X210946Y673780D02*
X210949D01*
G01X210943D02*
X210946D01*
G01X207014Y673782D02*
Y673784D01*
G01X207013Y673781D02*
X207014Y673782D01*
G01X207011Y673781D02*
X207013D01*
G01X207009Y673780D02*
X207011Y673781D01*
G01X207006Y673780D02*
X207009D01*
G01X207003D02*
X207006D01*
G01X203074Y673782D02*
Y673784D01*
G01X203073Y673781D02*
X203074Y673782D01*
G01X203071Y673781D02*
X203073D01*
G01X203069Y673780D02*
X203071Y673781D01*
G01X203066Y673780D02*
X203069D01*
G01X203063D02*
X203066D01*
G01X210569Y686061D02*
X210568Y686060D01*
G01X210570Y686062D02*
X210569Y686061D01*
G01X210571Y686063D02*
X210570Y686062D01*
G01X210573Y686063D02*
X210571D01*
G01X210576D02*
X210573D01*
G01X210579D02*
X210576D01*
G01X206629Y686061D02*
X206628Y686060D01*
G01X206630Y686062D02*
X206629Y686061D01*
G01X206631Y686063D02*
X206630Y686062D01*
G01X206633Y686063D02*
X206631D01*
G01X206636D02*
X206633D01*
G01X206639D02*
X206636D01*
G01X195978Y673919D02*
X195991Y673917D01*
G01X195965Y673920D02*
X195978Y673919D01*
G01X195951Y673921D02*
X195965Y673920D01*
G01X195939Y673921D02*
X195951D01*
G01X195927Y673922D02*
X195939Y673921D01*
G01X195914Y673922D02*
X195927D01*
G01X195985Y673919D02*
X195991Y673917D01*
G01X195979Y673920D02*
X195985Y673919D01*
G01X195972Y673921D02*
X195979Y673920D01*
G01X195967Y673921D02*
X195972D01*
G01X195961Y673922D02*
X195967Y673921D01*
G01X195955Y673922D02*
X195961D01*
G01X211026Y674705D02*
X210954Y674663D01*
G01X211099Y674744D02*
X211026Y674705D01*
G01X211175Y674778D02*
X211099Y674744D01*
G01X211254Y674809D02*
X211175Y674778D01*
G01X211336Y674836D02*
X211254Y674809D01*
G01X211414Y674857D02*
X211336Y674836D01*
G01X207086Y674705D02*
X207014Y674663D01*
G01X207159Y674744D02*
X207086Y674705D01*
G01X207235Y674778D02*
X207159Y674744D01*
G01X207314Y674809D02*
X207235Y674778D01*
G01X207396Y674836D02*
X207314Y674809D01*
G01X207474Y674857D02*
X207396Y674836D01*
G01X203146Y674705D02*
X203074Y674663D01*
G01X203219Y674744D02*
X203146Y674705D01*
G01X203295Y674778D02*
X203219Y674744D01*
G01X203374Y674809D02*
X203295Y674778D01*
G01X203456Y674836D02*
X203374Y674809D01*
G01X203534Y674857D02*
X203456Y674836D01*
G01X210497Y685138D02*
X210568Y685181D01*
G01X210423Y685100D02*
X210497Y685138D01*
G01X210347Y685065D02*
X210423Y685100D01*
G01X210268Y685034D02*
X210347Y685065D01*
G01X210187Y685008D02*
X210268Y685034D01*
G01X210108Y684986D02*
X210187Y685008D01*
G01X206557Y685138D02*
X206628Y685181D01*
G01X206483Y685100D02*
X206557Y685138D01*
G01X206407Y685065D02*
X206483Y685100D01*
G01X206328Y685034D02*
X206407Y685065D01*
G01X206247Y685008D02*
X206328Y685034D01*
G01X206168Y684986D02*
X206247Y685008D01*
G01X195961Y685922D02*
X195955D01*
G01X195967D02*
X195961D01*
G01X195974Y685923D02*
X195967Y685922D01*
G01X195979Y685924D02*
X195974Y685923D01*
G01X195985Y685925D02*
X195979Y685924D01*
G01X195991Y685926D02*
X195985Y685925D01*
G01X195928Y685922D02*
X195914D01*
G01X195940D02*
X195928D01*
G01X195954Y685923D02*
X195940Y685922D01*
G01X195967Y685924D02*
X195954Y685923D01*
G01X195979Y685925D02*
X195967Y685924D01*
G01X195991Y685926D02*
X195979Y685925D01*
G01X206173Y682005D02*
G03X206639Y682254I-423J1352D01*
G01X205003Y682243D02*
G03X205455Y682005I875J1114D01*
G01X210113D02*
G03X210579Y682254I-423J1352D01*
G01X208943Y682243D02*
G03X209395Y682005I875J1114D01*
G01X212550Y671072D02*
G03X212039Y671583I-511J0D01*
G01X211539D02*
G03X211027Y671072I0J-512D01*
G01X208627D02*
G03X208115Y671583I-511J0D01*
G01X207615D02*
G03X207103Y671072I0J-512D01*
G01X204703D02*
G03X204191Y671583I-511J0D01*
G01X207469Y677838D02*
G03X207003Y677589I423J-1352D01*
G01X208639Y677600D02*
G03X208188Y677838I-876J-1114D01*
G01X211409D02*
G03X210943Y677589I423J-1352D01*
G01X195994Y685911D02*
G03X195941Y686537I-53J311D01*
G01X193526Y685242D02*
G03X194017Y684980I315J0D01*
G01X203141Y684252D02*
G03I-1250J0D01*
G01X195941Y673307D02*
G03X195994Y673932I0J315D01*
G01X194017Y674863D02*
G03X193526Y674602I-176J-261D01*
G01X203691Y671583D02*
G03X203179Y671072I0J-512D01*
G01X199338Y678017D02*
G03X200001Y677265I253J-445D01*
G01X203529Y677838D02*
G03X203063Y677589I423J-1352D01*
G01X204699Y677600D02*
G03X204248Y677838I-876J-1114D01*
G01X169095Y669292D02*
G03I-5906J0D01*
G01X169607D02*
G03I-6418J0D01*
G01X169685D02*
G03I-6496J0D01*
G01X170552D02*
G03I-7363J0D01*
G01X171063D02*
G03I-7874J0D01*
G01D02*
G03I-7874J0D01*
G01X171457D02*
G03I-8268J0D01*
G01X172520D02*
G03I-9331J0D01*
G01X173032D02*
G03I-9843J0D01*
G01X211111Y686063D02*
X211090D01*
G01X207171D02*
X207150D01*
G01X210411Y673781D02*
X210433Y673780D01*
G01X206471Y673781D02*
X206493Y673780D01*
G01X206628Y691113D02*
X205014D01*
G01X210568D02*
X208954D01*
G01X199441Y690422D02*
X195941D01*
G01X214751Y689772D02*
X193541D01*
G01X214751Y688172D02*
X193541D01*
G01X214751Y687018D02*
X203791D01*
G01X206628Y686963D02*
X205014D01*
G01X210568D02*
X208954D01*
G01X207171Y686822D02*
X204471D01*
G01X211111D02*
X208411D01*
G01X206628Y686613D02*
X205014D01*
G01X210568D02*
X208954D01*
G01X203791Y686272D02*
X214751D01*
G01X206628Y686111D02*
X205014D01*
G01X210568D02*
X208954D01*
G01X203791Y686072D02*
X214751D01*
G01X207150Y686063D02*
X204493D01*
G01X211090D02*
X208433D01*
G01X195914Y685922D02*
X195954D01*
G01X208411Y685896D02*
X208511D01*
G01X211011D02*
X211111D01*
G01X204471D02*
X204571D01*
G01X207071D02*
X207171D01*
G01X195491Y685870D02*
X194941D01*
G01Y685669D02*
X195491D01*
G01X207150Y685513D02*
X204493D01*
G01X211090D02*
X208433D01*
G01X208493Y685484D02*
X208868D01*
G01X210654D02*
X211029D01*
G01X204553D02*
X204928D01*
G01X206714D02*
X207089D01*
G01X206628Y685421D02*
X205014D01*
G01X210568D02*
X208954D01*
G01X206771Y685372D02*
X208811D01*
G01X203791D02*
X204871D01*
G01X212751D02*
X210711D01*
G01X204871Y685157D02*
X203791D01*
G01X208811D02*
X206771D01*
G01X212751D02*
X210711D01*
G01X209400Y684986D02*
X210108D01*
G01X205460D02*
X206168D01*
G01X195181Y684671D02*
X194941D01*
G01X206628Y683647D02*
X205014D01*
G01X210568D02*
X208954D01*
G01X204871Y683572D02*
X201370D01*
G01X208811D02*
X206771D01*
G01X212751D02*
X210711D01*
G01X206628Y683116D02*
X205014D01*
G01X210568D02*
X208954D01*
G01X206628Y682666D02*
X205014D01*
G01X210568D02*
X208954D01*
G01Y682587D02*
X210568D01*
G01X205014D02*
X206628D01*
G01X204871Y682572D02*
X201006D01*
G01X206628D02*
X205014D01*
G01X208811D02*
X206771D01*
G01X210568D02*
X208954D01*
G01X212751D02*
X210711D01*
G01X210108Y682508D02*
X210568D01*
G01X208954D02*
X209400D01*
G01X206168D02*
X206628D01*
G01X205014D02*
X205460D01*
G01X196441Y682422D02*
X194941D01*
G01X206168Y682232D02*
X205460D01*
G01X210108D02*
X209400D01*
G01X194491Y682172D02*
X194941D01*
G01X195491D02*
X194941D01*
G01X209400Y682057D02*
X210108D01*
G01X205460D02*
X206168D01*
G01Y682022D02*
X205460D01*
G01X210108D02*
X209400D01*
G01X203791Y681972D02*
X199991D01*
G01X206771Y681122D02*
X204871D01*
G01X210711D02*
X208811D01*
G01X204831Y678722D02*
X202931D01*
G01X208771D02*
X206871D01*
G01X212711D02*
X210811D01*
G01X211414Y677822D02*
X212122D01*
G01X207474D02*
X208182D01*
G01X203534D02*
X204242D01*
G01Y677787D02*
X203534D01*
G01X208182D02*
X207474D01*
G01X212122D02*
X211414D01*
G01X194941Y677672D02*
X194491D01*
G01X195491D02*
X194941D01*
G01X211414Y677612D02*
X212122D01*
G01X207474D02*
X208182D01*
G01X203534D02*
X204242D01*
G01X196441Y677422D02*
X194941D01*
G01X203534Y677336D02*
X203074D01*
G01X204688D02*
X204242D01*
G01X207474D02*
X207014D01*
G01X208628D02*
X208182D01*
G01X211414D02*
X210954D01*
G01Y677272D02*
X212568D01*
G01X207014D02*
X208628D01*
G01X203074D02*
X204688D01*
G01X202931D02*
X199991D01*
G01X206871D02*
X204831D01*
G01X210811D02*
X208771D01*
G01X204688Y677256D02*
X203074D01*
G01X208628D02*
X207014D01*
G01X212568D02*
X210954D01*
G01Y677177D02*
X212568D01*
G01X207014D02*
X208628D01*
G01X203074D02*
X204688D01*
G01X210954Y676727D02*
X212568D01*
G01X207014D02*
X208628D01*
G01X203074D02*
X204688D01*
G01X208771Y676272D02*
X210811D01*
G01X204831D02*
X206871D01*
G01X198713D02*
X202931D01*
G01X210954Y676197D02*
X212568D01*
G01X207014D02*
X208628D01*
G01X203074D02*
X204688D01*
G01X194941Y675173D02*
X195181D01*
G01X204242Y674857D02*
X203534D01*
G01X208182D02*
X207474D01*
G01X212122D02*
X211414D01*
G01X208771Y674686D02*
X210811D01*
G01X204831D02*
X206871D01*
G01X199991D02*
X202931D01*
G01Y674472D02*
X199991D01*
G01X206871D02*
X204831D01*
G01X210811D02*
X208771D01*
G01X210954Y674423D02*
X212568D01*
G01X207014D02*
X208628D01*
G01X203074D02*
X204688D01*
G01X202988Y674360D02*
X202613D01*
G01X205149D02*
X204774D01*
G01X206928D02*
X206553D01*
G01X209089D02*
X208714D01*
G01X210868D02*
X210493D01*
G01X205210Y674330D02*
X202553D01*
G01X209150D02*
X206493D01*
G01X213090D02*
X210433D01*
G01X195491Y674174D02*
X194941D01*
G01Y673973D02*
X195491D01*
G01X202631Y673948D02*
X202531D01*
G01X205231D02*
X205131D01*
G01X206571D02*
X206471D01*
G01X209171D02*
X209071D01*
G01X210511D02*
X210411D01*
G01X195955Y673922D02*
X195914D01*
G01X205210Y673780D02*
X202553D01*
G01X209150D02*
X206493D01*
G01X213090D02*
X210433D01*
G01X199991Y673772D02*
X214751D01*
G01X210954Y673732D02*
X212568D01*
G01X207014D02*
X208628D01*
G01X203074D02*
X204688D01*
G01X214751Y673572D02*
X199991D01*
G01X210954Y673230D02*
X212568D01*
G01X207014D02*
X208628D01*
G01X203074D02*
X204688D01*
G01X210411Y673022D02*
X213111D01*
G01X206471D02*
X209171D01*
G01X202531D02*
X205231D01*
G01X210954Y672880D02*
X212568D01*
G01X207014D02*
X208628D01*
G01X203074D02*
X204688D01*
G01X199991Y672825D02*
X214751D01*
G01X193541Y671672D02*
X214751D01*
G01X204191Y671572D02*
X203691D01*
G01X208115D02*
X207615D01*
G01X212039D02*
X211539D01*
G01X203191Y670072D02*
X193541D01*
G01X207115D02*
X204691D01*
G01X211039D02*
X208615D01*
G01X199441Y669422D02*
X195941D01*
G01X204688Y668730D02*
X203074D01*
G01X208628D02*
X207014D01*
G01X212568D02*
X210954D01*
G01X204493Y686063D02*
X204471D01*
G01X208433D02*
X208411D01*
G01X205210Y673780D02*
X205231Y673781D01*
G01X209150Y673780D02*
X209171Y673781D01*
G01X195914Y685922D02*
X195422Y685905D01*
G01X202531Y673781D02*
X202553Y673780D01*
G01X194009Y674850D02*
X195491Y673851D01*
G01X211111Y685810D02*
X211011Y685896D01*
G01X210654Y685484D02*
X210786Y685372D01*
G01X207171Y685810D02*
X207071Y685896D01*
G01X206714Y685484D02*
X206846Y685372D01*
G01X210868Y674360D02*
X210736Y674472D01*
G01X210411Y674033D02*
X210511Y673948D01*
G01X206928Y674360D02*
X206796Y674472D01*
G01X206471Y674033D02*
X206571Y673948D01*
G01X202988Y674360D02*
X202856Y674472D01*
G01X202531Y674033D02*
X202631Y673948D01*
G01X208511Y685896D02*
X208868Y685484D01*
G01X208493D02*
X208411Y685579D01*
G01X204571Y685896D02*
X204928Y685484D01*
G01X204553D02*
X204471Y685579D01*
G01X209089Y674360D02*
X209171Y674265D01*
G01X209071Y673948D02*
X208714Y674360D01*
G01X205149D02*
X205231Y674265D01*
G01X205131Y673948D02*
X204774Y674360D01*
G01X211029Y685484D02*
X211047Y685372D01*
G01X210493Y674360D02*
X210475Y674472D01*
G01X207089Y685484D02*
X207107Y685372D01*
G01X206553Y674360D02*
X206535Y674472D01*
G01X202613Y674360D02*
X202595Y674472D01*
G01X211414Y674857D02*
Y677821D01*
G01X211111Y685372D02*
Y686822D01*
G01X211090Y685513D02*
Y686063D01*
G01X211039Y671072D02*
Y670072D01*
G01X210961Y685513D02*
Y686063D01*
G01X210954Y668730D02*
Y677575D01*
G01X210943Y674330D02*
Y673780D01*
G01X210914Y674330D02*
Y673780D01*
G01X210817Y686063D02*
Y685513D01*
G01X210811Y678722D02*
Y674472D01*
G01X210711Y685372D02*
Y681122D01*
G01X210706Y673780D02*
Y674330D01*
G01X210608Y685513D02*
Y686063D01*
G01X210579Y685513D02*
Y686063D01*
G01X210568Y682269D02*
Y691113D01*
G01X210561Y674330D02*
Y673780D01*
G01X210433Y674330D02*
Y673780D01*
G01X210411Y674472D02*
Y673022D01*
G01X210108Y684986D02*
Y682023D01*
G01X209400D02*
Y684986D01*
G01X209171Y674472D02*
Y673022D01*
G01X209150Y673780D02*
Y674330D01*
G01X209021Y673780D02*
Y674330D01*
G01X208954Y682257D02*
Y691113D01*
G01X208943Y686063D02*
Y685513D01*
G01X208914Y686063D02*
Y685513D01*
G01X208877Y674330D02*
Y673780D01*
G01X208811Y685372D02*
Y681122D01*
G01X208771Y678722D02*
Y674472D01*
G01X208706Y685513D02*
Y686063D01*
G01X208668Y673780D02*
Y674330D01*
G01X208639Y673780D02*
Y674330D01*
G01X208628Y677586D02*
Y668730D01*
G01X208615Y670072D02*
Y671072D01*
G01X208561Y686063D02*
Y685513D01*
G01X208433Y686063D02*
Y685513D01*
G01X208411Y686822D02*
Y685372D01*
G01X208182Y677821D02*
Y674857D01*
G01X207474D02*
Y677821D01*
G01X207171Y685372D02*
Y686822D01*
G01X207150Y685513D02*
Y686063D01*
G01X207115Y671072D02*
Y670072D01*
G01X207021Y685513D02*
Y686063D01*
G01X207014Y668730D02*
Y677575D01*
G01X207003Y674330D02*
Y673780D01*
G01X206974Y674330D02*
Y673780D01*
G01X206877Y686063D02*
Y685513D01*
G01X206871Y678722D02*
Y674472D01*
G01X206771Y685372D02*
Y681122D01*
G01X206766Y673780D02*
Y674330D01*
G01X206668Y685513D02*
Y686063D01*
G01X206639Y685513D02*
Y686063D01*
G01X206628Y682269D02*
Y691113D01*
G01X206621Y674330D02*
Y673780D01*
G01X206493Y674330D02*
Y673780D01*
G01X206471Y674472D02*
Y673022D01*
G01X206168Y684986D02*
Y682023D01*
G01X205460D02*
Y684986D01*
G01X205231Y674472D02*
Y673022D01*
G01X205210Y673780D02*
Y674330D01*
G01X205081Y673780D02*
Y674330D01*
G01X205014Y682257D02*
Y691113D01*
G01X205003Y686063D02*
Y685513D01*
G01X204974Y686063D02*
Y685513D01*
G01X204937Y674330D02*
Y673780D01*
G01X204871Y685372D02*
Y681122D01*
G01X204831Y678722D02*
Y674472D01*
G01X204766Y685513D02*
Y686063D01*
G01X204728Y673780D02*
Y674330D01*
G01X204699Y673780D02*
Y674330D01*
G01X204691Y670072D02*
Y671072D01*
G01X204688Y677586D02*
Y668730D01*
G01X204621Y686063D02*
Y685513D01*
G01X204493Y686063D02*
Y685513D01*
G01X204471Y686822D02*
Y685372D01*
G01X204242Y677821D02*
Y674857D01*
G01X203791Y688172D02*
Y686272D01*
G01Y686072D02*
Y681972D01*
G01X203534Y674857D02*
Y677821D01*
G01X203191Y671072D02*
Y670072D01*
G01X203074Y668730D02*
Y677575D01*
G01X203063Y674330D02*
Y673780D01*
G01X203034Y674330D02*
Y673780D01*
G01X202931Y678722D02*
Y674472D01*
G01X202826Y673780D02*
Y674330D01*
G01X202681D02*
Y673780D01*
G01X202553Y674330D02*
Y673780D01*
G01X202531Y674472D02*
Y673022D01*
G01X199991Y688172D02*
Y671672D01*
G01X199441Y669422D02*
Y690422D01*
G01X196501Y688172D02*
Y671672D01*
G01X196441Y682422D02*
Y677422D01*
G01X196201Y670072D02*
Y689772D01*
G01X195991Y682422D02*
Y685926D01*
G01Y673917D02*
Y677422D01*
G01X195941Y673322D02*
Y669422D01*
G01Y690422D02*
Y686522D01*
G01X195491Y685993D02*
Y673851D01*
G01X195344Y677672D02*
Y682172D01*
G01X195181Y677672D02*
Y675173D01*
G01Y684671D02*
Y682172D01*
G01X195122Y677672D02*
Y682172D01*
G01X194941Y685870D02*
Y673973D01*
G01X194867Y677672D02*
Y682172D01*
G01X194699Y677672D02*
Y682172D01*
G01X194491Y677672D02*
Y682172D01*
G01X193541Y674602D02*
Y670072D01*
G01Y689772D02*
Y685242D01*
G01X209107Y674472D02*
X209089Y674360D01*
G01X208475Y685372D02*
X208493Y685484D01*
G01X205167Y674472D02*
X205149Y674360D01*
G01X204535Y685372D02*
X204553Y685484D01*
G01X199122Y677398D02*
X198713Y676272D01*
G01X201370Y683572D02*
X199344Y678006D01*
G01X209071Y673948D02*
X209171Y674033D01*
G01X208714Y674360D02*
X208846Y674472D01*
G01X205131Y673948D02*
X205231Y674033D01*
G01X204774Y674360D02*
X204906Y674472D01*
G01X210868Y674360D02*
X210511Y673948D01*
G01X210411Y674265D02*
X210493Y674360D01*
G01X206928D02*
X206571Y673948D01*
G01X206471Y674265D02*
X206553Y674360D01*
G01X202988D02*
X202631Y673948D01*
G01X202531Y674265D02*
X202613Y674360D01*
G01X211111Y685579D02*
X211029Y685484D01*
G01X210654D02*
X211011Y685896D01*
G01X207171Y685579D02*
X207089Y685484D01*
G01X206714D02*
X207071Y685896D01*
G01X195491Y685993D02*
X194009Y684993D01*
G01X208868Y685484D02*
X208736Y685372D01*
G01X208511Y685896D02*
X208411Y685810D01*
G01X204928Y685484D02*
X204796Y685372D01*
G01X204571Y685896D02*
X204471Y685810D01*
G01X275709Y0D02*
G03X279646Y3937I0J3937D01*
G01X287520Y43308D02*
G03X279646I-3937J0D01*
G01Y3937D02*
Y43308D01*
G01Y74016D02*
Y425394D01*
G01Y74016D02*
G03X287520I3937J0D01*
G01X265438Y405580D02*
G03I-4291J0D01*
G01X219213Y433268D02*
G03Y425394I0J-3937D01*
G01X279646D02*
X219213D01*
G01X287520Y429331D02*
G03X283583Y433268I-3937J0D01*
G01X225197Y533465D02*
Y608268D01*
G01X224728Y608908D02*
X224812Y608924D01*
G01Y608842D02*
X224728Y608826D01*
G01X224410Y610237D02*
X225197D01*
G01X225113Y610138D02*
X224862D01*
G01X224762D02*
X224410D01*
G01X224963Y609728D02*
X225013D01*
G01Y609630D02*
X224946D01*
G01X225113Y609498D02*
X225197D01*
G01X224410D02*
X224946D01*
G01X225197Y609416D02*
X225113D01*
G01X224946D02*
X224410D01*
G01Y609285D02*
X224946D01*
G01Y609203D02*
X224862D01*
G01X224795D02*
X224410D01*
G01Y608908D02*
X224728D01*
G01Y608826D02*
X224410D01*
G01X224946Y608695D02*
X225080D01*
G01X224410Y608596D02*
X225063D01*
G01X225197Y608498D02*
X224410D01*
G01X224912Y609745D02*
X224963Y609728D01*
G01X224946Y609630D02*
X224896Y609646D01*
G01X225080Y608695D02*
X225197Y608596D01*
G01X225063D02*
X224946Y608695D01*
G01X224896Y609646D02*
X224829Y609695D01*
G01X224879Y609777D02*
X224912Y609745D01*
G01X224862Y609203D02*
X224896Y609170D01*
G01X224829D02*
X224795Y609203D01*
G01X224896Y609170D02*
X224929Y609121D01*
G01X224862D02*
X224829Y609170D01*
G01Y609695D02*
X224778Y609761D01*
G01X224862Y609827D02*
X224879Y609777D01*
G01X224778Y609761D02*
X224762Y609843D01*
G01X224929Y609121D02*
X224946Y609056D01*
G01X224879D02*
X224862Y609121D01*
G01X225197Y608596D02*
Y608498D01*
G01Y609498D02*
Y609416D01*
G01Y610237D02*
Y609843D01*
G01X225113Y609416D02*
Y609498D01*
G01Y609827D02*
Y610138D01*
G01X224946Y609285D02*
Y609203D01*
G01Y609056D02*
Y608990D01*
G01Y609498D02*
Y609416D01*
G01X224862Y610138D02*
Y609827D01*
G01X224762Y609843D02*
Y610138D01*
G01X224410Y609203D02*
Y609285D01*
G01Y609416D02*
Y609498D01*
G01Y610138D02*
Y610237D01*
G01Y608498D02*
Y608596D01*
G01Y608826D02*
Y608908D01*
G01X224862Y608859D02*
X224812Y608842D01*
G01X225063Y609646D02*
X225013Y609630D01*
G01Y609728D02*
X225063Y609745D01*
G01X224946Y608990D02*
X224929Y608941D01*
G01X225097Y609777D02*
X225113Y609827D01*
G01X224862Y608990D02*
X224879Y609056D01*
G01X225197Y609843D02*
X225180Y609761D01*
G01X225130Y609695D02*
X225063Y609646D01*
G01X224896Y608891D02*
X224862Y608859D01*
G01X224812Y608924D02*
X224845Y608957D01*
G01X225063Y609745D02*
X225097Y609777D01*
G01X225180Y609761D02*
X225130Y609695D01*
G01X224929Y608941D02*
X224896Y608891D01*
G01X224845Y608957D02*
X224862Y608990D01*
G01X232324Y674987D02*
X232341Y675173D01*
G01X232269Y674799D02*
X232324Y674987D01*
G01X232171Y674615D02*
X232269Y674799D01*
G01X232031Y674449D02*
X232171Y674615D01*
G01X214133Y682536D02*
X214048Y682508D01*
G01X214214Y682569D02*
X214133Y682536D01*
G01X214293Y682607D02*
X214214Y682569D01*
G01X214369Y682650D02*
X214293Y682607D01*
G01X214442Y682697D02*
X214369Y682650D01*
G01X214508Y682745D02*
X214442Y682697D01*
G01X218073Y682536D02*
X217988Y682508D01*
G01X218154Y682569D02*
X218073Y682536D01*
G01X218233Y682607D02*
X218154Y682569D01*
G01X218309Y682650D02*
X218233Y682607D01*
G01X218382Y682697D02*
X218309Y682650D01*
G01X218448Y682745D02*
X218382Y682697D01*
G01X222013Y682536D02*
X221928Y682508D01*
G01X222094Y682569D02*
X222013Y682536D01*
G01X222173Y682607D02*
X222094Y682569D01*
G01X222249Y682650D02*
X222173Y682607D01*
G01X222322Y682697D02*
X222249Y682650D01*
G01X222388Y682745D02*
X222322Y682697D01*
G01X215269Y677307D02*
X215354Y677336D01*
G01X215188Y677274D02*
X215269Y677307D01*
G01X215109Y677236D02*
X215188Y677274D01*
G01X215033Y677194D02*
X215109Y677236D01*
G01X214960Y677146D02*
X215033Y677194D01*
G01X214894Y677098D02*
X214960Y677146D01*
G01X219209Y677307D02*
X219294Y677336D01*
G01X219128Y677274D02*
X219209Y677307D01*
G01X219049Y677236D02*
X219128Y677274D01*
G01X218973Y677194D02*
X219049Y677236D01*
G01X218900Y677146D02*
X218973Y677194D01*
G01X218834Y677098D02*
X218900Y677146D01*
G01X223149Y677307D02*
X223234Y677336D01*
G01X223068Y677274D02*
X223149Y677307D01*
G01X222989Y677236D02*
X223068Y677274D01*
G01X222913Y677194D02*
X222989Y677236D01*
G01X222840Y677146D02*
X222913Y677194D01*
G01X222774Y677098D02*
X222840Y677146D01*
G01X215012Y685510D02*
X215030Y685513D01*
G01X214992Y685500D02*
X215012Y685510D01*
G01X214969Y685484D02*
X214992Y685500D01*
G01X218952Y685510D02*
X218970Y685513D01*
G01X218932Y685500D02*
X218952Y685510D01*
G01X218909Y685484D02*
X218932Y685500D01*
G01X222892Y685510D02*
X222910Y685513D01*
G01X222872Y685500D02*
X222892Y685510D01*
G01X222849Y685484D02*
X222872Y685500D01*
G01X214391Y674333D02*
X214373Y674330D01*
G01X214410Y674343D02*
X214391Y674333D01*
G01X214433Y674360D02*
X214410Y674343D01*
G01X218331Y674333D02*
X218313Y674330D01*
G01X218350Y674343D02*
X218331Y674333D01*
G01X218373Y674360D02*
X218350Y674343D01*
G01X222271Y674333D02*
X222253Y674330D01*
G01X222290Y674343D02*
X222271Y674333D01*
G01X222313Y674360D02*
X222290Y674343D01*
G01X212735Y686044D02*
X212894Y686063D01*
G01X212584Y685987D02*
X212735Y686044D01*
G01X212451Y685896D02*
X212584Y685987D01*
G01X216675Y686044D02*
X216834Y686063D01*
G01X216524Y685987D02*
X216675Y686044D01*
G01X216391Y685896D02*
X216524Y685987D01*
G01X220615Y686044D02*
X220774Y686063D01*
G01X220464Y685987D02*
X220615Y686044D01*
G01X220331Y685896D02*
X220464Y685987D01*
G01X212728Y673799D02*
X212568Y673780D01*
G01X212878Y673856D02*
X212728Y673799D01*
G01X213011Y673948D02*
X212878Y673856D01*
G01X216668Y673799D02*
X216508Y673780D01*
G01X216818Y673856D02*
X216668Y673799D01*
G01X216951Y673948D02*
X216818Y673856D01*
G01X220608Y673799D02*
X220448Y673780D01*
G01X220758Y673856D02*
X220608Y673799D01*
G01X220891Y673948D02*
X220758Y673856D01*
G01X224548Y673799D02*
X224388Y673780D01*
G01X224698Y673856D02*
X224548Y673799D01*
G01X224831Y673948D02*
X224698Y673856D01*
G01X212863Y685510D02*
X212894Y685513D01*
G01X212834Y685500D02*
X212863Y685510D01*
G01X212808Y685484D02*
X212834Y685500D01*
G01X216803Y685510D02*
X216834Y685513D01*
G01X216774Y685500D02*
X216803Y685510D01*
G01X216748Y685484D02*
X216774Y685500D01*
G01X220743Y685510D02*
X220774Y685513D01*
G01X220714Y685500D02*
X220743Y685510D01*
G01X220688Y685484D02*
X220714Y685500D01*
G01X212599Y674333D02*
X212568Y674330D01*
G01X212628Y674343D02*
X212599Y674333D01*
G01X212654Y674360D02*
X212628Y674343D01*
G01X216539Y674333D02*
X216508Y674330D01*
G01X216568Y674343D02*
X216539Y674333D01*
G01X216594Y674360D02*
X216568Y674343D01*
G01X220479Y674333D02*
X220448Y674330D01*
G01X220508Y674343D02*
X220479Y674333D01*
G01X220534Y674360D02*
X220508Y674343D01*
G01X224419Y674333D02*
X224388Y674330D01*
G01X224448Y674343D02*
X224419Y674333D01*
G01X224474Y674360D02*
X224448Y674343D01*
G01X214133Y682255D02*
X214048Y682232D01*
G01X214214Y682282D02*
X214133Y682255D01*
G01X214293Y682313D02*
X214214Y682282D01*
G01X214369Y682348D02*
X214293Y682313D01*
G01X214442Y682386D02*
X214369Y682348D01*
G01X214508Y682426D02*
X214442Y682386D01*
G01X218073Y682255D02*
X217988Y682232D01*
G01X218154Y682282D02*
X218073Y682255D01*
G01X218233Y682313D02*
X218154Y682282D01*
G01X218309Y682348D02*
X218233Y682313D01*
G01X218382Y682386D02*
X218309Y682348D01*
G01X218448Y682426D02*
X218382Y682386D01*
G01X222013Y682255D02*
X221928Y682232D01*
G01X222094Y682282D02*
X222013Y682255D01*
G01X222173Y682313D02*
X222094Y682282D01*
G01X222249Y682348D02*
X222173Y682313D01*
G01X222322Y682386D02*
X222249Y682348D01*
G01X222388Y682426D02*
X222322Y682386D01*
G01X215269Y677588D02*
X215354Y677612D01*
G01X215188Y677561D02*
X215269Y677588D01*
G01X215109Y677530D02*
X215188Y677561D01*
G01X215033Y677495D02*
X215109Y677530D01*
G01X214960Y677457D02*
X215033Y677495D01*
G01X214894Y677417D02*
X214960Y677457D01*
G01X219209Y677588D02*
X219294Y677612D01*
G01X219128Y677561D02*
X219209Y677588D01*
G01X219049Y677530D02*
X219128Y677561D01*
G01X218973Y677495D02*
X219049Y677530D01*
G01X218900Y677457D02*
X218973Y677495D01*
G01X218834Y677417D02*
X218900Y677457D01*
G01X223149Y677588D02*
X223234Y677612D01*
G01X223068Y677561D02*
X223149Y677588D01*
G01X222989Y677530D02*
X223068Y677561D01*
G01X222913Y677495D02*
X222989Y677530D01*
G01X222840Y677457D02*
X222913Y677495D01*
G01X222774Y677417D02*
X222840Y677457D01*
G01X214437Y682242D02*
X214508Y682294D01*
G01X214363Y682195D02*
X214437Y682242D01*
G01X214287Y682153D02*
X214363Y682195D01*
G01X214208Y682116D02*
X214287Y682153D01*
G01X214127Y682083D02*
X214208Y682116D01*
G01X214048Y682057D02*
X214127Y682083D01*
G01X218377Y682242D02*
X218448Y682294D01*
G01X218303Y682195D02*
X218377Y682242D01*
G01X218227Y682153D02*
X218303Y682195D01*
G01X218148Y682116D02*
X218227Y682153D01*
G01X218067Y682083D02*
X218148Y682116D01*
G01X217988Y682057D02*
X218067Y682083D01*
G01X222317Y682242D02*
X222388Y682294D01*
G01X222243Y682195D02*
X222317Y682242D01*
G01X222167Y682153D02*
X222243Y682195D01*
G01X222088Y682116D02*
X222167Y682153D01*
G01X222007Y682083D02*
X222088Y682116D01*
G01X221928Y682057D02*
X222007Y682083D01*
G01X214966Y677601D02*
X214894Y677549D01*
G01X215039Y677648D02*
X214966Y677601D01*
G01X215115Y677690D02*
X215039Y677648D01*
G01X215194Y677728D02*
X215115Y677690D01*
G01X215276Y677760D02*
X215194Y677728D01*
G01X215354Y677787D02*
X215276Y677760D01*
G01X218906Y677601D02*
X218834Y677549D01*
G01X218979Y677648D02*
X218906Y677601D01*
G01X219055Y677690D02*
X218979Y677648D01*
G01X219134Y677728D02*
X219055Y677690D01*
G01X219216Y677760D02*
X219134Y677728D01*
G01X219294Y677787D02*
X219216Y677760D01*
G01X222846Y677601D02*
X222774Y677549D01*
G01X222919Y677648D02*
X222846Y677601D01*
G01X222995Y677690D02*
X222919Y677648D01*
G01X223074Y677728D02*
X222995Y677690D01*
G01X223156Y677760D02*
X223074Y677728D01*
G01X223234Y677787D02*
X223156Y677760D01*
G01X215016Y685547D02*
X214987Y685504D01*
G01X215028Y685578D02*
X215016Y685547D01*
G01X215030Y685589D02*
X215028Y685578D01*
G01X214386Y674296D02*
X214416Y674339D01*
G01X214374Y674265D02*
X214386Y674296D01*
G01X214373Y674254D02*
X214374Y674265D01*
G01X218956Y685547D02*
X218927Y685504D01*
G01X218968Y685578D02*
X218956Y685547D01*
G01X218970Y685589D02*
X218968Y685578D01*
G01X218326Y674296D02*
X218356Y674339D01*
G01X218314Y674265D02*
X218326Y674296D01*
G01X218313Y674254D02*
X218314Y674265D01*
G01X222896Y685547D02*
X222867Y685504D01*
G01X222908Y685578D02*
X222896Y685547D01*
G01X222910Y685589D02*
X222908Y685578D01*
G01X222266Y674296D02*
X222296Y674339D01*
G01X222254Y674265D02*
X222266Y674296D01*
G01X222253Y674254D02*
X222254Y674265D01*
G01X212576Y673780D02*
X212579D01*
G01X212573D02*
X212576D01*
G01X212571Y673781D02*
X212573Y673780D01*
G01X212569Y673782D02*
X212571Y673781D01*
G01X212569Y673783D02*
Y673782D01*
G01X212568Y673784D02*
X212569Y673783D01*
G01X212887Y686063D02*
X212883D01*
G01X212889D02*
X212887D01*
G01X212891D02*
X212889D01*
G01X212893Y686062D02*
X212891Y686063D01*
G01X212894Y686061D02*
X212893Y686062D01*
G01X212894Y686060D02*
Y686061D01*
G01X216516Y673780D02*
X216519D01*
G01X216513D02*
X216516D01*
G01X216511Y673781D02*
X216513Y673780D01*
G01X216509Y673782D02*
X216511Y673781D01*
G01X216509Y673783D02*
Y673782D01*
G01X216508Y673784D02*
X216509Y673783D01*
G01X216827Y686063D02*
X216823D01*
G01X216829D02*
X216827D01*
G01X216831D02*
X216829D01*
G01X216833Y686062D02*
X216831Y686063D01*
G01X216834Y686061D02*
X216833Y686062D01*
G01X216834Y686060D02*
Y686061D01*
G01X220456Y673780D02*
X220459D01*
G01X220453D02*
X220456D01*
G01X220451Y673781D02*
X220453Y673780D01*
G01X220449Y673782D02*
X220451Y673781D01*
G01X220449Y673783D02*
Y673782D01*
G01X220448Y673784D02*
X220449Y673783D01*
G01X220767Y686063D02*
X220763D01*
G01X220769D02*
X220767D01*
G01X220771D02*
X220769D01*
G01X220773Y686062D02*
X220771Y686063D01*
G01X220774Y686061D02*
X220773Y686062D01*
G01X220774Y686060D02*
Y686061D01*
G01X224396Y673780D02*
X224399D01*
G01X224393D02*
X224396D01*
G01X224391Y673781D02*
X224393Y673780D01*
G01X224389Y673782D02*
X224391Y673781D01*
G01X224389Y673783D02*
Y673782D01*
G01X224388Y673784D02*
X224389Y673783D01*
G01X213088Y674265D02*
X213090Y674254D01*
G01X213076Y674296D02*
X213088Y674265D01*
G01X213047Y674339D02*
X213076Y674296D01*
G01X217028Y674265D02*
X217030Y674254D01*
G01X217016Y674296D02*
X217028Y674265D01*
G01X216987Y674339D02*
X217016Y674296D01*
G01X212374Y685578D02*
X212373Y685589D01*
G01X212386Y685547D02*
X212374Y685578D01*
G01X212416Y685504D02*
X212386Y685547D01*
G01X220968Y674265D02*
X220970Y674254D01*
G01X220956Y674296D02*
X220968Y674265D01*
G01X220927Y674339D02*
X220956Y674296D01*
G01X216314Y685578D02*
X216313Y685589D01*
G01X216326Y685547D02*
X216314Y685578D01*
G01X216356Y685504D02*
X216326Y685547D01*
G01X224908Y674265D02*
X224910Y674254D01*
G01X224896Y674296D02*
X224908Y674265D01*
G01X224867Y674339D02*
X224896Y674296D01*
G01X220254Y685578D02*
X220253Y685589D01*
G01X220266Y685547D02*
X220254Y685578D01*
G01X220296Y685504D02*
X220266Y685547D01*
G01X218202Y673799D02*
X218313Y673780D01*
G01X218101Y673856D02*
X218202Y673799D01*
G01X218017Y673948D02*
X218101Y673856D01*
G01X222142Y673799D02*
X222253Y673780D01*
G01X222041Y673856D02*
X222142Y673799D01*
G01X221957Y673948D02*
X222041Y673856D01*
G01X215140Y686044D02*
X215030Y686063D01*
G01X215242Y685987D02*
X215140Y686044D01*
G01X215326Y685896D02*
X215242Y685987D01*
G01X219080Y686044D02*
X218970Y686063D01*
G01X219182Y685987D02*
X219080Y686044D01*
G01X219266Y685896D02*
X219182Y685987D01*
G01X223020Y686044D02*
X222910Y686063D01*
G01X223122Y685987D02*
X223020Y686044D01*
G01X223206Y685896D02*
X223122Y685987D01*
G01X212573Y674330D02*
X212579D01*
G01X212569Y674331D02*
X212573Y674330D01*
G01X212568Y674332D02*
X212569Y674331D01*
G01X216513Y674330D02*
X216519D01*
G01X216509Y674331D02*
X216513Y674330D01*
G01X216508Y674332D02*
X216509Y674331D01*
G01X220453Y674330D02*
X220459D01*
G01X220449Y674331D02*
X220453Y674330D01*
G01X220448Y674332D02*
X220449Y674331D01*
G01X212889Y685513D02*
X212883D01*
G01X212893Y685512D02*
X212889Y685513D01*
G01X212894Y685511D02*
X212893Y685512D01*
G01X224393Y674330D02*
X224399D01*
G01X224389Y674331D02*
X224393Y674330D01*
G01X224388Y674332D02*
X224389Y674331D01*
G01X216829Y685513D02*
X216823D01*
G01X216833Y685512D02*
X216829Y685513D01*
G01X216834Y685511D02*
X216833Y685512D01*
G01X220769Y685513D02*
X220763D01*
G01X220773Y685512D02*
X220769Y685513D01*
G01X220774Y685511D02*
X220773Y685512D01*
G01X232325Y684855D02*
X232341Y684671D01*
G01X232269Y685043D02*
X232325Y684855D01*
G01X232172Y685227D02*
X232269Y685043D01*
G01X232031Y685394D02*
X232172Y685227D01*
G01X212281Y677728D02*
X212204Y677759D01*
G01X212360Y677691D02*
X212281Y677728D01*
G01X212432Y677651D02*
X212360Y677691D01*
G01X212501Y677608D02*
X212432Y677651D01*
G01X212568Y677560D02*
X212501Y677608D01*
G01X216144Y677759D02*
X216062Y677787D01*
G01X216221Y677728D02*
X216144Y677759D01*
G01X216300Y677691D02*
X216221Y677728D01*
G01X216372Y677651D02*
X216300Y677691D01*
G01X216441Y677608D02*
X216372Y677651D01*
G01X216508Y677560D02*
X216441Y677608D01*
G01X213258Y682084D02*
X213340Y682057D01*
G01X213182Y682115D02*
X213258Y682084D01*
G01X213103Y682152D02*
X213182Y682115D01*
G01X213030Y682192D02*
X213103Y682152D01*
G01X212961Y682236D02*
X213030Y682192D01*
G01X212894Y682283D02*
X212961Y682236D01*
G01X220084Y677759D02*
X220002Y677787D01*
G01X220161Y677728D02*
X220084Y677759D01*
G01X220240Y677691D02*
X220161Y677728D01*
G01X220312Y677651D02*
X220240Y677691D01*
G01X220381Y677608D02*
X220312Y677651D01*
G01X220448Y677560D02*
X220381Y677608D01*
G01X217198Y682084D02*
X217280Y682057D01*
G01X217122Y682115D02*
X217198Y682084D01*
G01X217043Y682152D02*
X217122Y682115D01*
G01X216970Y682192D02*
X217043Y682152D01*
G01X216901Y682236D02*
X216970Y682192D01*
G01X216834Y682283D02*
X216901Y682236D01*
G01X224024Y677759D02*
X223942Y677787D01*
G01X224101Y677728D02*
X224024Y677759D01*
G01X224180Y677691D02*
X224101Y677728D01*
G01X224252Y677651D02*
X224180Y677691D01*
G01X224321Y677608D02*
X224252Y677651D01*
G01X224388Y677560D02*
X224321Y677608D01*
G01X221138Y682084D02*
X221220Y682057D01*
G01X221062Y682115D02*
X221138Y682084D01*
G01X220983Y682152D02*
X221062Y682115D01*
G01X220910Y682192D02*
X220983Y682152D01*
G01X220841Y682236D02*
X220910Y682192D01*
G01X220774Y682283D02*
X220841Y682236D01*
G01X212281Y674810D02*
X212204Y674835D01*
G01X212360Y674779D02*
X212281Y674810D01*
G01X212432Y674746D02*
X212360Y674779D01*
G01X212501Y674711D02*
X212432Y674746D01*
G01X212568Y674672D02*
X212501Y674711D01*
G01X216144Y674835D02*
X216062Y674857D01*
G01X216221Y674810D02*
X216144Y674835D01*
G01X216300Y674779D02*
X216221Y674810D01*
G01X216372Y674746D02*
X216300Y674779D01*
G01X216441Y674711D02*
X216372Y674746D01*
G01X216508Y674672D02*
X216441Y674711D01*
G01X220084Y674835D02*
X220002Y674857D01*
G01X220161Y674810D02*
X220084Y674835D01*
G01X220240Y674779D02*
X220161Y674810D01*
G01X220312Y674746D02*
X220240Y674779D01*
G01X220381Y674711D02*
X220312Y674746D01*
G01X220448Y674672D02*
X220381Y674711D01*
G01X224024Y674835D02*
X223942Y674857D01*
G01X224101Y674810D02*
X224024Y674835D01*
G01X224180Y674779D02*
X224101Y674810D01*
G01X224252Y674746D02*
X224180Y674779D01*
G01X224321Y674711D02*
X224252Y674746D01*
G01X224388Y674672D02*
X224321Y674711D01*
G01X213258Y685008D02*
X213340Y684986D01*
G01X213182Y685034D02*
X213258Y685008D01*
G01X213103Y685064D02*
X213182Y685034D01*
G01X213030Y685097D02*
X213103Y685064D01*
G01X212961Y685133D02*
X213030Y685097D01*
G01X212894Y685172D02*
X212961Y685133D01*
G01X217198Y685008D02*
X217280Y684986D01*
G01X217122Y685034D02*
X217198Y685008D01*
G01X217043Y685064D02*
X217122Y685034D01*
G01X216970Y685097D02*
X217043Y685064D01*
G01X216901Y685133D02*
X216970Y685097D01*
G01X216834Y685172D02*
X216901Y685133D01*
G01X221138Y685008D02*
X221220Y684986D01*
G01X221062Y685034D02*
X221138Y685008D01*
G01X220983Y685064D02*
X221062Y685034D01*
G01X220910Y685097D02*
X220983Y685064D01*
G01X220841Y685133D02*
X220910Y685097D01*
G01X220774Y685172D02*
X220841Y685133D01*
G01X212499Y677158D02*
X212568Y677109D01*
G01X212429Y677202D02*
X212499Y677158D01*
G01X212352Y677244D02*
X212429Y677202D01*
G01X212278Y677279D02*
X212352Y677244D01*
G01X212201Y677309D02*
X212278Y677279D01*
G01X216439Y677158D02*
X216508Y677109D01*
G01X216369Y677202D02*
X216439Y677158D01*
G01X216292Y677244D02*
X216369Y677202D01*
G01X216218Y677279D02*
X216292Y677244D01*
G01X216141Y677309D02*
X216218Y677279D01*
G01X216062Y677336D02*
X216141Y677309D01*
G01X231713Y685911D02*
X231568Y685922D01*
G01X231842Y685901D02*
X231713Y685911D01*
G01X231944Y685891D02*
X231842Y685901D01*
G01X232009Y685881D02*
X231944Y685891D01*
G01X232031Y685870D02*
X232009Y685881D01*
G01X213052Y674343D02*
X213029Y674360D01*
G01X213072Y674333D02*
X213052Y674343D01*
G01X213090Y674330D02*
X213072Y674333D01*
G01X216992Y674343D02*
X216969Y674360D01*
G01X217012Y674333D02*
X216992Y674343D01*
G01X217030Y674330D02*
X217012Y674333D01*
G01X220932Y674343D02*
X220909Y674360D01*
G01X220952Y674333D02*
X220932Y674343D01*
G01X220970Y674330D02*
X220952Y674333D01*
G01X232100Y685905D02*
X231608Y685922D01*
G01X232300Y685896D02*
X232100Y685905D01*
G01X232453Y685887D02*
X232300Y685896D01*
G01X232549Y685879D02*
X232453Y685887D01*
G01X232581Y685870D02*
X232549Y685879D01*
G01X212499Y677467D02*
X212568Y677426D01*
G01X212429Y677502D02*
X212499Y677467D01*
G01X212352Y677536D02*
X212429Y677502D01*
G01X212278Y677565D02*
X212352Y677536D01*
G01X212201Y677590D02*
X212278Y677565D01*
G01X216439Y677467D02*
X216508Y677426D01*
G01X216369Y677502D02*
X216439Y677467D01*
G01X216292Y677536D02*
X216369Y677502D01*
G01X216218Y677565D02*
X216292Y677536D01*
G01X216141Y677590D02*
X216218Y677565D01*
G01X216062Y677612D02*
X216141Y677590D01*
G01X220379Y677467D02*
X220448Y677426D01*
G01X220309Y677502D02*
X220379Y677467D01*
G01X220232Y677536D02*
X220309Y677502D01*
G01X220158Y677565D02*
X220232Y677536D01*
G01X220081Y677590D02*
X220158Y677565D01*
G01X220002Y677612D02*
X220081Y677590D01*
G01X224319Y677467D02*
X224388Y677426D01*
G01X224249Y677502D02*
X224319Y677467D01*
G01X224172Y677536D02*
X224249Y677502D01*
G01X224098Y677565D02*
X224172Y677536D01*
G01X224021Y677590D02*
X224098Y677565D01*
G01X223942Y677612D02*
X224021Y677590D01*
G01X212964Y682377D02*
X212894Y682417D01*
G01X213033Y682341D02*
X212964Y682377D01*
G01X213110Y682307D02*
X213033Y682341D01*
G01X213185Y682278D02*
X213110Y682307D01*
G01X213261Y682253D02*
X213185Y682278D01*
G01X213340Y682232D02*
X213261Y682253D01*
G01X216904Y682377D02*
X216834Y682417D01*
G01X216973Y682341D02*
X216904Y682377D01*
G01X217050Y682307D02*
X216973Y682341D01*
G01X217125Y682278D02*
X217050Y682307D01*
G01X217201Y682253D02*
X217125Y682278D01*
G01X217280Y682232D02*
X217201Y682253D01*
G01X220844Y682377D02*
X220774Y682417D01*
G01X220913Y682341D02*
X220844Y682377D01*
G01X220990Y682307D02*
X220913Y682341D01*
G01X221065Y682278D02*
X220990Y682307D01*
G01X221141Y682253D02*
X221065Y682278D01*
G01X221220Y682232D02*
X221141Y682253D01*
G01X220379Y677158D02*
X220448Y677109D01*
G01X220309Y677202D02*
X220379Y677158D01*
G01X220232Y677244D02*
X220309Y677202D01*
G01X220158Y677279D02*
X220232Y677244D01*
G01X220081Y677309D02*
X220158Y677279D01*
G01X220002Y677336D02*
X220081Y677309D01*
G01X224319Y677158D02*
X224388Y677109D01*
G01X224249Y677202D02*
X224319Y677158D01*
G01X224172Y677244D02*
X224249Y677202D01*
G01X224098Y677279D02*
X224172Y677244D01*
G01X224021Y677309D02*
X224098Y677279D01*
G01X223942Y677336D02*
X224021Y677309D01*
G01X212964Y682685D02*
X212894Y682734D01*
G01X213033Y682641D02*
X212964Y682685D01*
G01X213110Y682600D02*
X213033Y682641D01*
G01X213185Y682565D02*
X213110Y682600D01*
G01X213261Y682534D02*
X213185Y682565D01*
G01X213340Y682508D02*
X213261Y682534D01*
G01X216904Y682685D02*
X216834Y682734D01*
G01X216973Y682641D02*
X216904Y682685D01*
G01X217050Y682600D02*
X216973Y682641D01*
G01X217125Y682565D02*
X217050Y682600D01*
G01X217201Y682534D02*
X217125Y682565D01*
G01X217280Y682508D02*
X217201Y682534D01*
G01X220844Y682685D02*
X220774Y682734D01*
G01X220913Y682641D02*
X220844Y682685D01*
G01X220990Y682600D02*
X220913Y682641D01*
G01X221065Y682565D02*
X220990Y682600D01*
G01X221141Y682534D02*
X221065Y682565D01*
G01X221220Y682508D02*
X221141Y682534D01*
G01X214834Y674343D02*
X214808Y674360D01*
G01X214863Y674333D02*
X214834Y674343D01*
G01X214894Y674330D02*
X214863Y674333D01*
G01X218774Y674343D02*
X218748Y674360D01*
G01X218803Y674333D02*
X218774Y674343D01*
G01X218834Y674330D02*
X218803Y674333D01*
G01X222714Y674343D02*
X222688Y674360D01*
G01X222743Y674333D02*
X222714Y674343D01*
G01X222774Y674330D02*
X222743Y674333D01*
G01X214568Y685500D02*
X214594Y685484D01*
G01X214539Y685510D02*
X214568Y685500D01*
G01X214508Y685513D02*
X214539Y685510D01*
G01X218508Y685500D02*
X218534Y685484D01*
G01X218479Y685510D02*
X218508Y685500D01*
G01X218448Y685513D02*
X218479Y685510D01*
G01X222448Y685500D02*
X222474Y685484D01*
G01X222419Y685510D02*
X222448Y685500D01*
G01X222388Y685513D02*
X222419Y685510D01*
G01X214584Y673856D02*
X214451Y673948D01*
G01X214735Y673799D02*
X214584Y673856D01*
G01X214894Y673780D02*
X214735Y673799D01*
G01X218524Y673856D02*
X218391Y673948D01*
G01X218675Y673799D02*
X218524Y673856D01*
G01X218834Y673780D02*
X218675Y673799D01*
G01X222464Y673856D02*
X222331Y673948D01*
G01X222615Y673799D02*
X222464Y673856D01*
G01X222774Y673780D02*
X222615Y673799D01*
G01X214818Y685987D02*
X214951Y685896D01*
G01X214668Y686044D02*
X214818Y685987D01*
G01X214508Y686063D02*
X214668Y686044D01*
G01X218758Y685987D02*
X218891Y685896D01*
G01X218608Y686044D02*
X218758Y685987D01*
G01X218448Y686063D02*
X218608Y686044D01*
G01X222698Y685987D02*
X222831Y685896D01*
G01X222548Y686044D02*
X222698Y685987D01*
G01X222388Y686063D02*
X222548Y686044D01*
G01X224872Y674343D02*
X224849Y674360D01*
G01X224892Y674333D02*
X224872Y674343D01*
G01X224910Y674330D02*
X224892Y674333D01*
G01X212410Y685500D02*
X212433Y685484D01*
G01X212391Y685510D02*
X212410Y685500D01*
G01X212373Y685513D02*
X212391Y685510D01*
G01X216350Y685500D02*
X216373Y685484D01*
G01X216331Y685510D02*
X216350Y685500D01*
G01X216313Y685513D02*
X216331Y685510D01*
G01X220290Y685500D02*
X220313Y685484D01*
G01X220271Y685510D02*
X220290Y685500D01*
G01X220253Y685513D02*
X220271Y685510D01*
G01X231594Y673922D02*
X231608D01*
G01X231582Y673921D02*
X231594Y673922D01*
G01X231568Y673921D02*
X231582D01*
G01X231556Y673920D02*
X231568Y673921D01*
G01X231543Y673919D02*
X231556Y673920D01*
G01X231531Y673917D02*
X231543Y673919D01*
G01X232009Y673963D02*
X232031Y673973D01*
G01X231944Y673953D02*
X232009Y673963D01*
G01X231843Y673942D02*
X231944Y673953D01*
G01X231713Y673932D02*
X231843Y673942D01*
G01X231568Y673922D02*
X231713Y673932D01*
G01X232549Y673965D02*
X232581Y673973D01*
G01X232453Y673956D02*
X232549Y673965D01*
G01X232300Y673947D02*
X232453Y673956D01*
G01X232100Y673939D02*
X232300Y673947D01*
G01X222773Y674331D02*
X222774Y674332D01*
G01X222769Y674330D02*
X222773Y674331D01*
G01X222763Y674330D02*
X222769D01*
G01X218833Y674331D02*
X218834Y674332D01*
G01X218829Y674330D02*
X218833Y674331D01*
G01X218823Y674330D02*
X218829D01*
G01X214893Y674331D02*
X214894Y674332D01*
G01X214889Y674330D02*
X214893Y674331D01*
G01X214883Y674330D02*
X214889D01*
G01X222389Y685512D02*
X222388Y685511D01*
G01X222393Y685513D02*
X222389Y685512D01*
G01X222399Y685513D02*
X222393D01*
G01X218449Y685512D02*
X218448Y685511D01*
G01X218453Y685513D02*
X218449Y685512D01*
G01X218459Y685513D02*
X218453D01*
G01X214509Y685512D02*
X214508Y685511D01*
G01X214513Y685513D02*
X214509Y685512D01*
G01X214519Y685513D02*
X214513D01*
G01X222774Y673782D02*
Y673784D01*
G01X222773Y673781D02*
X222774Y673782D01*
G01X222771Y673781D02*
X222773D01*
G01X222769Y673780D02*
X222771Y673781D01*
G01X222766Y673780D02*
X222769D01*
G01X222763D02*
X222766D01*
G01X218834Y673782D02*
Y673784D01*
G01X218833Y673781D02*
X218834Y673782D01*
G01X218831Y673781D02*
X218833D01*
G01X218829Y673780D02*
X218831Y673781D01*
G01X218826Y673780D02*
X218829D01*
G01X218823D02*
X218826D01*
G01X214894Y673782D02*
Y673784D01*
G01X214893Y673781D02*
X214894Y673782D01*
G01X214891Y673781D02*
X214893D01*
G01X214889Y673780D02*
X214891Y673781D01*
G01X214886Y673780D02*
X214889D01*
G01X214883D02*
X214886D01*
G01X222389Y686061D02*
X222388Y686060D01*
G01X222390Y686062D02*
X222389Y686061D01*
G01X222391Y686063D02*
X222390Y686062D01*
G01X222393Y686063D02*
X222391D01*
G01X222396D02*
X222393D01*
G01X222399D02*
X222396D01*
G01X218449Y686061D02*
X218448Y686060D01*
G01X218450Y686062D02*
X218449Y686061D01*
G01X218451Y686063D02*
X218450Y686062D01*
G01X218453Y686063D02*
X218451D01*
G01X218456D02*
X218453D01*
G01X218459D02*
X218456D01*
G01X214509Y686061D02*
X214508Y686060D01*
G01X214510Y686062D02*
X214509Y686061D01*
G01X214511Y686063D02*
X214510Y686062D01*
G01X214513Y686063D02*
X214511D01*
G01X214516D02*
X214513D01*
G01X214519D02*
X214516D01*
G01X231545Y685925D02*
X231531Y685926D01*
G01X231557Y685924D02*
X231545Y685925D01*
G01X231571Y685923D02*
X231557Y685924D01*
G01X231583Y685922D02*
X231571Y685923D01*
G01X231596Y685922D02*
X231583D01*
G01X231608D02*
X231596D01*
G01X231537Y685925D02*
X231531Y685926D01*
G01X231543Y685924D02*
X231537Y685925D01*
G01X231550Y685923D02*
X231543Y685924D01*
G01X231556Y685922D02*
X231550Y685923D01*
G01X231562Y685922D02*
X231556D01*
G01X231568D02*
X231562D01*
G01X222846Y674705D02*
X222774Y674663D01*
G01X222919Y674744D02*
X222846Y674705D01*
G01X222995Y674778D02*
X222919Y674744D01*
G01X223074Y674809D02*
X222995Y674778D01*
G01X223156Y674836D02*
X223074Y674809D01*
G01X223234Y674857D02*
X223156Y674836D01*
G01X218906Y674705D02*
X218834Y674663D01*
G01X218979Y674744D02*
X218906Y674705D01*
G01X219055Y674778D02*
X218979Y674744D01*
G01X219134Y674809D02*
X219055Y674778D01*
G01X219216Y674836D02*
X219134Y674809D01*
G01X219294Y674857D02*
X219216Y674836D01*
G01X214966Y674705D02*
X214894Y674663D01*
G01X215039Y674744D02*
X214966Y674705D01*
G01X215115Y674778D02*
X215039Y674744D01*
G01X215194Y674809D02*
X215115Y674778D01*
G01X215276Y674836D02*
X215194Y674809D01*
G01X215354Y674857D02*
X215276Y674836D01*
G01X222317Y685138D02*
X222388Y685181D01*
G01X222243Y685100D02*
X222317Y685138D01*
G01X222167Y685065D02*
X222243Y685100D01*
G01X222088Y685034D02*
X222167Y685065D01*
G01X222007Y685008D02*
X222088Y685034D01*
G01X221928Y684986D02*
X222007Y685008D01*
G01X218377Y685138D02*
X218448Y685181D01*
G01X218303Y685100D02*
X218377Y685138D01*
G01X218227Y685065D02*
X218303Y685100D01*
G01X218148Y685034D02*
X218227Y685065D01*
G01X218067Y685008D02*
X218148Y685034D01*
G01X217988Y684986D02*
X218067Y685008D01*
G01X214437Y685138D02*
X214508Y685181D01*
G01X214363Y685100D02*
X214437Y685138D01*
G01X214287Y685065D02*
X214363Y685100D01*
G01X214208Y685034D02*
X214287Y685065D01*
G01X214127Y685008D02*
X214208Y685034D01*
G01X214048Y684986D02*
X214127Y685008D01*
G01X231561Y673922D02*
X231568D01*
G01X231555Y673921D02*
X231561Y673922D01*
G01X231549Y673921D02*
X231555D01*
G01X231543Y673920D02*
X231549Y673921D01*
G01X231537Y673919D02*
X231543Y673920D01*
G01X231531Y673917D02*
X231537Y673919D01*
G01X225122Y673856D02*
X225206Y673948D01*
G01X225020Y673799D02*
X225122Y673856D01*
G01X224910Y673780D02*
X225020Y673799D01*
G01X221182Y673856D02*
X221266Y673948D01*
G01X221080Y673799D02*
X221182Y673856D01*
G01X220970Y673780D02*
X221080Y673799D01*
G01X217242Y673856D02*
X217326Y673948D01*
G01X217140Y673799D02*
X217242Y673856D01*
G01X217030Y673780D02*
X217140Y673799D01*
G01X220041Y685987D02*
X219957Y685896D01*
G01X220142Y686044D02*
X220041Y685987D01*
G01X220253Y686063D02*
X220142Y686044D01*
G01X216101Y685987D02*
X216017Y685896D01*
G01X216202Y686044D02*
X216101Y685987D01*
G01X216313Y686063D02*
X216202Y686044D01*
G01X233505Y684980D02*
G03X233996Y685242I176J262D01*
G01X231581Y686537D02*
G03X231529Y685911I0J-315D01*
G01X226881Y684252D02*
G03I-1250J0D01*
G01X221933Y682005D02*
G03X222399Y682254I-423J1352D01*
G01X220763Y682243D02*
G03X221215Y682005I875J1114D01*
G01X233996Y674602D02*
G03X233505Y674863I-315J0D01*
G01X231529Y673932D02*
G03X231581Y673307I52J-310D01*
G01X227522Y677264D02*
G03X228184Y678017I409J308D01*
G01X219289Y677838D02*
G03X218823Y677589I423J-1352D01*
G01X220459Y677600D02*
G03X220008Y677838I-876J-1114D01*
G01X223229D02*
G03X222763Y677589I423J-1352D01*
G01X224399Y677600D02*
G03X223948Y677838I-876J-1114D01*
G01X217993Y682005D02*
G03X218459Y682254I-423J1352D01*
G01X216823Y682243D02*
G03X217275Y682005I875J1114D01*
G01X214053D02*
G03X214519Y682254I-423J1352D01*
G01X212883Y682243D02*
G03X213335Y682005I875J1114D01*
G01X212579Y677600D02*
G03X212128Y677838I-876J-1114D01*
G01X215349D02*
G03X214883Y677589I423J-1352D01*
G01X216519Y677600D02*
G03X216068Y677838I-876J-1114D01*
G01X214351Y673781D02*
X214373Y673780D01*
G01X214508Y691113D02*
X212894D01*
G01X218448D02*
X216834D01*
G01X222388D02*
X220774D01*
G01X231581Y690422D02*
X228081D01*
G01X214751Y689772D02*
X233981D01*
G01Y688172D02*
X214751D01*
G01X223731Y687018D02*
X214751D01*
G01X214508Y686963D02*
X212894D01*
G01X218448D02*
X216834D01*
G01X222388D02*
X220774D01*
G01X215051Y686822D02*
X214751D01*
G01D02*
X212351D01*
G01X218991D02*
X216291D01*
G01X222931D02*
X220231D01*
G01X214508Y686613D02*
X212894D01*
G01X218448D02*
X216834D01*
G01X222388D02*
X220774D01*
G01X214751Y686272D02*
X223731D01*
G01X214508Y686111D02*
X212894D01*
G01X214751Y686072D02*
X223731D01*
G01X215030Y686063D02*
X212373D01*
G01X218970D02*
X216313D01*
G01X222910D02*
X220253D01*
G01X231568Y685922D02*
X231608D01*
G01X222831Y685896D02*
X223206D01*
G01X218891D02*
X219266D01*
G01X219957D02*
X220331D01*
G01X216017D02*
X216391D01*
G01X214951D02*
X215326D01*
G01X212351D02*
X212451D01*
G01X232581Y685870D02*
X232031D01*
G01Y685669D02*
X232581D01*
G01X215030Y685513D02*
X212373D01*
G01X218970D02*
X216313D01*
G01X222910D02*
X220253D01*
G01X222474Y685484D02*
X222849D01*
G01X218534D02*
X218909D01*
G01X220313D02*
X220688D01*
G01X216373D02*
X216748D01*
G01X214594D02*
X214969D01*
G01X212433D02*
X212808D01*
G01X214508Y685421D02*
X212894D01*
G01X218448D02*
X216834D01*
G01X222388D02*
X220774D01*
G01X222531Y685372D02*
X223731D01*
G01X218591D02*
X220631D01*
G01X214751D02*
X216691D01*
G01X214651D02*
X214751D01*
G01X216691Y685157D02*
X214751D01*
G01D02*
X214651D01*
G01X220631D02*
X218591D01*
G01X223731D02*
X222531D01*
G01X221220Y684986D02*
X221928D01*
G01X217280D02*
X217988D01*
G01X213340D02*
X214048D01*
G01X232581Y684671D02*
X232341D01*
G01X214508Y683647D02*
X212894D01*
G01X218448D02*
X216834D01*
G01X222388D02*
X220774D01*
G01X216691Y683572D02*
X214751D01*
G01D02*
X214651D01*
G01X220631D02*
X218591D01*
G01X226153D02*
X222531D01*
G01X214508Y683116D02*
X212894D01*
G01X218448D02*
X216834D01*
G01X222388D02*
X220774D01*
G01X214508Y682666D02*
X212894D01*
G01X218448D02*
X216834D01*
G01X222388D02*
X220774D01*
G01Y682587D02*
X222388D01*
G01X216834D02*
X218448D01*
G01X212894D02*
X214508D01*
G01X222531Y682572D02*
X226517D01*
G01X214751D02*
X216691D01*
G01X214651D02*
X214751D01*
G01X214508D02*
X212894D01*
G01X218448D02*
X216834D01*
G01X220631D02*
X218591D01*
G01X222388D02*
X220774D01*
G01X221928Y682508D02*
X222388D01*
G01X217988D02*
X218448D01*
G01X220774D02*
X221220D01*
G01X216834D02*
X217280D01*
G01X214048D02*
X214508D01*
G01X212894D02*
X213340D01*
G01X232581Y682422D02*
X231081D01*
G01X214048Y682232D02*
X213340D01*
G01X217988D02*
X217280D01*
G01X221928D02*
X221220D01*
G01X232581Y682172D02*
X233031D01*
G01X232581D02*
X232031D01*
G01X221220Y682057D02*
X221928D01*
G01X217280D02*
X217988D01*
G01X213340D02*
X214048D01*
G01Y682022D02*
X213340D01*
G01X217988D02*
X217280D01*
G01X221928D02*
X221220D01*
G01X227531Y681972D02*
X223731D01*
G01X214651Y681122D02*
X212751D01*
G01X218591D02*
X216691D01*
G01X222531D02*
X220631D01*
G01X216651Y678722D02*
X214751D01*
G01X220591D02*
X218691D01*
G01X224531D02*
X222631D01*
G01X223234Y677822D02*
X223942D01*
G01X219294D02*
X220002D01*
G01X215354D02*
X216062D01*
G01Y677787D02*
X215354D01*
G01X220002D02*
X219294D01*
G01X223942D02*
X223234D01*
G01X232581Y677672D02*
X233031D01*
G01X232031D02*
X232581D01*
G01X223234Y677612D02*
X223942D01*
G01X219294D02*
X220002D01*
G01X215354D02*
X216062D01*
G01X231081Y677422D02*
X232581D01*
G01X212568Y677336D02*
X212122D01*
G01X215354D02*
X214894D01*
G01X216508D02*
X216062D01*
G01X219294D02*
X218834D01*
G01X220448D02*
X220002D01*
G01X223234D02*
X222774D01*
G01X224388D02*
X223942D01*
G01X222774Y677272D02*
X224388D01*
G01X218834D02*
X220448D01*
G01X214894D02*
X216508D01*
G01X214751D02*
X212711D01*
G01X218691D02*
X216651D01*
G01X222631D02*
X220591D01*
G01X227532D02*
X224531D01*
G01X216508Y677256D02*
X214894D01*
G01X220448D02*
X218834D01*
G01X224388D02*
X222774D01*
G01Y677177D02*
X224388D01*
G01X218834D02*
X220448D01*
G01X214894D02*
X216508D01*
G01X222774Y676727D02*
X224388D01*
G01X218834D02*
X220448D01*
G01X214894D02*
X216508D01*
G01X224531Y676272D02*
X228810D01*
G01X220591D02*
X222631D01*
G01X216651D02*
X218691D01*
G01X212711D02*
X214751D01*
G01X222774Y676197D02*
X224388D01*
G01X218834D02*
X220448D01*
G01X214894D02*
X216508D01*
G01X232341Y675173D02*
X232581D01*
G01X216062Y674857D02*
X215354D01*
G01X220002D02*
X219294D01*
G01X223942D02*
X223234D01*
G01X224531Y674686D02*
X227531D01*
G01X220591D02*
X222631D01*
G01X216651D02*
X218691D01*
G01X212711D02*
X214751D01*
G01X224531Y674472D02*
X227531D01*
G01X214751D02*
X212711D01*
G01X218691D02*
X216651D01*
G01X222631D02*
X220591D01*
G01X222774Y674423D02*
X224388D01*
G01X218834D02*
X220448D01*
G01X214894D02*
X216508D01*
G01X213029Y674360D02*
X212654D01*
G01X216969D02*
X216594D01*
G01X214808D02*
X214433D01*
G01X220909D02*
X220534D01*
G01X218748D02*
X218373D01*
G01X222688D02*
X222313D01*
G01X224849D02*
X224474D01*
G01X217030Y674330D02*
X214373D01*
G01X220970D02*
X218313D01*
G01X224910D02*
X222253D01*
G01X232581Y674174D02*
X232031D01*
G01Y673973D02*
X232581D01*
G01X213111Y673948D02*
X213011D01*
G01X214451D02*
X214351D01*
G01X217326D02*
X216951D01*
G01X221266D02*
X220891D01*
G01X218391D02*
X218017D01*
G01X222331D02*
X221957D01*
G01X225206D02*
X224831D01*
G01X231608Y673922D02*
X231568D01*
G01X217030Y673780D02*
X214373D01*
G01X220970D02*
X218313D01*
G01X224910D02*
X222253D01*
G01X227531Y673772D02*
X214751D01*
G01X227531Y673572D02*
X214751D01*
G01X222774Y673230D02*
X224388D01*
G01X218834D02*
X220448D01*
G01X214894D02*
X216508D01*
G01X222231Y673022D02*
X224931D01*
G01X218291D02*
X220991D01*
G01X214751D02*
X217051D01*
G01X214351D02*
X214751D01*
G01X222774Y672880D02*
X224388D01*
G01X218834D02*
X220448D01*
G01X214894D02*
X216508D01*
G01X214751Y672825D02*
X227531D01*
G01X233981Y671672D02*
X214751D01*
G01X233981Y670072D02*
X214751D01*
G01D02*
X212539D01*
G01X231581Y669422D02*
X228081D01*
G01X216508Y668730D02*
X214894D01*
G01X220448D02*
X218834D01*
G01X224388D02*
X222774D01*
G01X212373Y686063D02*
X212351D01*
G01X213090Y673780D02*
X213111Y673781D01*
G01X231608Y673922D02*
X232100Y673939D01*
G01X232031Y685993D02*
X233513Y684993D01*
G01X223264Y685527D02*
X222831Y685896D01*
G01X222474Y685484D02*
X222907Y685115D01*
G01X219324Y685527D02*
X218891Y685896D01*
G01X218534Y685484D02*
X218967Y685115D01*
G01X215384Y685527D02*
X214951Y685896D01*
G01X214594Y685484D02*
X214726Y685372D01*
G01X214751Y685350D02*
X215027Y685115D01*
G01X222688Y674360D02*
X222255Y674729D01*
G01X221899Y674317D02*
X222331Y673948D01*
G01X218748Y674360D02*
X218315Y674729D01*
G01X217959Y674317D02*
X218391Y673948D01*
G01X214808Y674360D02*
X214676Y674472D01*
G01X214351Y674033D02*
X214451Y673948D01*
G01X220331Y685896D02*
X220688Y685484D01*
G01X220313D02*
X219957Y685896D01*
G01X220255Y685115D02*
X219899Y685527D01*
G01X216391Y685896D02*
X216748Y685484D01*
G01X216373D02*
X216017Y685896D01*
G01X216315Y685115D02*
X215959Y685527D01*
G01X224907Y674729D02*
X225264Y674317D01*
G01X224849Y674360D02*
X225206Y673948D01*
G01X224831D02*
X224474Y674360D01*
G01X212451Y685896D02*
X212808Y685484D01*
G01X212433D02*
X212351Y685579D01*
G01X220967Y674729D02*
X221324Y674317D01*
G01X220909Y674360D02*
X221266Y673948D01*
G01X220891D02*
X220534Y674360D01*
G01X217027Y674729D02*
X217384Y674317D01*
G01X216969Y674360D02*
X217326Y673948D01*
G01X216951D02*
X216594Y674360D01*
G01X213029D02*
X213111Y674265D01*
G01X213011Y673948D02*
X212654Y674360D01*
G01X228810Y676272D02*
X228400Y677398D01*
G01X226153Y683572D02*
X228178Y678006D01*
G01X223206Y685896D02*
X223264Y685527D01*
G01X222849Y685484D02*
X222907Y685115D01*
G01X222313Y674360D02*
X222255Y674729D01*
G01X221957Y673948D02*
X221899Y674317D01*
G01X219266Y685896D02*
X219324Y685527D01*
G01X218909Y685484D02*
X218967Y685115D01*
G01X218373Y674360D02*
X218315Y674729D01*
G01X218017Y673948D02*
X217959Y674317D01*
G01X215326Y685896D02*
X215384Y685527D01*
G01X214969Y685484D02*
X215027Y685115D01*
G01X214433Y674360D02*
X214415Y674472D01*
G01X233981Y674602D02*
Y670072D01*
G01Y689772D02*
Y685242D01*
G01X233031Y682172D02*
Y677672D01*
G01X232823Y682172D02*
Y677672D01*
G01X232655Y682172D02*
Y677672D01*
G01X232581Y673973D02*
Y685870D01*
G01X232400Y682172D02*
Y677672D01*
G01X232341Y682172D02*
Y684671D01*
G01Y675173D02*
Y677672D01*
G01X232179Y682172D02*
Y677672D01*
G01X232031Y685993D02*
Y673851D01*
G01X231581Y673322D02*
Y669422D01*
G01Y690422D02*
Y686522D01*
G01X231531Y677422D02*
Y673917D01*
G01Y685926D02*
Y682422D01*
G01X231321Y689772D02*
Y670072D01*
G01X231081Y682422D02*
Y677422D01*
G01X231021Y688172D02*
Y671672D01*
G01X228081Y690422D02*
Y669422D01*
G01X227531Y688172D02*
Y671672D01*
G01X224931Y673022D02*
Y674472D01*
G01X224910Y673780D02*
Y674330D01*
G01X224781Y673780D02*
Y674330D01*
G01X224637D02*
Y673780D01*
G01X224531Y678722D02*
Y674472D01*
G01X224428Y673780D02*
Y674330D01*
G01X224399Y673780D02*
Y674330D01*
G01X224388Y677586D02*
Y668730D01*
G01X223942Y677821D02*
Y674857D01*
G01X223731Y688172D02*
Y686272D01*
G01Y686072D02*
Y681972D01*
G01X223234Y674857D02*
Y677821D01*
G01X222931Y685372D02*
Y686822D01*
G01X222910Y685513D02*
Y686063D01*
G01X222781Y685513D02*
Y686063D01*
G01X222774Y668730D02*
Y677575D01*
G01X222763Y674330D02*
Y673780D01*
G01X222734Y674330D02*
Y673780D01*
G01X222637Y686063D02*
Y685513D01*
G01X222631Y678722D02*
Y674472D01*
G01X222531Y685372D02*
Y681122D01*
G01X222526Y673780D02*
Y674330D01*
G01X222428Y685513D02*
Y686063D01*
G01X222399Y685513D02*
Y686063D01*
G01X222388Y682269D02*
Y691113D01*
G01X222381Y674330D02*
Y673780D01*
G01X222253Y674330D02*
Y673780D01*
G01X222231Y674472D02*
Y673022D01*
G01X221928Y684986D02*
Y682023D01*
G01X221220D02*
Y684986D01*
G01X220991Y674472D02*
Y673022D01*
G01X220970Y673780D02*
Y674330D01*
G01X220841Y673780D02*
Y674330D01*
G01X220774Y682257D02*
Y691113D01*
G01X220763Y686063D02*
Y685513D01*
G01X220734Y686063D02*
Y685513D01*
G01X220697Y674330D02*
Y673780D01*
G01X220631Y685372D02*
Y681122D01*
G01X220591Y678722D02*
Y674472D01*
G01X220526Y685513D02*
Y686063D01*
G01X220488Y673780D02*
Y674330D01*
G01X220459Y673780D02*
Y674330D01*
G01X220448Y677586D02*
Y668730D01*
G01X220381Y686063D02*
Y685513D01*
G01X220253Y686063D02*
Y685513D01*
G01X220231Y686822D02*
Y685372D01*
G01X220002Y677821D02*
Y674857D01*
G01X219294D02*
Y677821D01*
G01X218991Y685372D02*
Y686822D01*
G01X218970Y685513D02*
Y686063D01*
G01X218841Y685513D02*
Y686063D01*
G01X218834Y668730D02*
Y677575D01*
G01X218823Y674330D02*
Y673780D01*
G01X218794Y674330D02*
Y673780D01*
G01X218697Y686063D02*
Y685513D01*
G01X218691Y678722D02*
Y674472D01*
G01X218591Y685372D02*
Y681122D01*
G01X218586Y673780D02*
Y674330D01*
G01X218488Y685513D02*
Y686063D01*
G01X218459Y685513D02*
Y686063D01*
G01X218448Y682269D02*
Y691113D01*
G01X218441Y674330D02*
Y673780D01*
G01X218313Y674330D02*
Y673780D01*
G01X218291Y674472D02*
Y673022D01*
G01X217988Y684986D02*
Y682023D01*
G01X217280D02*
Y684986D01*
G01X217051Y674472D02*
Y673022D01*
G01X217030Y673780D02*
Y674330D01*
G01X216901Y673780D02*
Y674330D01*
G01X216834Y682257D02*
Y691113D01*
G01X216823Y686063D02*
Y685513D01*
G01X216794Y686063D02*
Y685513D01*
G01X216757Y674330D02*
Y673780D01*
G01X216691Y685372D02*
Y681122D01*
G01X216651Y678722D02*
Y674472D01*
G01X216586Y685513D02*
Y686063D01*
G01X216548Y673780D02*
Y674330D01*
G01X216519Y673780D02*
Y674330D01*
G01X216508Y677586D02*
Y668730D01*
G01X216441Y686063D02*
Y685513D01*
G01X216313Y686063D02*
Y685513D01*
G01X216291Y686822D02*
Y685372D01*
G01X216062Y677821D02*
Y674857D01*
G01X215354D02*
Y677821D01*
G01X215051Y685372D02*
Y686822D01*
G01X215030Y685513D02*
Y686063D01*
G01X214901Y685513D02*
Y686063D01*
G01X214894Y668730D02*
Y677575D01*
G01X214883Y674330D02*
Y673780D01*
G01X214854Y674330D02*
Y673780D01*
G01X214757Y686063D02*
Y685513D01*
G01X214751Y673772D02*
Y670072D01*
G01Y685372D02*
Y674472D01*
G01Y689772D02*
Y686072D01*
G01X214651Y685372D02*
Y681122D01*
G01X214646Y673780D02*
Y674330D01*
G01X214548Y685513D02*
Y686063D01*
G01X214519Y685513D02*
Y686063D01*
G01X214508Y682269D02*
Y691113D01*
G01X214501Y674330D02*
Y673780D01*
G01X214373Y674330D02*
Y673780D01*
G01X214351Y674472D02*
Y673022D01*
G01X214048Y684986D02*
Y682023D01*
G01X213340D02*
Y684986D01*
G01X213111Y674472D02*
Y673022D01*
G01X213090Y673780D02*
Y674330D01*
G01X212961Y673780D02*
Y674330D01*
G01X212894Y682257D02*
Y691113D01*
G01X212883Y686063D02*
Y685513D01*
G01X212854Y686063D02*
Y685513D01*
G01X212817Y674330D02*
Y673780D01*
G01X212751Y685372D02*
Y681122D01*
G01X212711Y678722D02*
Y674472D01*
G01X212646Y685513D02*
Y686063D01*
G01X212608Y673780D02*
Y674330D01*
G01X212579Y673780D02*
Y674330D01*
G01X212568Y677586D02*
Y668730D01*
G01X212539Y670072D02*
Y671072D01*
G01X212501Y686063D02*
Y685513D01*
G01X212373Y686063D02*
Y685513D01*
G01X212351Y686822D02*
Y685372D01*
G01X212122Y677821D02*
Y674857D01*
G01X225264Y674317D02*
X225206Y673948D01*
G01X224907Y674729D02*
X224849Y674360D01*
G01X221324Y674317D02*
X221266Y673948D01*
G01X220967Y674729D02*
X220909Y674360D01*
G01X220255Y685115D02*
X220313Y685484D01*
G01X219899Y685527D02*
X219957Y685896D01*
G01X217384Y674317D02*
X217326Y673948D01*
G01X217027Y674729D02*
X216969Y674360D01*
G01X216315Y685115D02*
X216373Y685484D01*
G01X215959Y685527D02*
X216017Y685896D01*
G01X213047Y674472D02*
X213029Y674360D01*
G01X212415Y685372D02*
X212433Y685484D01*
G01X233513Y674850D02*
X232031Y673851D01*
G01X224831Y673948D02*
X225264Y674317D01*
G01X224474Y674360D02*
X224907Y674729D01*
G01X220891Y673948D02*
X221324Y674317D01*
G01X220534Y674360D02*
X220967Y674729D01*
G01X216951Y673948D02*
X217384Y674317D01*
G01X216594Y674360D02*
X217027Y674729D01*
G01X213011Y673948D02*
X213111Y674033D01*
G01X212654Y674360D02*
X212786Y674472D01*
G01X220688Y685484D02*
X220255Y685115D01*
G01X220331Y685896D02*
X219899Y685527D01*
G01X216748Y685484D02*
X216315Y685115D01*
G01X216391Y685896D02*
X215959Y685527D01*
G01X212808Y685484D02*
X212676Y685372D01*
G01X222688Y674360D02*
X222331Y673948D01*
G01X221957D02*
X222313Y674360D01*
G01X222255Y674729D02*
X221899Y674317D01*
G01X218748Y674360D02*
X218391Y673948D01*
G01X218017D02*
X218373Y674360D01*
G01X218315Y674729D02*
X217959Y674317D01*
G01X214808Y674360D02*
X214451Y673948D01*
G01X214351Y674265D02*
X214433Y674360D01*
G01X222907Y685115D02*
X223264Y685527D01*
G01X223206Y685896D02*
X222849Y685484D01*
G01X222474D02*
X222831Y685896D01*
G01X218967Y685115D02*
X219324Y685527D01*
G01X219266Y685896D02*
X218909Y685484D01*
G01X218534D02*
X218891Y685896D01*
G01X215027Y685115D02*
X215384Y685527D01*
G01X215326Y685896D02*
X214969Y685484D01*
G01X214594D02*
X214951Y685896D01*
G01X212451D02*
X212351Y685810D01*
G01X299363Y-714465D02*
Y-733402D01*
G01X352890Y27873D02*
X352943Y27626D01*
G01X352810Y28090D02*
X352890Y27873D01*
G01X352710Y28276D02*
X352810Y28090D01*
G01X352597Y28426D02*
X352710Y28276D01*
G01X352477Y28543D02*
X352597Y28426D01*
G01X352353Y28629D02*
X352477Y28543D01*
G01X352229Y28688D02*
X352353Y28629D01*
G01X352104Y28722D02*
X352229Y28688D01*
G01X351979Y28733D02*
X352104Y28722D01*
G01X347798Y24757D02*
X347731Y24780D01*
G01X347864Y24739D02*
X347798Y24757D01*
G01X347928Y24727D02*
X347864Y24739D01*
G01X353223Y17281D02*
X353151Y17404D01*
G01X353300Y17152D02*
X353223Y17281D01*
G01X353407Y17030D02*
X353300Y17152D01*
G01X353539Y16923D02*
X353407Y17030D01*
G01X353691Y16838D02*
X353539Y16923D01*
G01X353854Y16781D02*
X353691Y16838D01*
G01X352132Y24753D02*
X352062Y24740D01*
G01X352270Y24780D02*
X352132Y24753D01*
G01X353384Y24757D02*
X353451Y24780D01*
G01X353318Y24739D02*
X353384Y24757D01*
G01X353254Y24727D02*
X353318Y24739D01*
G01X348292Y27873D02*
X348239Y27626D01*
G01X348372Y28090D02*
X348292Y27873D01*
G01X348472Y28276D02*
X348372Y28090D01*
G01X348585Y28426D02*
X348472Y28276D01*
G01X348705Y28543D02*
X348585Y28426D01*
G01X348828Y28629D02*
X348705Y28543D01*
G01X348953Y28688D02*
X348828Y28629D01*
G01X349078Y28722D02*
X348953Y28688D01*
G01X349203Y28733D02*
X349078Y28722D01*
G01X349741Y28792D02*
X349641Y28714D01*
G01X349854Y28857D02*
X349741Y28792D01*
G01X349978Y28910D02*
X349854Y28857D01*
G01X350110Y28948D02*
X349978Y28910D01*
G01X350247Y28971D02*
X350110Y28948D01*
G01X350384Y28979D02*
X350247Y28971D01*
G01X341155Y54334D02*
X341268Y54264D01*
G01X341037Y54391D02*
X341155Y54334D01*
G01X340912Y54436D02*
X341037Y54391D01*
G01X340782Y54469D02*
X340912Y54436D01*
G01X340648Y54489D02*
X340782Y54469D01*
G01X340512Y54496D02*
X340648Y54489D01*
G01X351441Y28792D02*
X351541Y28714D01*
G01X351328Y28857D02*
X351441Y28792D01*
G01X351204Y28910D02*
X351328Y28857D01*
G01X351072Y28948D02*
X351204Y28910D01*
G01X350935Y28971D02*
X351072Y28948D01*
G01X350798Y28979D02*
X350935Y28971D01*
G01X338760Y54539D02*
X338741Y54704D01*
G01X338816Y54384D02*
X338760Y54539D01*
G01X338907Y54240D02*
X338816Y54384D01*
G01X339029Y54114D02*
X338907Y54240D01*
G01X339180Y54009D02*
X339029Y54114D01*
G01X339350Y53933D02*
X339180Y54009D01*
G01X339534Y53886D02*
X339350Y53933D01*
G01X339725Y53870D02*
X339534Y53886D01*
G01X353914Y55027D02*
X353937Y54830D01*
G01X353847Y55214D02*
X353914Y55027D01*
G01X353738Y55387D02*
X353847Y55214D01*
G01X353591Y55538D02*
X353738Y55387D01*
G01X353410Y55664D02*
X353591Y55538D01*
G01X353206Y55756D02*
X353410Y55664D01*
G01X352986Y55812D02*
X353206Y55756D01*
G01X352756Y55831D02*
X352986Y55812D01*
G01X339822Y62101D02*
X339425Y62032D01*
G01X340005Y62167D02*
X339822Y62101D01*
G01X340168Y62264D02*
X340005Y62167D01*
G01X340308Y62388D02*
X340168Y62264D01*
G01X340413Y62532D02*
X340308Y62388D01*
G01X340481Y62690D02*
X340413Y62532D01*
G01X340511Y62857D02*
X340481Y62690D01*
G01X340501Y63025D02*
X340511Y62857D01*
G01X340450Y63188D02*
X340501Y63025D01*
G01X340651Y53863D02*
X340512Y53870D01*
G01X340785Y53843D02*
X340651Y53863D01*
G01X340916Y53809D02*
X340785Y53843D01*
G01X341041Y53764D02*
X340916Y53809D01*
G01X341158Y53707D02*
X341041Y53764D01*
G01X341268Y53638D02*
X341158Y53707D01*
G01X352101Y28973D02*
X351979Y28979D01*
G01X352223Y28954D02*
X352101Y28973D01*
G01X352337Y28926D02*
X352223Y28954D01*
G01X352449Y28885D02*
X352337Y28926D01*
G01X352551Y28835D02*
X352449Y28885D01*
G01X352644Y28776D02*
X352551Y28835D01*
G01X340009Y12694D02*
X340017Y12669D01*
G01X339993Y12717D02*
X340009Y12694D01*
G01X339971Y12737D02*
X339993Y12717D01*
G01X347928Y24732D02*
X347929Y24736D01*
G01X347926Y24734D02*
X347928Y24732D01*
G01X349970Y13268D02*
X349962Y13278D01*
G01X349981Y13256D02*
X349970Y13268D01*
G01X339927Y12805D02*
X339922Y12843D01*
G01X339944Y12769D02*
X339927Y12805D01*
G01X339971Y12737D02*
X339944Y12769D01*
G01X339917Y63038D02*
X339727Y63089D01*
G01X340091Y62957D02*
X339917Y63038D01*
G01X340244Y62845D02*
X340091Y62957D01*
G01X340365Y62711D02*
X340244Y62845D01*
G01X340452Y62559D02*
X340365Y62711D01*
G01X340501Y62396D02*
X340452Y62559D01*
G01X340511Y62227D02*
X340501Y62396D01*
G01X340480Y62060D02*
X340511Y62227D01*
G01X340411Y61902D02*
X340480Y62060D01*
G01X340305Y61759D02*
X340411Y61902D01*
G01X340168Y61637D02*
X340305Y61759D01*
G01X340004Y61541D02*
X340168Y61637D01*
G01X339821Y61475D02*
X340004Y61541D01*
G01X339424Y61405D02*
X339821Y61475D01*
G01X346087Y54402D02*
X346063Y54204D01*
G01X346154Y54589D02*
X346087Y54402D01*
G01X346263Y54761D02*
X346154Y54589D01*
G01X346409Y54912D02*
X346263Y54761D01*
G01X346591Y55038D02*
X346409Y54912D01*
G01X346794Y55130D02*
X346591Y55038D01*
G01X347015Y55186D02*
X346794Y55130D01*
G01X347244Y55205D02*
X347015Y55186D01*
G01X337398Y62979D02*
X337363Y62793D01*
G01X337499Y63154D02*
X337398Y62979D01*
G01X338323Y62705D02*
X338192Y63075D01*
G01X338544Y62398D02*
X338323Y62705D01*
G01X340738Y51981D02*
X340512Y51969D01*
G01X340940Y52007D02*
X340738Y51981D01*
G01X341119Y52047D02*
X340940Y52007D01*
G01X341274Y52102D02*
X341119Y52047D01*
G01X341402Y52169D02*
X341274Y52102D01*
G01X341502Y52247D02*
X341402Y52169D01*
G01X341577Y52334D02*
X341502Y52247D01*
G01X341630Y52431D02*
X341577Y52334D01*
G01X341664Y52539D02*
X341630Y52431D01*
G01X341677Y52661D02*
X341664Y52539D01*
G01X341668Y52798D02*
X341677Y52661D01*
G01X341635Y52947D02*
X341668Y52798D01*
G01X341579Y53107D02*
X341635Y52947D01*
G01X341500Y53277D02*
X341579Y53107D01*
G01X341396Y53454D02*
X341500Y53277D01*
G01X341268Y53638D02*
X341396Y53454D01*
G01X340073Y12401D02*
X340001Y12583D01*
G01X340190Y12227D02*
X340073Y12401D01*
G01X339932Y12938D02*
X339922Y13001D01*
G01X339963Y12881D02*
X339932Y12938D01*
G01X351726Y28363D02*
X351772Y28201D01*
G01X351647Y28535D02*
X351726Y28363D01*
G01X351541Y28714D02*
X351647Y28535D01*
G01X340755Y51988D02*
X340512Y51969D01*
G01X340969Y52028D02*
X340755Y51988D01*
G01X341153Y52090D02*
X340969Y52028D01*
G01X341302Y52169D02*
X341153Y52090D01*
G01X341421Y52262D02*
X341302Y52169D01*
G01X341515Y52370D02*
X341421Y52262D01*
G01X341588Y52495D02*
X341515Y52370D01*
G01X341640Y52640D02*
X341588Y52495D01*
G01X341670Y52809D02*
X341640Y52640D01*
G01X341675Y53003D02*
X341670Y52809D01*
G01X341653Y53219D02*
X341675Y53003D01*
G01X341602Y53454D02*
X341653Y53219D01*
G01X341522Y53708D02*
X341602Y53454D01*
G01X341411Y53978D02*
X341522Y53708D01*
G01X341268Y54264D02*
X341411Y53978D01*
G01X355808Y2140D02*
X355670Y2150D01*
G01X351514Y-1386D02*
X351455Y-1181D01*
G01X351577Y-1583D02*
X351514Y-1386D01*
G01X351644Y-1771D02*
X351577Y-1583D01*
G01X352756Y28616D02*
X352644Y28776D01*
G01X352843Y28465D02*
X352756Y28616D01*
G01X352913Y28308D02*
X352843Y28465D01*
G01X352953Y28169D02*
X352913Y28308D01*
G01X339990Y12831D02*
X339963Y12881D01*
G01X340003Y12775D02*
X339990Y12831D01*
G01X339943Y12648D02*
X340018Y12422D01*
G01X339922Y12844D02*
X339943Y12648D01*
G01X352951Y27589D02*
X352953Y27581D01*
G01X352950Y27597D02*
X352951Y27589D01*
G01X352948Y27605D02*
X352950Y27597D01*
G01X352946Y27613D02*
X352948Y27605D01*
G01X352944Y27621D02*
X352946Y27613D01*
G01X352943Y27626D02*
X352944Y27621D01*
G01X353124Y17633D02*
X353084Y17857D01*
G01X353176Y17411D02*
X353124Y17633D01*
G01X350922Y28722D02*
X350798Y28733D01*
G01X351047Y28688D02*
X350922Y28722D01*
G01X351172Y28629D02*
X351047Y28688D01*
G01X351296Y28543D02*
X351172Y28629D01*
G01X351416Y28426D02*
X351296Y28543D01*
G01X351529Y28276D02*
X351416Y28426D01*
G01X351629Y28090D02*
X351529Y28276D01*
G01X351709Y27873D02*
X351629Y28090D01*
G01X351762Y27626D02*
X351709Y27873D01*
G01X353345Y25544D02*
X353451Y24974D01*
G01X353239Y26098D02*
X353345Y25544D01*
G01X353133Y26591D02*
X353239Y26098D01*
G01X352884Y27667D02*
X352971Y27328D01*
G01X352802Y28015D02*
X352884Y27667D01*
G01X352725Y28378D02*
X352802Y28015D01*
G01X352830Y27869D02*
X352929Y27428D01*
G01X352736Y28317D02*
X352830Y27869D01*
G01X352644Y28776D02*
X352736Y28317D01*
G01X351764Y27618D02*
X351762Y27626D01*
G01X351766Y27610D02*
X351764Y27618D01*
G01X351768Y27602D02*
X351766Y27610D01*
G01X351769Y27594D02*
X351768Y27602D01*
G01X351771Y27586D02*
X351769Y27594D01*
G01X351772Y27581D02*
X351771Y27586D01*
G01X352058Y26098D02*
X351952Y26591D01*
G01X352164Y25544D02*
X352058Y26098D01*
G01X352270Y24974D02*
X352164Y25544D01*
G01X353240Y18119D02*
X353277Y17856D01*
G01X353199Y18392D02*
X353240Y18119D01*
G01X353155Y18674D02*
X353199Y18392D01*
G01X340005Y12746D02*
X340003Y12768D01*
G01X340017Y12669D02*
X340005Y12746D01*
G01X352190Y25425D02*
X352270Y24780D01*
G01X352111Y26052D02*
X352190Y25425D01*
G01X352032Y26658D02*
X352111Y26052D01*
G01X351952Y27205D02*
X352032Y26658D01*
G01X351818Y26871D02*
X351880Y26367D01*
G01X351754Y27328D02*
X351818Y26871D01*
G01X353176Y25396D02*
X353258Y24743D01*
G01X353093Y26104D02*
X353176Y25396D01*
G01X353011Y26772D02*
X353093Y26104D01*
G01X352937Y27324D02*
X353011Y26772D01*
G01X339530Y54512D02*
X339725Y54496D01*
G01X339347Y54560D02*
X339530Y54512D01*
G01X339177Y54637D02*
X339347Y54560D01*
G01X339029Y54740D02*
X339177Y54637D01*
G01X338905Y54868D02*
X339029Y54740D01*
G01X338815Y55012D02*
X338905Y54868D01*
G01X338759Y55168D02*
X338815Y55012D01*
G01X338741Y55330D02*
X338759Y55168D01*
G01X339746Y55722D02*
X339922Y55462D01*
G01X339623Y55973D02*
X339746Y55722D01*
G01X339551Y56207D02*
X339623Y55973D01*
G01X339528Y56417D02*
X339551Y56207D01*
G01X353206Y26707D02*
X353133Y27206D01*
G01X353283Y26127D02*
X353206Y26707D01*
G01X353011Y26772D02*
X352937Y27328D01*
G01X353093Y26104D02*
X353011Y26772D01*
G01X353176Y25396D02*
X353093Y26104D01*
G01X353256Y24734D02*
X353176Y25396D01*
G01X352008Y25286D02*
X352062Y24741D01*
G01X351880Y26367D02*
X352008Y25286D01*
G01X352990Y55185D02*
X352756Y55205D01*
G01X353210Y55128D02*
X352990Y55185D01*
G01X353413Y55036D02*
X353210Y55128D01*
G01X353591Y54912D02*
X353413Y55036D01*
G01X353740Y54758D02*
X353591Y54912D01*
G01X353848Y54585D02*
X353740Y54758D01*
G01X353915Y54398D02*
X353848Y54585D01*
G01X353937Y54204D02*
X353915Y54398D01*
G01X338914Y55719D02*
X338741Y55462D01*
G01X339037Y55968D02*
X338914Y55719D01*
G01X339110Y56204D02*
X339037Y55968D01*
G01X339134Y56417D02*
X339110Y56204D01*
G01X347011Y55811D02*
X347244Y55831D01*
G01X346791Y55754D02*
X347011Y55811D01*
G01X346587Y55662D02*
X346791Y55754D01*
G01X346409Y55538D02*
X346587Y55662D01*
G01X346261Y55384D02*
X346409Y55538D01*
G01X346152Y55211D02*
X346261Y55384D01*
G01X346086Y55024D02*
X346152Y55211D01*
G01X346063Y54830D02*
X346086Y55024D01*
G01X339233Y61333D02*
X339424Y61405D01*
G01X339066Y61231D02*
X339233Y61333D01*
G01X338928Y61101D02*
X339066Y61231D01*
G01X338826Y60950D02*
X338928Y61101D01*
G01X338762Y60784D02*
X338826Y60950D01*
G01X338741Y60611D02*
X338762Y60784D01*
G01X348006Y25396D02*
X348089Y26104D01*
G01X347926Y24734D02*
X348006Y25396D01*
G01D02*
X347924Y24743D01*
G01X348089Y26104D02*
X348006Y25396D01*
G01X348171Y26772D02*
X348089Y26104D01*
G01X347976Y26707D02*
X348049Y27206D01*
G01X347899Y26127D02*
X347976Y26707D01*
G01X347731Y24780D02*
X347899Y26127D01*
G01X349301Y26367D02*
X349174Y25286D01*
G01X349364Y26871D02*
X349301Y26367D01*
G01X349428Y27328D02*
X349364Y26871D01*
G01X348992Y25425D02*
X348912Y24780D01*
G01X349071Y26052D02*
X348992Y25425D01*
G01X349150Y26658D02*
X349071Y26052D01*
G01X349230Y27205D02*
X349150Y26658D01*
G01X347942Y18119D02*
X347905Y17856D01*
G01X347983Y18392D02*
X347942Y18119D01*
G01X348027Y18674D02*
X347983Y18392D01*
G01X338717Y63015D02*
X338806Y63053D01*
G01X338642Y62967D02*
X338717Y63015D01*
G01X338588Y62913D02*
X338642Y62967D01*
G01X338555Y62854D02*
X338588Y62913D01*
G01X338544Y62793D02*
X338555Y62854D01*
G01X349124Y26098D02*
X349230Y26591D01*
G01X349018Y25544D02*
X349124Y26098D01*
G01X348912Y24974D02*
X349018Y25544D01*
G01X349418Y27618D02*
X349420Y27626D01*
G01X349416Y27610D02*
X349418Y27618D01*
G01X349414Y27602D02*
X349416Y27610D01*
G01X349412Y27594D02*
X349414Y27602D01*
G01X349411Y27586D02*
X349412Y27594D01*
G01X349410Y27581D02*
X349411Y27586D01*
G01X348352Y27869D02*
X348253Y27428D01*
G01X348446Y28317D02*
X348352Y27869D01*
G01X348537Y28776D02*
X348446Y28317D01*
G01X348298Y27667D02*
X348211Y27328D01*
G01X348379Y28015D02*
X348298Y27667D01*
G01X348457Y28378D02*
X348379Y28015D01*
G01X347837Y25544D02*
X347731Y24974D01*
G01X347943Y26098D02*
X347837Y25544D01*
G01X348049Y26591D02*
X347943Y26098D01*
G01X350259Y28722D02*
X350384Y28733D01*
G01X350135Y28688D02*
X350259Y28722D01*
G01X350010Y28629D02*
X350135Y28688D01*
G01X349886Y28543D02*
X350010Y28629D01*
G01X349766Y28426D02*
X349886Y28543D01*
G01X349653Y28276D02*
X349766Y28426D01*
G01X349553Y28090D02*
X349653Y28276D01*
G01X349473Y27873D02*
X349553Y28090D01*
G01X349420Y27626D02*
X349473Y27873D01*
G01X348058Y17633D02*
X348097Y17857D01*
G01X348005Y17411D02*
X348058Y17633D01*
G01X348230Y27589D02*
X348229Y27581D01*
G01X348232Y27597D02*
X348230Y27589D01*
G01X348234Y27605D02*
X348232Y27597D01*
G01X348236Y27613D02*
X348234Y27605D01*
G01X348237Y27621D02*
X348236Y27613D01*
G01X348239Y27626D02*
X348237Y27621D01*
G01X348426Y28616D02*
X348537Y28776D01*
G01X348339Y28465D02*
X348426Y28616D01*
G01X348269Y28308D02*
X348339Y28465D01*
G01X348229Y28169D02*
X348269Y28308D01*
G01X348424Y-1583D02*
X348357Y-1771D01*
G01X348487Y-1386D02*
X348424Y-1583D01*
G01X348546Y-1181D02*
X348487Y-1386D01*
G01X349456Y28363D02*
X349410Y28201D01*
G01X349535Y28535D02*
X349456Y28363D01*
G01X349641Y28714D02*
X349535Y28535D01*
G01X339437Y5121D02*
X339554Y5289D01*
G01X339358Y5008D02*
X339437Y5121D01*
G01X349080Y28973D02*
X349203Y28979D01*
G01X348959Y28954D02*
X349080Y28973D01*
G01X348845Y28926D02*
X348959Y28954D01*
G01X348733Y28885D02*
X348845Y28926D01*
G01X348631Y28835D02*
X348733Y28885D01*
G01X348537Y28776D02*
X348631Y28835D01*
G01X339387Y4997D02*
X339431Y5042D01*
G01X339274Y4939D02*
X339387Y4997D01*
G01X338762Y61411D02*
X338741Y61237D01*
G01X338827Y61579D02*
X338762Y61411D01*
G01X338931Y61730D02*
X338827Y61579D01*
G01X339070Y61859D02*
X338931Y61730D01*
G01X339237Y61961D02*
X339070Y61859D01*
G01X339425Y62032D02*
X339237Y61961D01*
G01X347959Y17281D02*
X348031Y17404D01*
G01X347881Y17152D02*
X347959Y17281D01*
G01X347775Y17030D02*
X347881Y17152D01*
G01X347643Y16923D02*
X347775Y17030D01*
G01X347491Y16838D02*
X347643Y16923D01*
G01X347328Y16781D02*
X347491Y16838D01*
G01X353937Y46049D02*
G03X354331Y45367I787J0D01*
G01X353937Y43898D02*
G03X354331Y45367I0J787D01*
G01X350213Y46481D02*
G03X349795Y46654I-418J-418D01*
G01X350827Y44489D02*
G03X351418Y43898I591J0D01*
G01X350827Y45622D02*
G03X350654Y46040I-590J1D01*
G01X348880Y39685D02*
G03X349449Y39364I1042J1182D01*
G01X348750Y39699D02*
G03X349425Y39289I1172J1168D01*
G01X348601Y39685D02*
G03X349390Y39177I1320J1183D01*
G01X349804Y38613D02*
G03X349390Y39177I-591J0D01*
G01X349922Y38613D02*
G03X349426Y39289I-709J0D01*
G01X350000Y38613D02*
G03X349449Y39364I-787J0D01*
G01X350000Y36096D02*
G03X349902Y36267I-198J0D01*
G01X349804Y36437D02*
G03X349902Y36267I196J0D01*
G01X350000Y36044D02*
G03X349902Y36214I-196J0D01*
G01X349804Y36385D02*
G03X349902Y36214I198J0D01*
G01X349203Y30906D02*
G03X346670Y28707I0J-2558D01*
G01X353331D02*
G03X350798Y30906I-2533J-359D01*
G01X350384D02*
G03X347851Y28707I0J-2558D01*
G01X354512D02*
G03X351979Y30906I-2533J-359D01*
G01X354528Y17409D02*
G03X356087Y17631I779J111D01*
G01X353347Y17409D02*
G03X354906Y17631I780J111D01*
G01X354333Y17382D02*
G03X356004Y18216I974J139D01*
G01X354495Y9761D02*
G03X355079Y10521I-203J760D01*
G01X355616Y7259D02*
G03X355867Y7835I-537J577D01*
G01X354699Y9000D02*
G03X355867Y10521I-406J1521D01*
G01X349185Y17879D02*
G03X348991Y15660I1012J-1206D01*
G01X348679Y18482D02*
G03X348388Y15154I1518J-1809D01*
G01X352473Y8403D02*
G03X351890Y7615I204J-760D01*
G01X352269Y9164D02*
G03X351103Y7588I408J-1521D01*
G01X352645Y4489D02*
G03X352320Y4027I941J-1007D01*
G01X352003Y3293D02*
G03X351890Y2747I1265J-546D01*
G01X352813Y-1911D02*
G03X353298Y-2165I485J336D01*
G01X351221Y-669D02*
G03X351811Y-1259I590J0D01*
G01X352813Y-1911D02*
G03X351644Y-1771I-647J-450D01*
G01X353298Y-1574D02*
G03X351455Y-1181I-1131J-787D01*
G01X347402Y41930D02*
G03X347008Y42323I-393J0D01*
G01Y40355D02*
G03X347402Y40748I0J394D01*
G01X346615Y41536D02*
G03X345741Y41898I-512J0D01*
G01X345363Y46654D02*
G03X344946Y46481I1J-591D01*
G01X344504Y46040D02*
G03X344331Y45622I418J-418D01*
G01X343741Y43898D02*
G03X344331Y44489I0J590D01*
G01X343741Y41435D02*
G03X344749Y41017I591J0D01*
G01X346693Y41536D02*
G03X345685Y41953I-590J0D01*
G01X343662Y41435D02*
G03X344804Y40961I669J0D01*
G01X345670Y45367D02*
G03X346063Y43898I393J-682D01*
G01X345670Y45367D02*
G03X346063Y46049I-395J682D01*
G01X347402Y34449D02*
G03X347008Y34843I-394J0D01*
G01Y32874D02*
G03X347402Y33268I0J394D01*
G01X345741Y33300D02*
G03X346615Y33662I362J362D01*
G01X344749Y34181D02*
G03X343741Y33763I-417J-418D01*
G01X345685Y33244D02*
G03X346693Y33662I417J418D01*
G01X344804Y34236D02*
G03X343662Y33763I-473J-473D01*
G01X339725Y42520D02*
G03X339922Y42323I197J0D01*
G01X342874Y40748D02*
G03X343268Y40355I393J0D01*
G01Y42323D02*
G03X342874Y41930I0J-394D01*
G01X338544Y42520D02*
G03X338740Y41810I1378J-2D01*
G01X342874Y33268D02*
G03X343268Y32874I394J0D01*
G01Y34843D02*
G03X342874Y34449I0J-394D01*
G01X346276Y17631D02*
G03X347835Y17409I779J-111D01*
G01X345095Y17631D02*
G03X346654Y17409I780J-111D01*
G01X345178Y18216D02*
G03X346849Y17382I696J-696D01*
G01X348679Y18482D02*
G03X349804Y20819I-2024J2414D01*
G01X349185Y17879D02*
G03X350000Y18819I-2530J3017D01*
G01X347402Y12402D02*
G03X347008Y12796I-394J0D01*
G01Y10827D02*
G03X347402Y11221I0J394D01*
G01X346615Y12008D02*
G03X345741Y12370I-512J0D01*
G01X346693Y12008D02*
G03X345685Y12426I-591J0D01*
G01X343741Y11907D02*
G03X344749Y11489I591J0D01*
G01X343662Y11907D02*
G03X344804Y11434I669J0D01*
G01X347402Y4922D02*
G03X347008Y5315I-393J0D01*
G01Y3347D02*
G03X347402Y3741I0J394D01*
G01X345741Y3772D02*
G03X346615Y4134I362J362D01*
G01X346703Y-2165D02*
G03X347188Y-1911I0J590D01*
G01X344749Y4653D02*
G03X343741Y4236I-418J-417D01*
G01X345685Y3717D02*
G03X346693Y4134I418J417D01*
G01X344804Y4709D02*
G03X343662Y4236I-473J-473D01*
G01X348357Y-1771D02*
G03X347188Y-1911I-522J-590D01*
G01X348546Y-1181D02*
G03X346703Y-1574I-712J-1180D01*
G01X343268Y12796D02*
G03X342874Y12402I0J-394D01*
G01Y11221D02*
G03X343268Y10827I394J0D01*
G01X340003Y12775D02*
G03X339963Y12881I-197J-14D01*
G01X339922Y13001D02*
G03X339963Y12881I196J0D01*
G01X340003Y12775D02*
G03X340266Y12203I903J69D01*
G01X340190Y12227D02*
G03X340238Y12175I718J614D01*
G01X339922Y12843D02*
G03X340210Y12147I985J0D01*
G01X338741Y12843D02*
G03X339375Y11312I2166J0D01*
G01X339833Y10965D02*
G03X339722Y11021I-140J-139D01*
G01X339610Y11076D02*
G03X339722Y11021I139J141D01*
G01X340612Y8925D02*
G03X340501Y10186I-807J564D01*
G01X340644Y8902D02*
G03X340529Y10213I-839J587D01*
G01X340676Y8880D02*
G03X340557Y10241I-871J610D01*
G01X341579Y8248D02*
G03X341336Y11021I-1774J1242D01*
G01X341611Y8225D02*
G03X341364Y11049I-1806J1265D01*
G01X341644Y8202D02*
G03X341392Y11076I-1839J1287D01*
G01X339086Y6677D02*
G03X338986Y6603I61J-187D01*
G01X339086Y6677D02*
G03X339186Y6751I-61J187D01*
G01X339331Y4968D02*
G03X339431Y5042I-61J187D01*
G01X339331Y4968D02*
G03X339231Y4894I61J-187D01*
G01X342874Y3741D02*
G03X343268Y3347I394J0D01*
G01Y5315D02*
G03X342874Y4922I0J-394D01*
G01X287520Y3937D02*
G03X291457Y0I3937J0D01*
G01X353258Y24743D02*
X353448Y24803D01*
G01X353052Y54366D02*
X350985Y53642D01*
G01X349428Y27328D02*
X349233Y27224D01*
G01X352813Y-1911D02*
X353298Y-1574D01*
G01X350000Y13310D02*
X349962Y13278D01*
G01X352953Y62028D02*
X346949Y57592D01*
G01X353052Y62359D02*
X347008Y57894D01*
G01X348991Y15660D02*
X348388Y15154D01*
G01X340219Y12253D02*
X340160Y12201D01*
G01X352953Y54154D02*
X352166Y53453D01*
G01X355616Y7259D02*
X352645Y4489D01*
G01X339922Y-1574D02*
X339331Y-2165D01*
G01X345741Y12370D02*
X344804Y11434D01*
G01X345685Y12426D02*
X344749Y11489D01*
G01X341392Y11076D02*
X340501Y10186D01*
G01X340139Y10659D02*
X340084Y10603D01*
G01X340266Y12203D02*
X339375Y11312D01*
G01X353256Y24734D02*
X353253Y24732D01*
G01X339387Y4997D02*
X339431Y5042D01*
G01X339231Y4894D02*
X339274Y4939D01*
G01X348229Y30433D02*
X346260Y28465D01*
G01X353544Y45197D02*
X352363Y44016D01*
G01X345741Y41898D02*
X344804Y40961D01*
G01X345685Y41953D02*
X344749Y41017D01*
G01X344036Y44804D02*
X343248Y44016D01*
G01X344946Y46481D02*
X344504Y46040D01*
G01X340020Y45197D02*
X340611Y45788D01*
G01X341890Y51496D02*
X341693Y51300D01*
G01X353258Y24743D02*
X353253Y24736D01*
G01X341611Y8225D02*
X339435Y5119D01*
G01X341644Y8202D02*
X339431Y5042D01*
G01X341579Y8248D02*
X338339Y3621D01*
G01X340676Y8880D02*
X339186Y6751D01*
G01X340644Y8902D02*
X339086Y6677D01*
G01X340612Y8925D02*
X337823Y4943D01*
G01X339331Y4968D02*
X339358Y5008D01*
G01X339357Y5007D02*
X339331Y4968D01*
G01X352130Y725D02*
X351947Y325D01*
G01X352320Y4027D02*
X352003Y3293D01*
G01X349449Y39364D02*
X349390Y39177D01*
G01X348049Y27206D02*
X348229Y28169D01*
G01X349230Y26591D02*
X349410Y27581D01*
G01X348229D02*
X348049Y26591D01*
G01X349410Y28201D02*
X349230Y27205D01*
G01X348226Y18635D02*
X348098Y17857D01*
G01X346917D02*
X347045Y18635D01*
G01X346718Y17857D02*
X346846Y18674D01*
G01X349641Y28714D02*
X349428Y27328D01*
G01X348224Y18621D02*
X349111Y24742D01*
G01X348912Y24780D02*
X348027Y18674D01*
G01Y18869D02*
X348912Y24974D01*
G01X347928Y24727D02*
X347042Y18621D01*
G01X346846Y18674D02*
X347731Y24780D01*
G01Y24974D02*
X346846Y18869D01*
G01X347899Y17857D02*
X347835Y17409D01*
G01X346916Y17857D02*
X346849Y17382D01*
G01X346718Y17857D02*
X346654Y17409D01*
G01X347851Y28707D02*
X346276Y17631D01*
G01X346670Y28707D02*
X345095Y17631D01*
G01X348171Y26772D02*
X348245Y27328D01*
G01X347899Y17857D02*
X348027Y18869D01*
G01X346846D02*
X346718Y17857D01*
G01X347928Y24727D02*
X347929Y24741D01*
G01X349174Y25286D02*
X349119Y24741D01*
G01X349998Y28885D02*
X349804Y20819D01*
G01X355670Y39685D02*
Y2150D01*
G01X355079Y10521D02*
Y39685D01*
G01X354336Y18869D02*
Y18674D01*
G01X354134Y34370D02*
Y30433D01*
G01Y77976D02*
Y55532D01*
G01X353937Y46049D02*
Y83689D01*
G01Y8780D02*
Y39685D01*
G01X353544Y48150D02*
Y45197D01*
G01X353465Y5253D02*
Y-78D01*
G01X353451Y24780D02*
Y24974D01*
G01X353298Y-1574D02*
Y-2165D01*
G01X353155Y18674D02*
Y18869D01*
G01X353150Y39685D02*
Y11170D01*
G01Y83689D02*
Y54241D01*
G01X353133Y26591D02*
Y27206D01*
G01X353052Y62359D02*
Y63512D01*
G01Y54366D02*
Y55704D01*
G01X352953Y28169D02*
Y27581D01*
G01X352756Y55831D02*
Y55205D01*
G01X352559Y58682D02*
Y55532D01*
G01X352270Y24974D02*
Y24780D01*
G01X352166Y53453D02*
Y51595D01*
G01Y58682D02*
Y55532D01*
G01X351979Y28733D02*
Y28979D01*
G01X351969Y11170D02*
Y10945D01*
G01X351952Y27205D02*
Y26591D01*
G01X351890Y2747D02*
Y-78D01*
G01X351772Y27581D02*
Y28201D01*
G01X351516Y39685D02*
Y44016D01*
G01X351221Y-669D02*
Y-78D01*
G01X351181Y11170D02*
Y10945D01*
G01X351122Y44804D02*
Y46969D01*
G01X351103Y11170D02*
Y7993D01*
G01X350985Y53642D02*
Y51595D01*
G01X350827Y44489D02*
Y45622D01*
G01X350798Y28979D02*
Y28733D01*
G01X350591Y7993D02*
Y80D01*
G01X350384Y28979D02*
Y28733D01*
G01X350000Y39685D02*
Y1103D01*
G01X349902Y38613D02*
Y36214D01*
G01X349804Y38613D02*
Y36385D01*
G01X349410Y27581D02*
Y28201D01*
G01X349230Y27205D02*
Y26591D01*
G01X349203Y28733D02*
Y28979D01*
G01X348912Y24974D02*
Y24780D01*
G01X348229Y28169D02*
Y27581D01*
G01Y34370D02*
Y30433D01*
G01X348049Y26591D02*
Y27206D01*
G01X348027Y18674D02*
Y18869D01*
G01X347731Y24780D02*
Y24974D01*
G01X353252Y24741D02*
X353254Y24727D01*
G01X353451Y24780D02*
X353283Y26127D01*
G01X354336Y18869D02*
X354464Y17857D01*
G01X353283D02*
X353155Y18869D01*
G01X347402Y40748D02*
Y41930D01*
G01Y33268D02*
Y34449D01*
G01Y11221D02*
Y12402D01*
G01Y3741D02*
Y4922D01*
G01X347244Y55205D02*
Y55831D01*
G01X346949Y57592D02*
Y56341D01*
G01X346851Y73522D02*
Y55217D01*
G01X346846Y18869D02*
Y18674D01*
G01X346703Y-2165D02*
Y-1574D01*
G01X346693Y33662D02*
Y41536D01*
G01Y4134D02*
Y12008D01*
G01X346615Y33662D02*
Y41536D01*
G01Y4134D02*
Y12008D01*
G01X346457Y45197D02*
Y48150D01*
G01X346063Y54830D02*
Y46049D01*
G01Y73522D02*
Y55217D01*
G01X346024Y57894D02*
Y56122D01*
G01X344331Y45622D02*
Y44489D01*
G01X344036Y44804D02*
Y46969D01*
G01X343741Y41435D02*
Y43898D01*
G01Y11907D02*
Y33763D01*
G01Y-2165D02*
Y4236D01*
G01X343662Y41435D02*
Y43898D01*
G01Y11907D02*
Y33763D01*
G01Y-2165D02*
Y4236D01*
G01X343642Y44016D02*
Y39685D01*
G01X343071Y48347D02*
Y45788D01*
G01X342973Y45886D02*
Y48248D01*
G01X342874Y4922D02*
Y3741D01*
G01Y12402D02*
Y11221D01*
G01Y34449D02*
Y33268D01*
G01Y41930D02*
Y40748D01*
G01X341693Y51300D02*
Y48544D01*
G01X341677Y52675D02*
Y52940D01*
G01X341595Y48248D02*
Y51595D01*
G01X341268Y54264D02*
Y53638D01*
G01X341201Y39685D02*
Y54646D01*
G01X340611Y49421D02*
Y45788D01*
G01X340512Y62272D02*
Y62898D01*
G01Y51969D02*
Y-2165D01*
G01Y54496D02*
Y53870D01*
G01X340118Y97067D02*
Y45886D01*
G01X340020Y51496D02*
Y30433D01*
G01X339922Y-1574D02*
Y97245D01*
G01X339725Y53870D02*
Y54496D01*
G01Y49421D02*
Y42520D01*
G01X339626Y62067D02*
Y61441D01*
G01X339528Y96319D02*
Y56417D01*
G01X339233Y49421D02*
Y50985D01*
G01Y47756D02*
Y45197D01*
G01Y89961D02*
Y53347D01*
G01X339134Y56417D02*
Y97165D01*
G01X338741Y-2165D02*
Y97245D01*
G01X338544Y97445D02*
Y42520D01*
G01X337363Y97445D02*
Y62003D01*
G01X339963Y12864D02*
Y12881D01*
G01X352130Y725D02*
X351890Y7615D01*
G01X351316Y1485D02*
X351103Y7588D01*
G01X339963Y12864D02*
X339965Y12816D01*
G01D02*
X339971Y12737D01*
G01X354512Y28707D02*
X356087Y17631D01*
G01X353331Y28707D02*
X354906Y17631D01*
G01X354464Y17857D02*
X354528Y17409D01*
G01X354265Y17857D02*
X354333Y17382D01*
G01X353283Y17857D02*
X353347Y17409D01*
G01X353451Y24974D02*
X354336Y18869D01*
G01Y18674D02*
X353451Y24780D01*
G01X353254Y24727D02*
X354139Y18621D01*
G01X353155Y18869D02*
X352270Y24974D01*
G01Y24780D02*
X353155Y18674D01*
G01X352958Y18621D02*
X352071Y24742D01*
G01X351541Y28714D02*
X351754Y27328D01*
G01X354464Y17857D02*
X354336Y18674D01*
G01X354265Y17857D02*
X354137Y18635D01*
G01X352956D02*
X353084Y17857D01*
G01X337823Y4943D02*
X338017Y3846D01*
G01X351772Y28201D02*
X351952Y27205D01*
G01X352953Y27581D02*
X353133Y26591D01*
G01X351952D02*
X351772Y27581D01*
G01X353133Y27206D02*
X352953Y28169D01*
G01X339971Y12737D02*
X340002Y12582D01*
G01X287520Y3937D02*
Y429331D01*
G01X340003Y12775D02*
X339990Y12831D01*
G01X339233Y45197D02*
X340020Y42259D01*
G01X340053Y12544D02*
X340017Y12669D01*
G01X351316Y1485D02*
X351672Y315D01*
G01X340120Y12396D02*
X340051Y12548D01*
G01X339963Y12881D02*
X339932Y12938D01*
G01X350000Y1103D02*
X351364Y-1259D01*
G01X340018Y12422D02*
X340160Y12201D01*
G01X340219Y12253D02*
X340118Y12399D01*
G01X347924Y24743D02*
X347929Y24736D01*
G01X350213Y46481D02*
X350654Y46040D01*
G01X351122Y44804D02*
X351910Y44016D01*
G01X348679Y18482D02*
X349185Y17879D01*
G01X348991Y15660D02*
X350000Y14457D01*
G01X348388Y15154D02*
X349962Y13278D01*
G01X349967Y13271D02*
X349976Y13262D01*
G01X349989Y13246D02*
X349981Y13255D01*
G01X349992Y13244D02*
X349981Y13255D01*
G01X349995Y13240D02*
X349989Y13246D01*
G01X349992Y13244D02*
X350000Y13234D01*
G01X346457Y45197D02*
X347638Y44016D01*
G01X341693Y48544D02*
X341890Y48347D01*
G01X356103Y28465D02*
X354134Y30433D01*
G01X340020Y40867D02*
X341201Y39685D01*
G01X344804Y34236D02*
X345741Y33300D01*
G01X344749Y34181D02*
X345685Y33244D01*
G01X341989Y28465D02*
X340020Y30433D01*
G01X350591Y7993D02*
X350000Y8583D01*
G01X340266Y12203D02*
X341392Y11076D01*
G01X340238Y12175D02*
X341364Y11049D01*
G01X340210Y12147D02*
X341336Y11021D01*
G01X339833Y10965D02*
X340557Y10241D01*
G01X339722Y11021D02*
X340529Y10213D01*
G01X339375Y11312D02*
X340501Y10186D01*
G01X344804Y4709D02*
X345741Y3772D01*
G01X344749Y4653D02*
X345685Y3717D01*
G01X348819Y39685D02*
X350000Y38898D01*
G01X352953Y55926D02*
X346949Y56341D01*
G01X353052Y55704D02*
X347008Y56122D01*
G01X350000Y28097D02*
X349979D01*
G01X338544Y62480D02*
X337363D01*
G01X353150Y62411D02*
X353937D01*
G01X353150Y62133D02*
X353937D01*
G01Y62115D02*
X353150D01*
G01X353937Y62028D02*
X352953D01*
G01X337363Y62002D02*
X338544D01*
G01X346851Y61850D02*
X346063D01*
G01X353937Y60593D02*
X353150D01*
G01X346063Y59764D02*
X346851D01*
G01X359882Y58682D02*
X352166D01*
G01X353150Y58507D02*
X353937D01*
G01X354134Y57927D02*
X359882D01*
G01X347008Y57894D02*
X346024D01*
G01X346851Y57796D02*
X346063D01*
G01X346851Y57778D02*
X346063D01*
G01Y57500D02*
X346851D01*
G01X346063Y56516D02*
X346851D01*
G01X339528Y56417D02*
X339134D01*
G01X346063Y56239D02*
X346851D01*
G01Y56221D02*
X346063D01*
G01X347008Y56122D02*
X346024D01*
G01X353937Y55926D02*
X352953D01*
G01X352756Y55831D02*
X347244D01*
G01X353937Y55816D02*
X353150D01*
G01X353937Y55798D02*
X353150D01*
G01X352166Y55532D02*
X359882D01*
G01X353150Y55521D02*
X353937D01*
G01X338741Y55379D02*
X339233D01*
G01X346851Y55217D02*
X346063D01*
G01X352756Y55205D02*
X347244D01*
G01X339233Y54846D02*
X338741D01*
G01Y54828D02*
X339922D01*
G01X341201Y54646D02*
X358800D01*
G01X353150Y54537D02*
X353937D01*
G01X340512Y54496D02*
X339725D01*
G01X346063Y54264D02*
X341268D01*
G01X358733D02*
X353937D01*
G01X353150Y54259D02*
X353937D01*
G01Y54241D02*
X353150D01*
G01X339922Y54233D02*
X338741D01*
G01Y54161D02*
X339922D01*
G01X353937Y54154D02*
X352953D01*
G01X339922Y54102D02*
X338741D01*
G01X340512Y53870D02*
X339725D01*
G01X353937Y53638D02*
X358733D01*
G01X341268D02*
X346063D01*
G01X339922Y53418D02*
X338741D01*
G01X339922Y53347D02*
X338741D01*
G01Y52472D02*
X339922D01*
G01X353937Y51969D02*
X361260D01*
G01X346063D02*
X338741D01*
G01X350985Y51595D02*
X341595D01*
G01X358406D02*
X352166D01*
G01X340020Y51496D02*
X359981D01*
G01X339922Y50985D02*
X338741D01*
G01X341595Y49421D02*
X341693D01*
G01X339233D02*
X341201D01*
G01X339922Y48622D02*
X338741D01*
G01X341890Y48347D02*
X343071D01*
G01X342973Y48248D02*
X341595D01*
G01X353544Y48150D02*
X346457D01*
G01X339922Y47953D02*
X338741D01*
G01X340020Y47756D02*
X339233D01*
G01X346457Y47166D02*
X353544D01*
G01X339922Y47135D02*
X338741D01*
G01X351122Y46969D02*
X344036D01*
G01X341201Y46870D02*
X340118D01*
G01X349795Y46654D02*
X345363D01*
G01X339922Y46484D02*
X338741D01*
G01X344725Y46260D02*
X350433D01*
G01X339922D02*
X338741D01*
G01Y46189D02*
X339922D01*
G01X340118Y45886D02*
X342973D01*
G01X339922Y45802D02*
X338741D01*
G01X343071Y45788D02*
X340611D01*
G01X338741Y45505D02*
X339922D01*
G01Y45446D02*
X338741D01*
G01X339922Y45374D02*
X338741D01*
G01X339922Y44292D02*
X339725D01*
G01X338741D02*
X338544D01*
G01X343248Y44016D02*
X340020D01*
G01X359981D02*
X343642D01*
G01X346063Y43898D02*
X361260D01*
G01X338741D02*
X343662D01*
G01Y42323D02*
X343268D01*
G01X347008D02*
X343741D01*
G01X339922Y41654D02*
X338741D01*
G01X339922Y40867D02*
X338741D01*
G01X359981D02*
X340020D01*
G01X346693Y40355D02*
X347008D01*
G01X343268D02*
X346615D01*
G01X358800Y39685D02*
X341201D01*
G01X355867Y39569D02*
X355079D01*
G01X357244Y38898D02*
X350000D01*
G01Y38613D02*
X349804D01*
G01X355867Y38558D02*
X355079D01*
G01X355867Y38513D02*
X355079D01*
G01X355867Y38217D02*
X355079D01*
G01X355867Y38165D02*
X355079D01*
G01X355867Y37717D02*
X355079D01*
G01X350000Y36733D02*
X349804D01*
G01X346615Y34843D02*
X343268D01*
G01X347008D02*
X346693D01*
G01X340020Y34370D02*
X359981D01*
G01X343741Y32874D02*
X347008D01*
G01X343268D02*
X343662D01*
G01X349203Y30906D02*
X351979D01*
G01X347441Y29646D02*
X340807D01*
G01X359193D02*
X354922D01*
G01X349203Y28979D02*
X351979D01*
G01X349203Y28733D02*
X351979D01*
G01X341989Y28465D02*
X346260D01*
G01X338741Y27756D02*
X339922D01*
G01X348239Y27626D02*
X352943D01*
G01X348245Y27328D02*
X352937D01*
G01X339922Y26697D02*
X338741D01*
G01X348049Y26591D02*
X353133D01*
G01X339922Y26453D02*
X338741D01*
G01X347731Y24974D02*
X353451D01*
G01X347929Y24741D02*
X353252D01*
G01X354333Y17382D02*
X354528Y17409D01*
G01X354495Y9761D02*
X352269Y9164D01*
G01X354699Y9000D02*
X352473Y8403D01*
G01X353155Y18674D02*
X352958Y18621D01*
G01X354139D02*
X354336Y18674D01*
G01X340612Y8925D02*
X341644Y8202D01*
G01X339370Y7151D02*
X339434Y7106D01*
G01X339660Y5506D02*
X339724Y5461D01*
G01X337878Y5021D02*
X338845Y4343D01*
G01X338017Y3846D02*
X338339Y3621D01*
G01X346703Y-1574D02*
X347188Y-1911D01*
G01X351754Y27328D02*
X351949Y27224D01*
G01X347924Y24743D02*
X347734Y24803D01*
G01X348027Y18674D02*
X348224Y18621D01*
G01X347042D02*
X346846Y18674D01*
G01X348912Y24780D02*
X349050Y24753D01*
G01D02*
X349120Y24740D01*
G01X346849Y17382D02*
X346654Y17409D01*
G01X355670Y2150D02*
X355808Y2140D01*
G01X348031Y17404D02*
X347836Y17409D01*
G01X350000Y20814D02*
X349804Y20819D01*
G01X346846Y18869D02*
X354336D01*
G01X347045Y18635D02*
X354137D01*
G01X346917Y17857D02*
X346718D01*
G01D02*
X354464D01*
G01X354265D02*
X354464D01*
G01X339922Y12843D02*
X338741D01*
G01X343662Y12796D02*
X343268D01*
G01X347008D02*
X343741D01*
G01X353150Y11170D02*
X351103D01*
G01X351969Y10945D02*
X351181D01*
G01X346693Y10827D02*
X347008D01*
G01X343268D02*
X346615D01*
G01X353937Y9764D02*
X351103D01*
G01X353937Y8780D02*
X351103D01*
G01Y7993D02*
X350591D01*
G01X346615Y5315D02*
X343268D01*
G01X347008D02*
X346693D01*
G01X343741Y3347D02*
X347008D01*
G01X343268D02*
X343662D01*
G01X339922Y2804D02*
X338741D01*
G01X355670Y2150D02*
X350000D01*
G01X291457Y0D02*
X921260D01*
G01X351221Y-78D02*
X353465D01*
G01X339922Y-196D02*
X338741D01*
G01X348546Y-1181D02*
X351455D01*
G01X355881Y-1259D02*
X351364D01*
G01X339922Y-1574D02*
X360079D01*
G01X351644Y-1771D02*
X348357D01*
G01X361260Y-2165D02*
X338741D01*
G01X353151Y17404D02*
X353346Y17409D01*
G01X351302Y1871D02*
X351890Y1891D01*
G01Y1619D02*
X351312Y1599D01*
G01X352002Y444D02*
X351890Y440D01*
G01X351947Y325D02*
X351672Y315D01*
G01X348164Y68215D02*
X348145Y68377D01*
G01X348219Y68062D02*
X348164Y68215D01*
G01X348309Y67921D02*
X348219Y68062D01*
G01X348429Y67797D02*
X348309Y67921D01*
G01X348577Y67693D02*
X348429Y67797D01*
G01X348744Y67618D02*
X348577Y67693D01*
G01X348925Y67572D02*
X348744Y67618D01*
G01X349113Y67556D02*
X348925Y67572D01*
G01X348998Y68554D02*
X348995Y68574D01*
G01X349004Y68535D02*
X348998Y68554D01*
G01X349015Y68518D02*
X349004Y68535D01*
G01X349030Y68503D02*
X349015Y68518D01*
G01X349048Y68490D02*
X349030Y68503D01*
G01X349068Y68481D02*
X349048Y68490D01*
G01X349090Y68475D02*
X349068Y68481D01*
G01X349113Y68473D02*
X349090Y68475D01*
G01X351119Y69675D02*
X351121Y69655D01*
G01X351112Y69694D02*
X351119Y69675D01*
G01X351101Y69711D02*
X351112Y69694D01*
G01X351087Y69726D02*
X351101Y69711D01*
G01X351069Y69739D02*
X351087Y69726D01*
G01X351048Y69748D02*
X351069Y69739D01*
G01X351026Y69754D02*
X351048Y69748D01*
G01X351003Y69756D02*
X351026Y69754D01*
G01X351953Y70222D02*
X351972Y70060D01*
G01X351897Y70376D02*
X351953Y70222D01*
G01X351808Y70517D02*
X351897Y70376D01*
G01X351688Y70641D02*
X351808Y70517D01*
G01X351539Y70744D02*
X351688Y70641D01*
G01X351372Y70820D02*
X351539Y70744D01*
G01X351191Y70866D02*
X351372Y70820D01*
G01X351003Y70881D02*
X351191Y70866D01*
G01X340363Y63340D02*
X340450Y63188D01*
G01X340241Y63473D02*
X340363Y63340D01*
G01X340090Y63583D02*
X340241Y63473D01*
G01X339916Y63665D02*
X340090Y63583D01*
G01X339726Y63715D02*
X339916Y63665D01*
G01X339528Y63732D02*
X339726Y63715D01*
G01X339727Y63089D02*
X339528Y63106D01*
G01X350334Y68111D02*
X350354Y68273D01*
G01X350279Y67957D02*
X350334Y68111D01*
G01X350190Y67816D02*
X350279Y67957D01*
G01X350070Y67692D02*
X350190Y67816D01*
G01X349921Y67589D02*
X350070Y67692D01*
G01X349754Y67514D02*
X349921Y67589D01*
G01X349573Y67467D02*
X349754Y67514D01*
G01X349385Y67452D02*
X349573Y67467D01*
G01X349761Y68658D02*
X349763Y68678D01*
G01X349754Y68639D02*
X349761Y68658D01*
G01X349743Y68622D02*
X349754Y68639D01*
G01X349728Y68607D02*
X349743Y68622D01*
G01X349710Y68594D02*
X349728Y68607D01*
G01X349690Y68585D02*
X349710Y68594D01*
G01X349668Y68580D02*
X349690Y68585D01*
G01X349645Y68578D02*
X349668Y68580D01*
G01X350356Y69779D02*
X350354Y69760D01*
G01X350363Y69798D02*
X350356Y69779D01*
G01X350374Y69815D02*
X350363Y69798D01*
G01X350388Y69830D02*
X350374Y69815D01*
G01X350406Y69843D02*
X350388Y69830D01*
G01X350427Y69852D02*
X350406Y69843D01*
G01X350449Y69858D02*
X350427Y69852D01*
G01X350472Y69860D02*
X350449Y69858D01*
G01X349782Y70118D02*
X349763Y69956D01*
G01X349837Y70271D02*
X349782Y70118D01*
G01X349927Y70413D02*
X349837Y70271D01*
G01X350047Y70537D02*
X349927Y70413D01*
G01X350196Y70640D02*
X350047Y70537D01*
G01X350362Y70715D02*
X350196Y70640D01*
G01X350543Y70762D02*
X350362Y70715D01*
G01X350732Y70777D02*
X350543Y70762D01*
G01X350356Y73966D02*
X350354Y73946D01*
G01X350363Y73985D02*
X350356Y73966D01*
G01X350374Y74002D02*
X350363Y73985D01*
G01X350388Y74017D02*
X350374Y74002D01*
G01X350406Y74030D02*
X350388Y74017D01*
G01X350427Y74039D02*
X350406Y74030D01*
G01X350449Y74045D02*
X350427Y74039D01*
G01X350472Y74047D02*
X350449Y74045D01*
G01X348998Y73966D02*
X348995Y73946D01*
G01X349004Y73985D02*
X348998Y73966D01*
G01X349015Y74002D02*
X349004Y73985D01*
G01X349030Y74017D02*
X349015Y74002D01*
G01X349048Y74030D02*
X349030Y74017D01*
G01X349068Y74039D02*
X349048Y74030D01*
G01X349090Y74045D02*
X349068Y74039D01*
G01X349113Y74047D02*
X349090Y74045D01*
G01X348164Y74305D02*
X348145Y74143D01*
G01X348219Y74458D02*
X348164Y74305D01*
G01X348309Y74600D02*
X348219Y74458D01*
G01X348429Y74723D02*
X348309Y74600D01*
G01X348577Y74827D02*
X348429Y74723D01*
G01X348744Y74902D02*
X348577Y74827D01*
G01X348925Y74948D02*
X348744Y74902D01*
G01X349113Y74964D02*
X348925Y74948D01*
G01X351119Y78164D02*
X351121Y78183D01*
G01X351112Y78145D02*
X351119Y78164D01*
G01X351101Y78128D02*
X351112Y78145D01*
G01X351087Y78113D02*
X351101Y78128D01*
G01X351069Y78100D02*
X351087Y78113D01*
G01X351048Y78091D02*
X351069Y78100D01*
G01X351026Y78085D02*
X351048Y78091D01*
G01X351003Y78083D02*
X351026Y78085D01*
G01X351953Y80631D02*
X351972Y80793D01*
G01X351897Y80478D02*
X351953Y80631D01*
G01X351808Y80337D02*
X351897Y80478D01*
G01X351688Y80213D02*
X351808Y80337D01*
G01X351539Y80109D02*
X351688Y80213D01*
G01X351372Y80034D02*
X351539Y80109D01*
G01X351191Y79988D02*
X351372Y80034D01*
G01X351003Y79972D02*
X351191Y79988D01*
G01X350765Y81178D02*
X350767Y81198D01*
G01X350758Y81160D02*
X350765Y81178D01*
G01X350747Y81143D02*
X350758Y81160D01*
G01X350732Y81127D02*
X350747Y81143D01*
G01X350714Y81115D02*
X350732Y81127D01*
G01X350694Y81106D02*
X350714Y81115D01*
G01X350672Y81100D02*
X350694Y81106D01*
G01X350649Y81098D02*
X350672Y81100D01*
G01X349352Y82340D02*
X349350Y82320D01*
G01X349359Y82359D02*
X349352Y82340D01*
G01X349370Y82376D02*
X349359Y82359D01*
G01X349384Y82391D02*
X349370Y82376D01*
G01X349402Y82404D02*
X349384Y82391D01*
G01X349423Y82413D02*
X349402Y82404D01*
G01X349445Y82418D02*
X349423Y82413D01*
G01X349468Y82420D02*
X349445Y82418D01*
G01X348164Y82679D02*
X348145Y82516D01*
G01X348219Y82832D02*
X348164Y82679D01*
G01X348309Y82973D02*
X348219Y82832D01*
G01X348429Y83097D02*
X348309Y82973D01*
G01X348577Y83200D02*
X348429Y83097D01*
G01X348744Y83276D02*
X348577Y83200D01*
G01X348925Y83322D02*
X348744Y83276D01*
G01X349113Y83338D02*
X348925Y83322D01*
G01X348154Y87163D02*
X348145Y87084D01*
G01X348181Y87238D02*
X348154Y87163D01*
G01X348225Y87307D02*
X348181Y87238D01*
G01X348283Y87367D02*
X348225Y87307D01*
G01X348356Y87417D02*
X348283Y87367D01*
G01X348437Y87454D02*
X348356Y87417D01*
G01X348526Y87477D02*
X348437Y87454D01*
G01X348617Y87484D02*
X348526Y87477D01*
G01X337662Y63316D02*
X337499Y63154D01*
G01X337881Y63457D02*
X337662Y63316D01*
G01X338154Y63575D02*
X337881Y63457D01*
G01X338459Y63661D02*
X338154Y63575D01*
G01X338790Y63714D02*
X338459Y63661D01*
G01X339134Y63732D02*
X338790Y63714D01*
G01X348650Y87588D02*
X348659Y87587D01*
G01X348644Y87588D02*
X348650D01*
G01X348637D02*
X348644D01*
G01X348631Y87589D02*
X348637Y87588D01*
G01X348624Y87589D02*
X348631D01*
G01X348617D02*
X348624D01*
G01X348626Y87484D02*
X348617D01*
G01X348632D02*
X348626D01*
G01X348639D02*
X348632D01*
G01X348645D02*
X348639D01*
G01X348652Y87483D02*
X348645Y87484D01*
G01X348659Y87483D02*
X348652D01*
G01X349761Y73862D02*
X349763Y73842D01*
G01X349754Y73881D02*
X349761Y73862D01*
G01X349743Y73898D02*
X349754Y73881D01*
G01X349728Y73913D02*
X349743Y73898D01*
G01X349710Y73926D02*
X349728Y73913D01*
G01X349690Y73935D02*
X349710Y73926D01*
G01X349668Y73940D02*
X349690Y73935D01*
G01X349645Y73942D02*
X349668Y73940D01*
G01X351119Y73862D02*
X351121Y73842D01*
G01X351112Y73881D02*
X351119Y73862D01*
G01X351101Y73898D02*
X351112Y73881D01*
G01X351087Y73913D02*
X351101Y73898D01*
G01X351069Y73926D02*
X351087Y73913D01*
G01X351048Y73935D02*
X351069Y73926D01*
G01X351026Y73940D02*
X351048Y73935D01*
G01X351003Y73942D02*
X351026Y73940D01*
G01X351953Y74409D02*
X351972Y74247D01*
G01X351897Y74563D02*
X351953Y74409D01*
G01X351808Y74704D02*
X351897Y74563D01*
G01X351688Y74828D02*
X351808Y74704D01*
G01X351539Y74931D02*
X351688Y74828D01*
G01X351372Y75006D02*
X351539Y74931D01*
G01X351191Y75053D02*
X351372Y75006D01*
G01X351003Y75068D02*
X351191Y75053D01*
G01X351119Y76877D02*
X351121Y76857D01*
G01X351112Y76896D02*
X351119Y76877D01*
G01X351101Y76913D02*
X351112Y76896D01*
G01X351087Y76928D02*
X351101Y76913D01*
G01X351069Y76941D02*
X351087Y76928D01*
G01X351048Y76950D02*
X351069Y76941D01*
G01X351026Y76955D02*
X351048Y76950D01*
G01X351003Y76957D02*
X351026Y76955D01*
G01X348164Y80735D02*
X348145Y80898D01*
G01X348219Y80582D02*
X348164Y80735D01*
G01X348309Y80441D02*
X348219Y80582D01*
G01X348429Y80317D02*
X348309Y80441D01*
G01X348577Y80214D02*
X348429Y80317D01*
G01X348744Y80138D02*
X348577Y80214D01*
G01X348925Y80092D02*
X348744Y80138D01*
G01X349113Y80076D02*
X348925Y80092D01*
G01X349352Y81074D02*
X349350Y81094D01*
G01X349359Y81055D02*
X349352Y81074D01*
G01X349370Y81038D02*
X349359Y81055D01*
G01X349384Y81023D02*
X349370Y81038D01*
G01X349402Y81011D02*
X349384Y81023D01*
G01X349423Y81001D02*
X349402Y81011D01*
G01X349445Y80996D02*
X349423Y81001D01*
G01X349468Y80994D02*
X349445Y80996D01*
G01X350765Y82236D02*
X350767Y82216D01*
G01X350758Y82254D02*
X350765Y82236D01*
G01X350747Y82272D02*
X350758Y82254D01*
G01X350732Y82287D02*
X350747Y82272D01*
G01X350714Y82299D02*
X350732Y82287D01*
G01X350694Y82308D02*
X350714Y82299D01*
G01X350672Y82314D02*
X350694Y82308D01*
G01X350649Y82316D02*
X350672Y82314D01*
G01X351953Y82783D02*
X351972Y82621D01*
G01X351897Y82936D02*
X351953Y82783D01*
G01X351808Y83078D02*
X351897Y82936D01*
G01X351688Y83201D02*
X351808Y83078D01*
G01X351539Y83305D02*
X351688Y83201D01*
G01X351372Y83380D02*
X351539Y83305D01*
G01X351191Y83426D02*
X351372Y83380D01*
G01X351003Y83442D02*
X351191Y83426D01*
G01X345541Y97498D02*
X345670Y97576D01*
G01X345433Y97398D02*
X345541Y97498D01*
G01X345351Y97283D02*
X345433Y97398D01*
G01X345299Y97157D02*
X345351Y97283D01*
G01X345277Y97024D02*
X345299Y97157D01*
G01X345287Y96889D02*
X345277Y97024D01*
G01X345327Y96761D02*
X345287Y96889D01*
G01X345399Y96640D02*
X345327Y96761D01*
G01X345497Y96534D02*
X345399Y96640D01*
G01X345616Y96449D02*
X345497Y96534D01*
G01X345756Y96384D02*
X345616Y96449D01*
G01X345908Y96344D02*
X345756Y96384D01*
G01X346063Y96330D02*
X345908Y96344D01*
G01X341538Y97262D02*
X341404Y97110D01*
G01X341635Y97401D02*
X341538Y97262D01*
G01X341702Y97527D02*
X341635Y97401D01*
G01X341741Y97643D02*
X341702Y97527D01*
G01X341755Y97747D02*
X341741Y97643D01*
G01X341744Y97839D02*
X341755Y97747D01*
G01X341706Y97918D02*
X341744Y97839D01*
G01X341639Y97979D02*
X341706Y97918D01*
G01X341540Y98020D02*
X341639Y97979D01*
G01X341404Y98036D02*
X341540Y98020D01*
G01X341631Y98189D02*
X341404Y97736D01*
G01X341743Y98600D02*
X341631Y98189D01*
G01X341738Y98931D02*
X341743Y98600D01*
G01X341625Y99140D02*
X341738Y98931D01*
G01X341404Y99217D02*
X341625Y99140D01*
G01X354143Y97079D02*
X354111Y97110D01*
G01X354178Y97049D02*
X354143Y97079D01*
G01X354214Y97020D02*
X354178Y97049D01*
G01X354251Y96996D02*
X354214Y97020D01*
G01X354291Y96971D02*
X354251Y96996D01*
G01X354331Y96951D02*
X354291Y96971D01*
G01X354096Y96344D02*
X353937Y96330D01*
G01X354248Y96384D02*
X354096Y96344D01*
G01X354387Y96450D02*
X354248Y96384D01*
G01X354506Y96536D02*
X354387Y96450D01*
G01X354604Y96642D02*
X354506Y96536D01*
G01X354674Y96763D02*
X354604Y96642D01*
G01X354715Y96891D02*
X354674Y96763D01*
G01X354724Y97026D02*
X354715Y96891D01*
G01X354701Y97160D02*
X354724Y97026D01*
G01X354649Y97285D02*
X354701Y97160D01*
G01X354566Y97400D02*
X354649Y97285D01*
G01X354458Y97499D02*
X354566Y97400D01*
G01X354331Y97576D02*
X354458Y97499D01*
G01X354289Y97598D02*
X354331Y97576D01*
G01X354249Y97623D02*
X354289Y97598D01*
G01X354211Y97649D02*
X354249Y97623D01*
G01X354176Y97676D02*
X354211Y97649D01*
G01X354142Y97706D02*
X354176Y97676D01*
G01X354111Y97736D02*
X354142Y97706D01*
G01X338192Y63075D02*
X338150Y63482D01*
G01X349011Y86478D02*
X348995Y86427D01*
G01X349054Y86514D02*
X349011Y86478D01*
G01X349115Y86528D02*
X349054Y86514D01*
G01X354460Y96872D02*
X354331Y96951D01*
G01X354568Y96772D02*
X354460Y96872D01*
G01X354650Y96657D02*
X354568Y96772D01*
G01X354702Y96532D02*
X354650Y96657D01*
G01X354724Y96398D02*
X354702Y96532D01*
G01X354714Y96263D02*
X354724Y96398D01*
G01X354673Y96135D02*
X354714Y96263D01*
G01X354602Y96015D02*
X354673Y96135D01*
G01X354504Y95908D02*
X354602Y96015D01*
G01X354384Y95823D02*
X354504Y95908D01*
G01X354245Y95758D02*
X354384Y95823D01*
G01X354093Y95718D02*
X354245Y95758D01*
G01X353937Y95705D02*
X354093Y95718D01*
G01X341203Y96941D02*
X341404Y97110D01*
G01X340976Y96799D02*
X341203Y96941D01*
G01X340735Y96688D02*
X340976Y96799D01*
G01X340471Y96606D02*
X340735Y96688D01*
G01X340196Y96555D02*
X340471Y96606D01*
G01X339922Y96539D02*
X340196Y96555D01*
G01X338555Y96288D02*
X338544Y96226D01*
G01X338589Y96347D02*
X338555Y96288D01*
G01X338643Y96400D02*
X338589Y96347D01*
G01X338717Y96448D02*
X338643Y96400D01*
G01X338807Y96487D02*
X338717Y96448D01*
G01X338909Y96516D02*
X338807Y96487D01*
G01X339020Y96533D02*
X338909Y96516D01*
G01X339134Y96539D02*
X339020Y96533D01*
G01X353969Y97359D02*
X353937Y97411D01*
G01X353997Y97313D02*
X353969Y97359D01*
G01X354025Y97266D02*
X353997Y97313D01*
G01X354056Y97211D02*
X354025Y97266D01*
G01X354084Y97161D02*
X354056Y97211D01*
G01X354111Y97110D02*
X354084Y97161D01*
G01X354082Y97823D02*
X354111Y97736D01*
G01X354052Y97908D02*
X354082Y97823D01*
G01X354023Y97991D02*
X354052Y97908D01*
G01X353993Y98071D02*
X354023Y97991D01*
G01X353964Y98149D02*
X353993Y98071D01*
G01X353937Y98217D02*
X353964Y98149D01*
G01X338960Y96913D02*
X338741Y97112D01*
G01X339092Y96639D02*
X338960Y96913D01*
G01X339134Y96319D02*
X339092Y96639D01*
G01X348922Y67468D02*
X349113Y67452D01*
G01X348741Y67515D02*
X348922Y67468D01*
G01X348575Y67591D02*
X348741Y67515D01*
G01X348429Y67692D02*
X348575Y67591D01*
G01X348307Y67819D02*
X348429Y67692D01*
G01X348218Y67960D02*
X348307Y67819D01*
G01X348163Y68114D02*
X348218Y67960D01*
G01X348145Y68273D02*
X348163Y68114D01*
G01X349090Y68580D02*
X349113Y68578D01*
G01X349068Y68585D02*
X349090Y68580D01*
G01X349048Y68595D02*
X349068Y68585D01*
G01X349030Y68607D02*
X349048Y68595D01*
G01X349015Y68622D02*
X349030Y68607D01*
G01X349004Y68640D02*
X349015Y68622D01*
G01X348998Y68658D02*
X349004Y68640D01*
G01X348995Y68678D02*
X348998Y68658D01*
G01X348922Y79988D02*
X349113Y79972D01*
G01X348741Y80035D02*
X348922Y79988D01*
G01X348575Y80111D02*
X348741Y80035D01*
G01X348429Y80213D02*
X348575Y80111D01*
G01X348307Y80339D02*
X348429Y80213D01*
G01X348218Y80481D02*
X348307Y80339D01*
G01X348163Y80634D02*
X348218Y80481D01*
G01X348145Y80793D02*
X348163Y80634D01*
G01X349668Y74045D02*
X349645Y74047D01*
G01X349690Y74039D02*
X349668Y74045D01*
G01X349711Y74030D02*
X349690Y74039D01*
G01X349728Y74017D02*
X349711Y74030D01*
G01X349743Y74002D02*
X349728Y74017D01*
G01X349754Y73985D02*
X349743Y74002D01*
G01X349761Y73966D02*
X349754Y73985D01*
G01X349763Y73946D02*
X349761Y73966D01*
G01X349444Y81100D02*
X349468Y81098D01*
G01X349422Y81106D02*
X349444Y81100D01*
G01X349402Y81115D02*
X349422Y81106D01*
G01X349384Y81127D02*
X349402Y81115D01*
G01X349369Y81143D02*
X349384Y81127D01*
G01X349359Y81160D02*
X349369Y81143D01*
G01X349352Y81179D02*
X349359Y81160D01*
G01X349350Y81198D02*
X349352Y81179D01*
G01X351027Y69858D02*
X351003Y69860D01*
G01X351049Y69852D02*
X351027Y69858D01*
G01X351069Y69843D02*
X351049Y69852D01*
G01X351087Y69830D02*
X351069Y69843D01*
G01X351102Y69815D02*
X351087Y69830D01*
G01X351112Y69798D02*
X351102Y69815D01*
G01X351119Y69779D02*
X351112Y69798D01*
G01X351121Y69760D02*
X351119Y69779D01*
G01X351027Y74045D02*
X351003Y74047D01*
G01X351049Y74039D02*
X351027Y74045D01*
G01X351069Y74030D02*
X351049Y74039D01*
G01X351087Y74017D02*
X351069Y74030D01*
G01X351102Y74002D02*
X351087Y74017D01*
G01X351112Y73985D02*
X351102Y74002D01*
G01X351119Y73966D02*
X351112Y73985D01*
G01X351121Y73946D02*
X351119Y73966D01*
G01X351027Y77060D02*
X351003Y77062D01*
G01X351049Y77054D02*
X351027Y77060D01*
G01X351069Y77045D02*
X351049Y77054D01*
G01X351087Y77032D02*
X351069Y77045D01*
G01X351102Y77017D02*
X351087Y77032D01*
G01X351112Y77000D02*
X351102Y77017D01*
G01X351119Y76981D02*
X351112Y77000D01*
G01X351121Y76961D02*
X351119Y76981D01*
G01X351195Y70761D02*
X351003Y70777D01*
G01X351375Y70714D02*
X351195Y70761D01*
G01X351542Y70638D02*
X351375Y70714D01*
G01X351688Y70537D02*
X351542Y70638D01*
G01X351810Y70410D02*
X351688Y70537D01*
G01X351899Y70269D02*
X351810Y70410D01*
G01X351953Y70115D02*
X351899Y70269D01*
G01X351972Y69956D02*
X351953Y70115D01*
G01X350672Y82418D02*
X350649Y82420D01*
G01X350694Y82413D02*
X350672Y82418D01*
G01X350715Y82403D02*
X350694Y82413D01*
G01X350732Y82391D02*
X350715Y82403D01*
G01X350747Y82376D02*
X350732Y82391D01*
G01X350758Y82358D02*
X350747Y82376D01*
G01X350765Y82340D02*
X350758Y82358D01*
G01X350767Y82320D02*
X350765Y82340D01*
G01X351195Y74948D02*
X351003Y74964D01*
G01X351375Y74901D02*
X351195Y74948D01*
G01X351542Y74825D02*
X351375Y74901D01*
G01X351688Y74723D02*
X351542Y74825D01*
G01X351810Y74597D02*
X351688Y74723D01*
G01X351899Y74456D02*
X351810Y74597D01*
G01X351953Y74302D02*
X351899Y74456D01*
G01X351972Y74143D02*
X351953Y74302D01*
G01X351195Y83321D02*
X351003Y83338D01*
G01X351375Y83275D02*
X351195Y83321D01*
G01X351542Y83199D02*
X351375Y83275D01*
G01X351688Y83097D02*
X351542Y83199D01*
G01X351810Y82971D02*
X351688Y83097D01*
G01X351899Y82829D02*
X351810Y82971D01*
G01X351953Y82676D02*
X351899Y82829D01*
G01X351972Y82516D02*
X351953Y82676D01*
G01X338323Y92535D02*
X338544Y93075D01*
G01X338192Y92027D02*
X338323Y92535D01*
G01X338150Y91573D02*
X338192Y92027D01*
G01X348524Y87581D02*
X348617Y87589D01*
G01X348436Y87558D02*
X348524Y87581D01*
G01X348355Y87521D02*
X348436Y87558D01*
G01X348283Y87471D02*
X348355Y87521D01*
G01X348224Y87410D02*
X348283Y87471D01*
G01X348181Y87341D02*
X348224Y87410D01*
G01X348154Y87266D02*
X348181Y87341D01*
G01X348145Y87188D02*
X348154Y87266D01*
G01X348922Y83426D02*
X349113Y83442D01*
G01X348741Y83379D02*
X348922Y83426D01*
G01X348575Y83303D02*
X348741Y83379D01*
G01X348429Y83201D02*
X348575Y83303D01*
G01X348307Y83075D02*
X348429Y83201D01*
G01X348218Y82934D02*
X348307Y83075D01*
G01X348163Y82780D02*
X348218Y82934D01*
G01X348145Y82621D02*
X348163Y82780D01*
G01X348922Y75052D02*
X349113Y75068D01*
G01X348741Y75005D02*
X348922Y75052D01*
G01X348575Y74929D02*
X348741Y75005D01*
G01X348429Y74828D02*
X348575Y74929D01*
G01X348307Y74701D02*
X348429Y74828D01*
G01X348218Y74560D02*
X348307Y74701D01*
G01X348163Y74407D02*
X348218Y74560D01*
G01X348145Y74247D02*
X348163Y74407D01*
G01X349444Y82314D02*
X349468Y82316D01*
G01X349422Y82308D02*
X349444Y82314D01*
G01X349402Y82299D02*
X349422Y82308D01*
G01X349384Y82287D02*
X349402Y82299D01*
G01X349369Y82271D02*
X349384Y82287D01*
G01X349359Y82254D02*
X349369Y82271D01*
G01X349352Y82235D02*
X349359Y82254D01*
G01X349350Y82216D02*
X349352Y82235D01*
G01X349090Y73940D02*
X349113Y73942D01*
G01X349068Y73935D02*
X349090Y73940D01*
G01X349048Y73925D02*
X349068Y73935D01*
G01X349030Y73913D02*
X349048Y73925D01*
G01X349015Y73898D02*
X349030Y73913D01*
G01X349004Y73880D02*
X349015Y73898D01*
G01X348998Y73862D02*
X349004Y73880D01*
G01X348995Y73842D02*
X348998Y73862D01*
G01X350672Y80996D02*
X350649Y80994D01*
G01X350694Y81002D02*
X350672Y80996D01*
G01X350715Y81011D02*
X350694Y81002D01*
G01X350732Y81023D02*
X350715Y81011D01*
G01X350747Y81039D02*
X350732Y81023D01*
G01X350758Y81056D02*
X350747Y81039D01*
G01X350765Y81075D02*
X350758Y81056D01*
G01X350767Y81094D02*
X350765Y81075D01*
G01X350540Y70865D02*
X350732Y70881D01*
G01X350359Y70818D02*
X350540Y70865D01*
G01X350193Y70743D02*
X350359Y70818D01*
G01X350047Y70641D02*
X350193Y70743D01*
G01X349925Y70515D02*
X350047Y70641D01*
G01X349836Y70373D02*
X349925Y70515D01*
G01X349781Y70220D02*
X349836Y70373D01*
G01X349763Y70060D02*
X349781Y70220D01*
G01X350448Y73940D02*
X350472Y73942D01*
G01X350426Y73935D02*
X350448Y73940D01*
G01X350406Y73925D02*
X350426Y73935D01*
G01X350388Y73913D02*
X350406Y73925D01*
G01X350373Y73898D02*
X350388Y73913D01*
G01X350362Y73880D02*
X350373Y73898D01*
G01X350356Y73862D02*
X350362Y73880D01*
G01X350354Y73842D02*
X350356Y73862D01*
G01X349668Y68475D02*
X349645Y68473D01*
G01X349690Y68481D02*
X349668Y68475D01*
G01X349711Y68490D02*
X349690Y68481D01*
G01X349728Y68503D02*
X349711Y68490D01*
G01X349743Y68518D02*
X349728Y68503D01*
G01X349754Y68535D02*
X349743Y68518D01*
G01X349761Y68554D02*
X349754Y68535D01*
G01X349763Y68574D02*
X349761Y68554D01*
G01X351027Y77981D02*
X351003Y77979D01*
G01X351049Y77987D02*
X351027Y77981D01*
G01X351069Y77996D02*
X351049Y77987D01*
G01X351087Y78008D02*
X351069Y77996D01*
G01X351102Y78024D02*
X351087Y78008D01*
G01X351112Y78041D02*
X351102Y78024D01*
G01X351119Y78060D02*
X351112Y78041D01*
G01X351121Y78079D02*
X351119Y78060D01*
G01X350448Y69754D02*
X350472Y69756D01*
G01X350426Y69748D02*
X350448Y69754D01*
G01X350406Y69739D02*
X350426Y69748D01*
G01X350388Y69726D02*
X350406Y69739D01*
G01X350373Y69711D02*
X350388Y69726D01*
G01X350362Y69694D02*
X350373Y69711D01*
G01X350356Y69675D02*
X350362Y69694D01*
G01X350354Y69655D02*
X350356Y69675D01*
G01X349577Y67572D02*
X349385Y67556D01*
G01X349757Y67619D02*
X349577Y67572D01*
G01X349924Y67695D02*
X349757Y67619D01*
G01X350070Y67797D02*
X349924Y67695D01*
G01X350192Y67923D02*
X350070Y67797D01*
G01X350280Y68064D02*
X350192Y67923D01*
G01X350335Y68218D02*
X350280Y68064D01*
G01X350354Y68377D02*
X350335Y68218D01*
G01X351195Y80093D02*
X351003Y80076D01*
G01X351375Y80140D02*
X351195Y80093D01*
G01X351542Y80215D02*
X351375Y80140D01*
G01X351688Y80317D02*
X351542Y80215D01*
G01X351810Y80443D02*
X351688Y80317D01*
G01X351899Y80585D02*
X351810Y80443D01*
G01X351953Y80738D02*
X351899Y80585D01*
G01X351972Y80898D02*
X351953Y80738D01*
G01X338784Y97147D02*
X339134Y97165D01*
G01X338453Y97093D02*
X338784Y97147D01*
G01X338149Y97006D02*
X338453Y97093D01*
G01X337881Y96890D02*
X338149Y97006D01*
G01X337659Y96746D02*
X337881Y96890D01*
G01X337496Y96584D02*
X337659Y96746D01*
G01X337396Y96409D02*
X337496Y96584D01*
G01X337363Y96226D02*
X337396Y96409D01*
G01X339017Y63100D02*
X339134Y63106D01*
G01X338907Y63082D02*
X339017Y63100D01*
G01X338806Y63053D02*
X338907Y63082D01*
G01X349054Y86410D02*
X349115Y86423D01*
G01X349011Y86373D02*
X349054Y86410D01*
G01X348995Y86323D02*
X349011Y86373D01*
G01X346034Y98140D02*
X346063Y98217D01*
G01X346004Y98061D02*
X346034Y98140D01*
G01X345975Y97981D02*
X346004Y98061D01*
G01X345945Y97898D02*
X345975Y97981D01*
G01X345916Y97813D02*
X345945Y97898D01*
G01X345889Y97736D02*
X345916Y97813D01*
G01X345921Y97169D02*
X345889Y97110D01*
G01X345949Y97218D02*
X345921Y97169D01*
G01X345977Y97267D02*
X345949Y97218D01*
G01X346008Y97320D02*
X345977Y97267D01*
G01X346036Y97366D02*
X346008Y97320D01*
G01X346063Y97411D02*
X346036Y97366D01*
G01X345711Y96973D02*
X345670Y96951D01*
G01X345752Y96997D02*
X345711Y96973D01*
G01X345790Y97023D02*
X345752Y96997D01*
G01X345825Y97050D02*
X345790Y97023D01*
G01X345859Y97080D02*
X345825Y97050D01*
G01X345889Y97110D02*
X345859Y97080D01*
G01X339568Y96633D02*
X339528Y96319D01*
G01X339699Y96909D02*
X339568Y96633D01*
G01X339922Y97112D02*
X339699Y96909D01*
G01X340204Y97182D02*
X339922Y97165D01*
G01X340479Y97233D02*
X340204Y97182D01*
G01X340736Y97315D02*
X340479Y97233D01*
G01X340984Y97429D02*
X340736Y97315D01*
G01X341209Y97572D02*
X340984Y97429D01*
G01X341404Y97736D02*
X341209Y97572D01*
G01X345905Y95718D02*
X346063Y95705D01*
G01X345753Y95759D02*
X345905Y95718D01*
G01X345614Y95824D02*
X345753Y95759D01*
G01X345495Y95910D02*
X345614Y95824D01*
G01X345397Y96016D02*
X345495Y95910D01*
G01X345326Y96137D02*
X345397Y96016D01*
G01X345286Y96266D02*
X345326Y96137D01*
G01X345277Y96400D02*
X345286Y96266D01*
G01X345299Y96534D02*
X345277Y96400D01*
G01X345352Y96659D02*
X345299Y96534D01*
G01X345435Y96774D02*
X345352Y96659D01*
G01X345543Y96873D02*
X345435Y96774D01*
G01X345670Y96951D02*
X345543Y96873D01*
G01X345857Y97705D02*
X345889Y97736D01*
G01X345823Y97674D02*
X345857Y97705D01*
G01X345786Y97646D02*
X345823Y97674D01*
G01X345750Y97621D02*
X345786Y97646D01*
G01X345709Y97597D02*
X345750Y97621D01*
G01X345670Y97576D02*
X345709Y97597D01*
G01X339134Y98036D02*
G03X338544Y97445I0J-590D01*
G01X338740Y82206D02*
G03X338544Y81496I1182J-708D01*
G01X339134Y99217D02*
G03X337363Y97445I0J-1771D01*
G01X338628Y88306D02*
G03X338347Y86844I3656J-1461D01*
G01X337532Y88745D02*
G03X337166Y86844I4752J-1901D01*
G01X352953Y77776D02*
X346949Y75361D01*
G01X353052Y78041D02*
X347008Y75611D01*
G01X352953Y69902D02*
X346949Y67482D01*
G01X353052Y70172D02*
X347008Y67737D01*
G01X338544Y80751D02*
X337953Y79728D01*
G01X340709Y88742D02*
X340125Y87618D01*
G01X339233Y89817D02*
X338628Y88306D01*
G01X337532Y88745D02*
X338741Y91767D01*
G01X340125Y87618D02*
X340709Y89868D01*
G01X354725Y96372D02*
Y96998D01*
G01X354331Y97576D02*
Y96951D01*
G01X354134Y85421D02*
Y81174D01*
G01X354111Y97110D02*
Y97736D01*
G01X353937Y95705D02*
Y96330D01*
G01Y87422D02*
Y85650D01*
G01Y99217D02*
Y97411D01*
G01X353150Y98036D02*
Y99217D01*
G01Y87312D02*
Y85737D01*
G01X353052Y85849D02*
Y87045D01*
G01Y78041D02*
Y79194D01*
G01Y70172D02*
Y71381D01*
G01X352756Y99217D02*
Y98036D01*
G01X352559Y85421D02*
Y75668D01*
G01X352166Y75921D02*
Y90178D01*
G01X351972Y70060D02*
Y67452D01*
G01Y74247D02*
Y71599D01*
G01Y79255D02*
Y75785D01*
G01Y82621D02*
Y80793D01*
G01Y87341D02*
Y86211D01*
G01X351121Y69760D02*
Y67452D01*
G01Y73946D02*
Y71599D01*
G01Y76961D02*
Y75785D01*
G01Y79255D02*
Y78079D01*
G01X351003Y79972D02*
Y80076D01*
G01Y76957D02*
Y77062D01*
G01Y73942D02*
Y74047D01*
G01Y69756D02*
Y69860D01*
G01Y70881D02*
Y70777D01*
G01Y75068D02*
Y74964D01*
G01Y78083D02*
Y77979D01*
G01Y83442D02*
Y83338D01*
G01X350767Y82320D02*
Y81094D01*
G01X350732Y70777D02*
Y70881D01*
G01X350649Y82316D02*
Y82420D01*
G01Y81098D02*
Y80994D01*
G01X350472Y69860D02*
Y69756D01*
G01Y74047D02*
Y73942D01*
G01X350354Y69760D02*
Y68273D01*
G01Y73946D02*
Y71999D01*
G01X350197Y97067D02*
Y90178D01*
G01X349804Y97067D02*
Y90178D01*
G01X349763Y70060D02*
Y68574D01*
G01Y73946D02*
Y71999D01*
G01X349645Y73942D02*
Y74047D01*
G01Y68578D02*
Y68473D01*
G01X349468Y80994D02*
Y81098D01*
G01Y82420D02*
Y82316D01*
G01X349385Y67452D02*
Y67556D01*
G01X349350Y82320D02*
Y81094D01*
G01X349124Y86527D02*
Y86423D01*
G01X349113Y83338D02*
Y83442D01*
G01Y74964D02*
Y75068D01*
G01Y68473D02*
Y68578D01*
G01Y67556D02*
Y67452D01*
G01Y74047D02*
Y73942D01*
G01Y80076D02*
Y79972D01*
G01X348995Y70881D02*
Y68574D01*
G01Y73946D02*
Y71599D01*
G01Y86427D02*
Y84159D01*
G01X348659Y87483D02*
Y87587D01*
G01X348145Y70881D02*
Y68273D01*
G01Y74247D02*
Y71599D01*
G01Y78083D02*
Y76957D01*
G01Y82621D02*
Y80793D01*
G01Y87188D02*
Y84159D01*
G01X347796Y90178D02*
Y87618D01*
G01X347244Y98036D02*
Y99217D01*
G01X346949Y67482D02*
Y66237D01*
G01Y75361D02*
Y74116D01*
G01Y85257D02*
Y84006D01*
G01X346851Y83780D02*
Y85355D01*
G01Y73937D02*
Y75512D01*
G01Y99217D02*
Y98036D01*
G01X346063Y83780D02*
Y85355D01*
G01Y73937D02*
Y75512D01*
G01Y99217D02*
Y97411D01*
G01Y96330D02*
Y95705D01*
G01X346024Y67737D02*
Y65965D01*
G01Y75611D02*
Y73839D01*
G01Y85453D02*
Y83682D01*
G01X345889Y97736D02*
Y97110D01*
G01X345670Y97576D02*
Y96951D01*
G01X345276Y96372D02*
Y96998D01*
G01X343957Y93130D02*
Y97067D01*
G01X342678D02*
Y96182D01*
G01X341755Y97752D02*
Y98762D01*
G01X341654Y99217D02*
Y98036D01*
G01X341595Y97067D02*
Y93130D01*
G01X341404Y97110D02*
Y97736D01*
G01Y99217D02*
Y98036D01*
G01X340971D02*
Y99217D01*
G01X340709Y88742D02*
Y97067D01*
G01X340552Y98036D02*
Y99217D01*
G01X340512D02*
Y98036D01*
G01X340040D02*
Y99217D01*
G01X339528D02*
Y98036D01*
G01X339233Y96182D02*
Y93898D01*
G01X338347Y84453D02*
Y86844D01*
G01X338150Y63482D02*
Y91573D01*
G01X337166Y86844D02*
Y84453D01*
G01X352559Y85421D02*
X352166Y87030D01*
G01X339134Y68765D02*
X339233Y68554D01*
G01X350197Y90178D02*
X352953Y87422D01*
G01X349804Y90293D02*
X353052Y87045D01*
G01X346949Y84006D02*
X352953Y79548D01*
G01X347008Y83682D02*
X353052Y79194D01*
G01X352559Y75668D02*
X352166Y75921D01*
G01X348659Y87587D02*
X351972Y87341D01*
G01Y87237D02*
X348659Y87483D01*
G01X351972Y86316D02*
X349115Y86528D01*
G01Y86423D02*
X351972Y86211D01*
G01X339134Y99217D02*
X360867D01*
G01X339134Y98036D02*
X360867D01*
G01X354111Y97736D02*
X358597D01*
G01X341404D02*
X345889D01*
G01X339922Y97245D02*
X338741D01*
G01X339134Y97165D02*
X339922D01*
G01X345889Y97110D02*
X341404D01*
G01X358597D02*
X354111D01*
G01X340118Y97067D02*
X349804D01*
G01X359882D02*
X350197D01*
G01X339134Y96539D02*
X339922D01*
G01X353937Y96330D02*
X346063D01*
G01X339134Y96319D02*
X339528D01*
G01X349804Y96182D02*
X350197D01*
G01X339233D02*
X342678D01*
G01X338741Y95930D02*
X339233D01*
G01X337363Y95913D02*
X338544D01*
G01X353937Y95705D02*
X346063D01*
G01X339233Y95397D02*
X338741D01*
G01X350197Y95217D02*
X359292D01*
G01X340709Y94710D02*
X349804D01*
G01X338544Y94099D02*
X337363D01*
G01X339922Y93898D02*
X338741D01*
G01X339922Y93831D02*
X338741D01*
G01X338544Y93311D02*
X337363D01*
G01X341595Y93130D02*
X343957D01*
G01X338741Y93069D02*
X339922D01*
G01Y92308D02*
X338741D01*
G01X338150Y91573D02*
X337363D01*
G01X338741Y91551D02*
X339922D01*
G01Y90790D02*
X338741D01*
G01X350197Y90178D02*
X352166D01*
G01X349804D02*
X347796D01*
G01X338741Y90028D02*
X339922D01*
G01Y89961D02*
X338741D01*
G01X339233Y88462D02*
X338741D01*
G01X339233Y87929D02*
X338741D01*
G01X340125Y87618D02*
X347796D01*
G01X353937Y87422D02*
X352953D01*
G01X353937Y87312D02*
X353150D01*
G01X353937Y87294D02*
X353150D01*
G01Y87017D02*
X353937D01*
G01X353150Y86033D02*
X353937D01*
G01X353150Y85756D02*
X353937D01*
G01Y85737D02*
X353150D01*
G01X353937Y85650D02*
X352953D01*
G01X347008Y85453D02*
X346024D01*
G01X352559Y85421D02*
X354134D01*
G01X346851Y85355D02*
X346063D01*
G01X346851Y85337D02*
X346063D01*
G01Y85059D02*
X346851D01*
G01X338347Y84453D02*
X337166D01*
G01X339233D02*
X338741D01*
G01X348995Y84263D02*
X348145D01*
G01X338544Y84256D02*
X337363D01*
G01X348995Y84159D02*
X348145D01*
G01X346063Y84075D02*
X346851D01*
G01X337363Y83862D02*
X338544D01*
G01X339233D02*
X338741D01*
G01X346063Y83798D02*
X346851D01*
G01Y83780D02*
X346063D01*
G01X353937Y83689D02*
X353150D01*
G01X347008Y83682D02*
X346024D01*
G01X338544Y83469D02*
X337363D01*
G01X349113Y83442D02*
X351003D01*
G01X349113Y83338D02*
X351003D01*
G01X339233Y82484D02*
X338741D01*
G01X349468Y82420D02*
X350649D01*
G01X349468Y82316D02*
X350649D01*
G01X339233Y82288D02*
X338741D01*
G01Y82063D02*
X339233D01*
G01X354134Y81911D02*
X359882D01*
G01X338544Y81697D02*
X337363D01*
G01X339233Y81500D02*
X338741D01*
G01X354134Y81174D02*
X359882D01*
G01X350649Y81098D02*
X349468D01*
G01X350649Y80994D02*
X349468D01*
G01X351003Y80076D02*
X349113D01*
G01X351003Y79972D02*
X349113D01*
G01X337953Y79728D02*
X337363D01*
G01X338741Y79725D02*
X338544D01*
G01X353937Y79548D02*
X352953D01*
G01X353937Y79438D02*
X353150D01*
G01X353937Y79420D02*
X353150D01*
G01X351121Y79255D02*
X351972D01*
G01X351121Y79151D02*
X351972D01*
G01X353150Y79143D02*
X353937D01*
G01X353150Y78159D02*
X353937D01*
G01X348145Y78083D02*
X351003D01*
G01X348145Y77979D02*
X351003D01*
G01X354134Y77976D02*
X359882D01*
G01X353150Y77881D02*
X353937D01*
G01Y77863D02*
X353150D01*
G01X353937Y77776D02*
X352953D01*
G01X351003Y77062D02*
X348145D01*
G01X351003Y76957D02*
X348145D01*
G01X354134Y76554D02*
X352166D01*
G01X359882Y76411D02*
X354134D01*
G01X351972Y75890D02*
X351121D01*
G01X351972Y75785D02*
X351121D01*
G01X354134Y75668D02*
X352559D01*
G01X347008Y75611D02*
X346024D01*
G01X346851Y75512D02*
X346063D01*
G01X346851Y75494D02*
X346063D01*
G01Y75217D02*
X346851D01*
G01X339233Y75119D02*
X338741D01*
G01X349113Y75068D02*
X351003D01*
G01X349113Y74964D02*
X351003D01*
G01X339233Y74922D02*
X339134D01*
G01X353937Y74888D02*
X353150D01*
G01Y74443D02*
X353937D01*
G01X346063Y74233D02*
X346851D01*
G01X349645Y74047D02*
X349113D01*
G01X351003D02*
X350472D01*
G01X346063Y73955D02*
X346851D01*
G01X349645Y73942D02*
X349113D01*
G01X351003D02*
X350472D01*
G01X346851Y73937D02*
X346063D01*
G01X347008Y73839D02*
X346024D01*
G01X338741Y73649D02*
X339233D01*
G01X354134Y73644D02*
X359882D01*
G01X346851Y73522D02*
X346063D01*
G01X339233Y72967D02*
X338741D01*
G01X354134Y72380D02*
X359882D01*
G01X350354Y72103D02*
X349763D01*
G01X350354Y71999D02*
X349763D01*
G01X348995Y71703D02*
X348145D01*
G01X351972D02*
X351121D01*
G01X353937Y71674D02*
X352953D01*
G01X348995Y71599D02*
X348145D01*
G01X351972D02*
X351121D01*
G01X353937Y71564D02*
X353150D01*
G01X353937Y71546D02*
X353150D01*
G01Y71269D02*
X353937D01*
G01X350732Y70881D02*
X351003D01*
G01X348145D02*
X348995D01*
G01X350732Y70777D02*
X351003D01*
G01X348145D02*
X348995D01*
G01X353150Y70285D02*
X353937D01*
G01X353150Y70007D02*
X353937D01*
G01Y69989D02*
X353150D01*
G01X353937Y69902D02*
X352953D01*
G01X351003Y69860D02*
X350472D01*
G01X351003Y69756D02*
X350472D01*
G01X346851Y69519D02*
X346063D01*
G01Y68821D02*
X346851D01*
G01X349113Y68578D02*
X349645D01*
G01X349113Y68473D02*
X349645D01*
G01X347008Y67737D02*
X346024D01*
G01X346851Y67638D02*
X346063D01*
G01X346851Y67620D02*
X346063D01*
G01X349385Y67556D02*
X349113D01*
G01X351972D02*
X351121D01*
G01X349385Y67452D02*
X349113D01*
G01X351972D02*
X351121D01*
G01X346063Y67343D02*
X346851D01*
G01X346063Y66359D02*
X346851D01*
G01X346063Y66081D02*
X346851D01*
G01X339233Y66063D02*
X338741D01*
G01X346851D02*
X346063D01*
G01X347008Y65965D02*
X346024D01*
G01X339233Y65276D02*
X338741D01*
G01X353937Y63800D02*
X352953D01*
G01X339528Y63732D02*
X339134D01*
G01X353937Y63690D02*
X353150D01*
G01X353937Y63672D02*
X353150D01*
G01X337363Y63482D02*
X338150D01*
G01X353150Y63395D02*
X353937D01*
G01X353052Y85849D02*
X347008Y85453D01*
G01X352953Y85650D02*
X346949Y85257D01*
G01X352953Y71674D02*
X346949Y74116D01*
G01X353052Y71381D02*
X347008Y73839D01*
G01X352953Y63800D02*
X346949Y66237D01*
G01X353052Y63512D02*
X347008Y65965D01*
G01X339528Y63106D02*
X339134D01*
G01X306231Y183651D02*
X305906Y183716D01*
G01X306505Y183466D02*
X306231Y183651D01*
G01X306685Y183193D02*
X306505Y183466D01*
G01X306748Y182871D02*
X306685Y183193D01*
G01X306683Y182549D02*
X306748Y182871D01*
G01X306501Y182279D02*
X306683Y182549D01*
G01X306230Y182097D02*
X306501Y182279D01*
G01X305906Y182032D02*
X306230Y182097D01*
G01X311615Y186496D02*
G03X312402Y187284I0J787D01*
G01X299410Y184548D02*
G03X300197Y183760I788J0D01*
G01X304528D02*
G03X305315Y184542I0J787D01*
G01X305906Y183701D02*
G03Y182048I0J-827D01*
G01X307284Y185709D02*
G03X306103Y184536I0J-1181D01*
G01X311615Y185709D02*
G03X313189Y187284I0J1574D01*
G01X298622Y184548D02*
G03X300197Y182973I1575J0D01*
G01X304528D02*
G03X306103Y184536I0J1575D01*
G01X307284Y186496D02*
G03X305315Y184542I0J-1969D01*
G01X315748Y179725D02*
G03X317717Y181693I0J1969D01*
G01X294095D02*
G03X296063Y179725I1968J0D01*
G01X307924Y182874D02*
G03I-2018J0D01*
G01X308071D02*
G03I-2165J0D01*
G01X315552Y157678D02*
G03I-6497J0D01*
G01X316142Y184496D02*
X314567Y183587D01*
G01X302874Y187933D02*
X303662Y188721D01*
G01X317717Y181693D02*
Y189075D01*
G01X316929Y185237D02*
Y182087D01*
G01X316733Y193308D02*
Y192126D01*
G01Y196457D02*
Y195276D01*
G01Y199607D02*
Y198426D01*
G01Y202756D02*
Y201575D01*
G01Y205906D02*
Y204725D01*
G01X316142Y184496D02*
Y182678D01*
G01X313780Y185237D02*
Y182087D01*
G01X313189Y187284D02*
Y383977D01*
G01X312402Y187284D02*
Y383977D01*
G01X311615Y185709D02*
Y186496D01*
G01X309843Y180512D02*
Y179725D01*
G01X308937Y383327D02*
Y187933D01*
G01X308859Y193308D02*
Y192126D01*
G01Y196457D02*
Y195276D01*
G01Y199607D02*
Y198426D01*
G01Y202756D02*
Y201575D01*
G01Y205906D02*
Y204725D01*
G01X308150Y382540D02*
Y188721D01*
G01X302953Y205906D02*
X295079D01*
G01X316733D02*
X308859D01*
G01X302953Y204725D02*
X295079D01*
G01X316733D02*
X308859D01*
G01X302953Y202756D02*
X295079D01*
G01X316733D02*
X308859D01*
G01X302953Y201575D02*
X295079D01*
G01X316733D02*
X308859D01*
G01X302953Y199607D02*
X295079D01*
G01X316733D02*
X308859D01*
G01X302953Y198426D02*
X295079D01*
G01X316733D02*
X308859D01*
G01X302953Y196457D02*
X295079D01*
G01X316733D02*
X308859D01*
G01X302953Y195276D02*
X295079D01*
G01X316733D02*
X308859D01*
G01X302953Y193308D02*
X295079D01*
G01X316733D02*
X308859D01*
G01X302953Y192126D02*
X295079D01*
G01X316733D02*
X308859D01*
G01X299410Y189075D02*
X294095D01*
G01X317717D02*
X312402D01*
G01X308150Y188721D02*
X303662D01*
G01X308937Y187933D02*
X302874D01*
G01X317717Y187500D02*
X294095D01*
G01X312402Y187284D02*
X313189D01*
G01X307284Y186496D02*
X311615D01*
G01Y185709D02*
X307284D01*
G01X316929Y185237D02*
X313780D01*
G01X298622Y184548D02*
X299410D01*
G01X300197Y183760D02*
X304528D01*
G01X307284Y186496D02*
Y185709D01*
G01X305906Y180856D02*
Y182032D01*
G01Y183716D02*
Y184893D01*
G01X304528Y182973D02*
Y183760D01*
G01X303662Y382540D02*
Y188721D01*
G01X302953Y193308D02*
Y192126D01*
G01Y196457D02*
Y195276D01*
G01Y199607D02*
Y198426D01*
G01Y202756D02*
Y201575D01*
G01Y205906D02*
Y204725D01*
G01X302874Y187933D02*
Y383327D01*
G01X301969Y180512D02*
Y179725D01*
G01X300197Y183760D02*
Y182973D01*
G01X299410Y386713D02*
Y184548D01*
G01X298622D02*
Y386713D01*
G01X295079Y193308D02*
Y192126D01*
G01Y196457D02*
Y195276D01*
G01Y199607D02*
Y198426D01*
G01Y202756D02*
Y201575D01*
G01Y205906D02*
Y204725D01*
G01X294095Y189075D02*
Y181693D01*
G01X306103Y184536D02*
X305315Y184542D01*
G01X304528Y182973D02*
X300197D01*
G01X316929Y182087D02*
X313780D01*
G01X309843Y180512D02*
X301969D01*
G01Y179725D02*
X296063D01*
G01X315748D02*
X309843D01*
G01X308150Y188721D02*
X308937Y187933D01*
G01X314567Y183587D02*
X316142Y182678D01*
G01X302953Y278347D02*
X295079D01*
G01X316733D02*
X308859D01*
G01X302953Y277166D02*
X295079D01*
G01X316733D02*
X308859D01*
G01X302953Y275197D02*
X295079D01*
G01X316733D02*
X308859D01*
G01X302953Y274016D02*
X295079D01*
G01X316733D02*
X308859D01*
G01X302953Y272048D02*
X295079D01*
G01X316733D02*
X308859D01*
G01X302953Y270867D02*
X295079D01*
G01X316733D02*
X308859D01*
G01X302953Y268898D02*
X295079D01*
G01X316733D02*
X308859D01*
G01X299410Y268308D02*
X298622D01*
G01X313189D02*
X312402D01*
G01X302953Y267717D02*
X295079D01*
G01X316733D02*
X308859D01*
G01X302953Y265748D02*
X295079D01*
G01X316733D02*
X308859D01*
G01X302953Y264567D02*
X295079D01*
G01X316733D02*
X308859D01*
G01X302953Y262599D02*
X295079D01*
G01X316733D02*
X308859D01*
G01X299410Y262008D02*
X298622D01*
G01X313189D02*
X312402D01*
G01X302953Y261418D02*
X295079D01*
G01X316733D02*
X308859D01*
G01X302953Y259449D02*
X295079D01*
G01X316733D02*
X308859D01*
G01X302953Y258268D02*
X295079D01*
G01X316733D02*
X308859D01*
G01X302953Y256300D02*
X295079D01*
G01X316733D02*
X308859D01*
G01X302953Y255119D02*
X295079D01*
G01X316733D02*
X308859D01*
G01X302953Y253150D02*
X295079D01*
G01X316733D02*
X308859D01*
G01X299410Y252559D02*
X298622D01*
G01X313189D02*
X312402D01*
G01X302953Y251969D02*
X295079D01*
G01X316733D02*
X308859D01*
G01X302953Y250000D02*
X295079D01*
G01X316733D02*
X308859D01*
G01X302953Y248819D02*
X295079D01*
G01X316733D02*
X308859D01*
G01X302953Y246851D02*
X295079D01*
G01X316733D02*
X308859D01*
G01X299410Y246260D02*
X298622D01*
G01X313189D02*
X312402D01*
G01X302953Y245670D02*
X295079D01*
G01X316733D02*
X308859D01*
G01X302953Y243701D02*
X295079D01*
G01X316733D02*
X308859D01*
G01X302953Y242520D02*
X295079D01*
G01X316733D02*
X308859D01*
G01X302953Y240552D02*
X295079D01*
G01X316733D02*
X308859D01*
G01X302953Y239370D02*
X295079D01*
G01X316733D02*
X308859D01*
G01X302953Y237402D02*
X295079D01*
G01X316733D02*
X308859D01*
G01X302953Y236221D02*
X295079D01*
G01X316733D02*
X308859D01*
G01X302953Y234252D02*
X295079D01*
G01X316733D02*
X308859D01*
G01X302953Y233071D02*
X295079D01*
G01X316733D02*
X308859D01*
G01X302953Y231103D02*
X295079D01*
G01X316733D02*
X308859D01*
G01X302953Y229922D02*
X295079D01*
G01X316733D02*
X308859D01*
G01X302953Y227953D02*
X295079D01*
G01X316733D02*
X308859D01*
G01X302953Y226772D02*
X295079D01*
G01X316733D02*
X308859D01*
G01X302953Y224804D02*
X295079D01*
G01X316733D02*
X308859D01*
G01X316733Y209056D02*
Y207874D01*
G01Y212205D02*
Y211024D01*
G01Y215355D02*
Y214174D01*
G01Y218504D02*
Y217323D01*
G01Y221654D02*
Y220473D01*
G01Y224804D02*
Y223622D01*
G01Y227953D02*
Y226772D01*
G01Y231103D02*
Y229922D01*
G01Y234252D02*
Y233071D01*
G01Y237402D02*
Y236221D01*
G01Y240552D02*
Y239370D01*
G01Y243701D02*
Y242520D01*
G01Y246851D02*
Y245670D01*
G01Y250000D02*
Y248819D01*
G01Y253150D02*
Y251969D01*
G01Y256300D02*
Y255119D01*
G01Y259449D02*
Y258268D01*
G01Y262599D02*
Y261418D01*
G01Y265748D02*
Y264567D01*
G01Y268898D02*
Y267717D01*
G01Y272048D02*
Y270867D01*
G01Y275197D02*
Y274016D01*
G01Y278347D02*
Y277166D01*
G01X308859Y209056D02*
Y207874D01*
G01Y212205D02*
Y211024D01*
G01Y215355D02*
Y214174D01*
G01Y218504D02*
Y217323D01*
G01Y221654D02*
Y220473D01*
G01Y224804D02*
Y223622D01*
G01Y227953D02*
Y226772D01*
G01Y231103D02*
Y229922D01*
G01Y234252D02*
Y233071D01*
G01Y237402D02*
Y236221D01*
G01Y240552D02*
Y239370D01*
G01Y243701D02*
Y242520D01*
G01Y246851D02*
Y245670D01*
G01Y250000D02*
Y248819D01*
G01Y253150D02*
Y251969D01*
G01Y256300D02*
Y255119D01*
G01Y259449D02*
Y258268D01*
G01Y262599D02*
Y261418D01*
G01Y265748D02*
Y264567D01*
G01Y268898D02*
Y267717D01*
G01Y272048D02*
Y270867D01*
G01Y275197D02*
Y274016D01*
G01Y278347D02*
Y277166D01*
G01X302953Y223622D02*
X295079D01*
G01X316733D02*
X308859D01*
G01X302953Y221654D02*
X295079D01*
G01X316733D02*
X308859D01*
G01X302953Y220473D02*
X295079D01*
G01X316733D02*
X308859D01*
G01X302953Y218504D02*
X295079D01*
G01X316733D02*
X308859D01*
G01X302953Y217323D02*
X295079D01*
G01X316733D02*
X308859D01*
G01X302953Y215355D02*
X295079D01*
G01X316733D02*
X308859D01*
G01X302953Y214174D02*
X295079D01*
G01X316733D02*
X308859D01*
G01X302953Y212205D02*
X295079D01*
G01X316733D02*
X308859D01*
G01X302953Y211024D02*
X295079D01*
G01X316733D02*
X308859D01*
G01X302953Y209056D02*
X295079D01*
G01X316733D02*
X308859D01*
G01X302953Y207874D02*
X295079D01*
G01X316733D02*
X308859D01*
G01X302953Y209056D02*
Y207874D01*
G01Y212205D02*
Y211024D01*
G01Y215355D02*
Y214174D01*
G01Y218504D02*
Y217323D01*
G01Y221654D02*
Y220473D01*
G01Y224804D02*
Y223622D01*
G01Y227953D02*
Y226772D01*
G01Y231103D02*
Y229922D01*
G01Y234252D02*
Y233071D01*
G01Y237402D02*
Y236221D01*
G01Y240552D02*
Y239370D01*
G01Y243701D02*
Y242520D01*
G01Y246851D02*
Y245670D01*
G01Y250000D02*
Y248819D01*
G01Y253150D02*
Y251969D01*
G01Y256300D02*
Y255119D01*
G01Y259449D02*
Y258268D01*
G01Y262599D02*
Y261418D01*
G01Y265748D02*
Y264567D01*
G01Y268898D02*
Y267717D01*
G01Y272048D02*
Y270867D01*
G01Y275197D02*
Y274016D01*
G01Y278347D02*
Y277166D01*
G01X295079Y209056D02*
Y207874D01*
G01Y212205D02*
Y211024D01*
G01Y215355D02*
Y214174D01*
G01Y218504D02*
Y217323D01*
G01Y224804D02*
Y223622D01*
G01Y221654D02*
Y220473D01*
G01Y227953D02*
Y226772D01*
G01Y231103D02*
Y229922D01*
G01Y234252D02*
Y233071D01*
G01Y237402D02*
Y236221D01*
G01Y240552D02*
Y239370D01*
G01Y243701D02*
Y242520D01*
G01Y246851D02*
Y245670D01*
G01Y250000D02*
Y248819D01*
G01Y253150D02*
Y251969D01*
G01Y256300D02*
Y255119D01*
G01Y259449D02*
Y258268D01*
G01Y262599D02*
Y261418D01*
G01Y265748D02*
Y264567D01*
G01Y268898D02*
Y267717D01*
G01Y272048D02*
Y270867D01*
G01Y275197D02*
Y274016D01*
G01Y278347D02*
Y277166D01*
G01X302953Y349607D02*
X295079D01*
G01X316733D02*
X308859D01*
G01X302953Y347638D02*
X295079D01*
G01X316733D02*
X308859D01*
G01X302953Y346457D02*
X295079D01*
G01X316733D02*
X308859D01*
G01X302953Y344489D02*
X295079D01*
G01X316733D02*
X308859D01*
G01X302953Y343308D02*
X295079D01*
G01X316733D02*
X308859D01*
G01X302953Y341339D02*
X295079D01*
G01X316733D02*
X308859D01*
G01X302953Y340158D02*
X295079D01*
G01X316733D02*
X308859D01*
G01X302953Y338189D02*
X295079D01*
G01X316733D02*
X308859D01*
G01X302953Y337008D02*
X295079D01*
G01X316733D02*
X308859D01*
G01X302953Y335040D02*
X295079D01*
G01X316733D02*
X308859D01*
G01X302953Y333859D02*
X295079D01*
G01X316733D02*
X308859D01*
G01X302953Y331890D02*
X295079D01*
G01X316733D02*
X308859D01*
G01X302953Y330709D02*
X295079D01*
G01X316733D02*
X308859D01*
G01X302953Y328741D02*
X295079D01*
G01X316733D02*
X308859D01*
G01X302953Y327559D02*
X295079D01*
G01X316733D02*
X308859D01*
G01X302953Y325591D02*
X295079D01*
G01X316733D02*
X308859D01*
G01X298622Y325000D02*
X299410D01*
G01X313189D02*
X312402D01*
G01X302953Y324410D02*
X295079D01*
G01X316733D02*
X308859D01*
G01X302953Y322441D02*
X295079D01*
G01X316733D02*
X308859D01*
G01X302953Y321260D02*
X295079D01*
G01X316733D02*
X308859D01*
G01X302953Y319292D02*
X295079D01*
G01X316733D02*
X308859D01*
G01X312402Y318701D02*
X313189D01*
G01X299410D02*
X298622D01*
G01X302953Y318111D02*
X295079D01*
G01X316733D02*
X308859D01*
G01X302953Y316142D02*
X295079D01*
G01X316733D02*
X308859D01*
G01X302953Y314961D02*
X295079D01*
G01X316733D02*
X308859D01*
G01X302953Y312993D02*
X295079D01*
G01X316733D02*
X308859D01*
G01X302953Y311811D02*
X295079D01*
G01X316733D02*
X308859D01*
G01X302953Y309843D02*
X295079D01*
G01X316733D02*
X308859D01*
G01X299410Y309252D02*
X298622D01*
G01X313189D02*
X312402D01*
G01X302953Y308662D02*
X295079D01*
G01X316733D02*
X308859D01*
G01X302953Y306693D02*
X295079D01*
G01X316733D02*
X308859D01*
G01X302953Y305512D02*
X295079D01*
G01X316733D02*
X308859D01*
G01X302953Y303544D02*
X295079D01*
G01X316733D02*
X308859D01*
G01X312402Y302953D02*
X313189D01*
G01X299410D02*
X298622D01*
G01X302953Y302363D02*
X295079D01*
G01X316733D02*
X308859D01*
G01X302953Y300394D02*
X295079D01*
G01X316733D02*
X308859D01*
G01X302953Y299213D02*
X295079D01*
G01X316733D02*
X308859D01*
G01X302953Y297245D02*
X295079D01*
G01X316733D02*
X308859D01*
G01X302953Y296063D02*
X295079D01*
G01X316733D02*
X308859D01*
G01X302953Y294095D02*
X295079D01*
G01X316733D02*
X308859D01*
G01X302953Y292914D02*
X295079D01*
G01X316733D02*
X308859D01*
G01X299449Y291536D02*
X299410D01*
G01X302953Y290945D02*
X295079D01*
G01X316733D02*
X308859D01*
G01X299449Y290822D02*
X299410D01*
G01X302953Y289764D02*
X295079D01*
G01X316733D02*
X308859D01*
G01X302953Y287796D02*
X295079D01*
G01X316733D02*
X308859D01*
G01X299449Y287730D02*
X299410D01*
G01X299449Y287254D02*
X299410D01*
G01X302953Y286615D02*
X295079D01*
G01X316733D02*
X308859D01*
G01X299449Y286303D02*
X299410D01*
G01X299449Y286184D02*
X299410D01*
G01X299449Y285946D02*
X299410D01*
G01X299449Y285589D02*
X299410D01*
G01X299449Y285470D02*
X299410D01*
G01X299449Y285233D02*
X299410D01*
G01X299449Y284995D02*
X299410D01*
G01X299449Y284876D02*
X299410D01*
G01X302953Y284646D02*
X295079D01*
G01X316733D02*
X308859D01*
G01X299449Y284400D02*
X299410D01*
G01X302953Y283465D02*
X295079D01*
G01X316733D02*
X308859D01*
G01X299449Y283330D02*
X299410D01*
G01X299449Y282854D02*
X299410D01*
G01X299449Y282735D02*
X299410D01*
G01X299449Y282497D02*
X299410D01*
G01X299449Y282378D02*
X299410D01*
G01X299449Y282259D02*
X299410D01*
G01X299449Y281784D02*
X299410D01*
G01X299449Y281665D02*
X299410D01*
G01X302953Y281496D02*
X295079D01*
G01X316733D02*
X308859D01*
G01X299449Y280713D02*
X299410D01*
G01X302953Y280315D02*
X295079D01*
G01X316733D02*
X308859D01*
G01X299449Y280000D02*
X299410D01*
G01X316733Y281496D02*
Y280315D01*
G01Y284646D02*
Y283465D01*
G01Y287796D02*
Y286615D01*
G01Y290945D02*
Y289764D01*
G01Y294095D02*
Y292914D01*
G01Y297245D02*
Y296063D01*
G01Y300394D02*
Y299213D01*
G01Y303544D02*
Y302363D01*
G01Y306693D02*
Y305512D01*
G01Y309843D02*
Y308662D01*
G01Y312993D02*
Y311811D01*
G01Y316142D02*
Y314961D01*
G01Y319292D02*
Y318111D01*
G01Y322441D02*
Y321260D01*
G01Y325591D02*
Y324410D01*
G01Y328741D02*
Y327559D01*
G01Y331890D02*
Y330709D01*
G01Y335040D02*
Y333859D01*
G01Y338189D02*
Y337008D01*
G01Y341339D02*
Y340158D01*
G01Y344489D02*
Y343308D01*
G01Y347638D02*
Y346457D01*
G01Y350788D02*
Y349607D01*
G01X308859Y281496D02*
Y280315D01*
G01Y284646D02*
Y283465D01*
G01Y287796D02*
Y286615D01*
G01Y290945D02*
Y289764D01*
G01Y294095D02*
Y292914D01*
G01Y297245D02*
Y296063D01*
G01Y300394D02*
Y299213D01*
G01Y303544D02*
Y302363D01*
G01Y306693D02*
Y305512D01*
G01Y309843D02*
Y308662D01*
G01Y312993D02*
Y311811D01*
G01Y316142D02*
Y314961D01*
G01Y319292D02*
Y318111D01*
G01Y322441D02*
Y321260D01*
G01Y325591D02*
Y324410D01*
G01Y328741D02*
Y327559D01*
G01Y331890D02*
Y330709D01*
G01Y335040D02*
Y333859D01*
G01Y338189D02*
Y337008D01*
G01Y341339D02*
Y340158D01*
G01Y344489D02*
Y343308D01*
G01Y347638D02*
Y346457D01*
G01Y350788D02*
Y349607D01*
G01X302953Y281496D02*
Y280315D01*
G01Y284646D02*
Y283465D01*
G01Y287796D02*
Y286615D01*
G01Y290945D02*
Y289764D01*
G01Y294095D02*
Y292914D01*
G01Y297245D02*
Y296063D01*
G01Y300394D02*
Y299213D01*
G01Y303544D02*
Y302363D01*
G01Y306693D02*
Y305512D01*
G01Y309843D02*
Y308662D01*
G01Y312993D02*
Y311811D01*
G01Y316142D02*
Y314961D01*
G01Y319292D02*
Y318111D01*
G01Y322441D02*
Y321260D01*
G01Y325591D02*
Y324410D01*
G01Y328741D02*
Y327559D01*
G01Y331890D02*
Y330709D01*
G01Y335040D02*
Y333859D01*
G01Y338189D02*
Y337008D01*
G01Y341339D02*
Y340158D01*
G01Y344489D02*
Y343308D01*
G01Y347638D02*
Y346457D01*
G01Y350788D02*
Y349607D01*
G01X299449Y280713D02*
Y280000D01*
G01Y286303D02*
Y281665D01*
G01Y291536D02*
Y287254D01*
G01X295079Y281496D02*
Y280315D01*
G01Y287796D02*
Y286615D01*
G01Y284646D02*
Y283465D01*
G01Y290945D02*
Y289764D01*
G01Y294095D02*
Y292914D01*
G01Y297245D02*
Y296063D01*
G01Y300394D02*
Y299213D01*
G01Y303544D02*
Y302363D01*
G01Y306693D02*
Y305512D01*
G01Y309843D02*
Y308662D01*
G01Y312993D02*
Y311811D01*
G01Y316142D02*
Y314961D01*
G01Y319292D02*
Y318111D01*
G01Y322441D02*
Y321260D01*
G01Y325591D02*
Y324410D01*
G01Y328741D02*
Y327559D01*
G01Y331890D02*
Y330709D01*
G01Y335040D02*
Y333859D01*
G01Y338189D02*
Y337008D01*
G01Y341339D02*
Y340158D01*
G01Y344489D02*
Y343308D01*
G01Y347638D02*
Y346457D01*
G01Y350788D02*
Y349607D01*
G01X312402Y383977D02*
G03X311615Y384764I-787J0D01*
G01X300197Y387500D02*
G03X299410Y386713I0J-787D01*
G01X305315Y386719D02*
G03X304528Y387500I-787J-6D01*
G01X306103Y386724D02*
G03X307284Y385552I1181J9D01*
G01X307123Y388386D02*
G03I-1217J0D01*
G01X307284D02*
G03I-1378J0D01*
G01X313189Y383977D02*
G03X311615Y385552I-1575J0D01*
G01X300197Y388288D02*
G03X298622Y386713I0J-1575D01*
G01X306103Y386724D02*
G03X304528Y388288I-1575J-11D01*
G01X305315Y386719D02*
G03X307284Y384764I1969J14D01*
G01X307874Y388386D02*
G03I-1968J0D01*
G01X317717Y389567D02*
G03X315748Y391536I-1969J0D01*
G01X296063D02*
G03X294095Y389567I0J-1968D01*
G01X302559Y420276D02*
G03Y406890I0J-6693D01*
G01X315945D02*
G03Y420276I0J6693D01*
G01D02*
X302559D01*
G01X315945Y406890D02*
X302559D01*
G01X301969Y391536D02*
X296063D01*
G01X315748D02*
X309843D01*
G01Y390748D02*
X301969D01*
G01X304528Y388288D02*
X300197D01*
G01X304528Y387500D02*
X300197D01*
G01X299410Y386713D02*
X298622D01*
G01X311615Y385552D02*
X307284D01*
G01X311615Y384764D02*
X307284D01*
G01X305315Y386719D02*
X306103Y386724D01*
G01X313189Y383977D02*
X312402D01*
G01X317717Y383760D02*
X294095D01*
G01X302874Y383327D02*
X308937D01*
G01X308150Y382540D02*
X303662D01*
G01X299410Y382185D02*
X294095D01*
G01X317717D02*
X312402D01*
G01X302953Y379134D02*
X295079D01*
G01X316733D02*
X308859D01*
G01X302953Y377953D02*
X295079D01*
G01X316733D02*
X308859D01*
G01X302953Y375985D02*
X295079D01*
G01X316733D02*
X308859D01*
G01X302953Y374804D02*
X295079D01*
G01X316733D02*
X308859D01*
G01X302953Y372835D02*
X295079D01*
G01X316733D02*
X308859D01*
G01X302953Y371654D02*
X295079D01*
G01X316733D02*
X308859D01*
G01X302953Y369685D02*
X295079D01*
G01X316733D02*
X308859D01*
G01X302953Y368504D02*
X295079D01*
G01X316733D02*
X308859D01*
G01X302953Y366536D02*
X295079D01*
G01X316733D02*
X308859D01*
G01X302953Y365355D02*
X295079D01*
G01X316733D02*
X308859D01*
G01X302953Y363386D02*
X295079D01*
G01X316733D02*
X308859D01*
G01X302953Y362205D02*
X295079D01*
G01X316733D02*
X308859D01*
G01X302953Y360237D02*
X295079D01*
G01X316733D02*
X308859D01*
G01X302953Y359056D02*
X295079D01*
G01X316733D02*
X308859D01*
G01X302953Y357087D02*
X295079D01*
G01X316733D02*
X308859D01*
G01X302953Y355906D02*
X295079D01*
G01X316733D02*
X308859D01*
G01X302953Y353937D02*
X295079D01*
G01X316733D02*
X308859D01*
G01X302953Y352756D02*
X295079D01*
G01X316733D02*
X308859D01*
G01X302953Y350788D02*
X295079D01*
G01X316733D02*
X308859D01*
G01X303662Y382540D02*
X302874Y383327D01*
G01X308937D02*
X308150Y382540D01*
G01X317717Y382185D02*
Y389567D01*
G01X316733Y353937D02*
Y352756D01*
G01Y357087D02*
Y355906D01*
G01Y360237D02*
Y359056D01*
G01Y363386D02*
Y362205D01*
G01Y366536D02*
Y365355D01*
G01Y369685D02*
Y368504D01*
G01Y372835D02*
Y371654D01*
G01Y375985D02*
Y374804D01*
G01Y379134D02*
Y377953D01*
G01X311615Y384764D02*
Y385552D01*
G01X309843Y391536D02*
Y390748D01*
G01X308859Y353937D02*
Y352756D01*
G01Y357087D02*
Y355906D01*
G01Y360237D02*
Y359056D01*
G01Y363386D02*
Y362205D01*
G01Y366536D02*
Y365355D01*
G01Y369685D02*
Y368504D01*
G01Y372835D02*
Y371654D01*
G01Y375985D02*
Y374804D01*
G01Y379134D02*
Y377953D01*
G01X307284Y385552D02*
Y384764D01*
G01X304528Y387500D02*
Y388288D01*
G01X302953Y353937D02*
Y352756D01*
G01Y357087D02*
Y355906D01*
G01Y360237D02*
Y359056D01*
G01Y363386D02*
Y362205D01*
G01Y366536D02*
Y365355D01*
G01Y369685D02*
Y368504D01*
G01Y372835D02*
Y371654D01*
G01Y375985D02*
Y374804D01*
G01Y379134D02*
Y377953D01*
G01X301969Y391536D02*
Y390748D01*
G01X300197Y388288D02*
Y387500D01*
G01X295079Y353937D02*
Y352756D01*
G01Y357087D02*
Y355906D01*
G01Y360237D02*
Y359056D01*
G01Y363386D02*
Y362205D01*
G01Y366536D02*
Y365355D01*
G01Y369685D02*
Y368504D01*
G01Y372835D02*
Y371654D01*
G01Y375985D02*
Y374804D01*
G01Y379134D02*
Y377953D01*
G01X294095Y389567D02*
Y382185D01*
G01X321851Y472441D02*
G03I-6890J0D01*
G01X299363Y1463291D02*
Y1444354D01*
G01X345139D02*
X853013D01*
G01X388445Y-614831D02*
Y-419310D01*
G01X360726Y4939D02*
X360770Y4894D01*
G01X360614Y4997D02*
X360726Y4939D01*
G01X358845Y53708D02*
X358733Y53638D01*
G01X358963Y53765D02*
X358845Y53708D01*
G01X359088Y53811D02*
X358963Y53765D01*
G01X359219Y53843D02*
X359088Y53811D01*
G01X359353Y53863D02*
X359219Y53843D01*
G01X359489Y53870D02*
X359353Y53863D01*
G01X361445Y62855D02*
X361457Y62793D01*
G01X361412Y62914D02*
X361445Y62855D01*
G01X361357Y62967D02*
X361412Y62914D01*
G01X361284Y63015D02*
X361357Y62967D01*
G01X361193Y63054D02*
X361284Y63015D01*
G01X361238Y60785D02*
X361260Y60611D01*
G01X361173Y60954D02*
X361238Y60785D01*
G01X361070Y61104D02*
X361173Y60954D01*
G01X360931Y61233D02*
X361070Y61104D01*
G01X360764Y61335D02*
X360931Y61233D01*
G01X360576Y61406D02*
X360764Y61335D01*
G01X360178Y61475D02*
X360576Y61406D01*
G01X359499Y63021D02*
X359549Y63185D01*
G01X359490Y62853D02*
X359499Y63021D01*
G01X359521Y62686D02*
X359490Y62853D01*
G01X359590Y62528D02*
X359521Y62686D01*
G01X359696Y62385D02*
X359590Y62528D01*
G01X359833Y62263D02*
X359696Y62385D01*
G01X359997Y62167D02*
X359833Y62263D01*
G01X360179Y62101D02*
X359997Y62167D01*
G01X358546Y54082D02*
X358733Y54264D01*
G01X358407Y53901D02*
X358546Y54082D01*
G01X358312Y53725D02*
X358407Y53901D01*
G01X358255Y53555D02*
X358312Y53725D01*
G01X358231Y53388D02*
X358255Y53555D01*
G01X358237Y53218D02*
X358231Y53388D01*
G01X358270Y53051D02*
X358237Y53218D01*
G01X358322Y52903D02*
X358270Y53051D01*
G01X358382Y52776D02*
X358322Y52903D01*
G01X358444Y52668D02*
X358382Y52776D01*
G01X358501Y52581D02*
X358444Y52668D01*
G01X358571Y52489D02*
X358501Y52581D01*
G01X358648Y52413D02*
X358571Y52489D01*
G01X358744Y52337D02*
X358648Y52413D01*
G01X358858Y52263D02*
X358744Y52337D01*
G01X358988Y52189D02*
X358858Y52263D01*
G01X359136Y52116D02*
X358988Y52189D01*
G01X359303Y52042D02*
X359136Y52116D01*
G01X359489Y51969D02*
X359303Y52042D01*
G01X356537Y1700D02*
X356678Y1517D01*
G01X356390Y1848D02*
X356537Y1700D01*
G01X359996Y61542D02*
X360178Y61475D01*
G01X359832Y61638D02*
X359996Y61542D01*
G01X359693Y61762D02*
X359832Y61638D01*
G01X359588Y61906D02*
X359693Y61762D01*
G01X359519Y62064D02*
X359588Y61906D01*
G01X359490Y62231D02*
X359519Y62064D01*
G01X359500Y62399D02*
X359490Y62231D01*
G01X359550Y62563D02*
X359500Y62399D01*
G01X359638Y62714D02*
X359550Y62563D01*
G01X359760Y62847D02*
X359638Y62714D01*
G01X359911Y62957D02*
X359760Y62847D01*
G01X360085Y63039D02*
X359911Y62957D01*
G01X361241Y55165D02*
X361260Y55330D01*
G01X361185Y55010D02*
X361241Y55165D01*
G01X361094Y54866D02*
X361185Y55010D01*
G01X360972Y54740D02*
X361094Y54866D01*
G01X360821Y54635D02*
X360972Y54740D01*
G01X360651Y54559D02*
X360821Y54635D01*
G01X360467Y54512D02*
X360651Y54559D01*
G01X360276Y54496D02*
X360467Y54512D01*
G01X355949Y2107D02*
X355808Y2140D01*
G01X356093Y2050D02*
X355949Y2107D01*
G01X356240Y1965D02*
X356093Y2050D01*
G01X356390Y1848D02*
X356240Y1965D01*
G01X356537Y1700D02*
X356390Y1848D01*
G01X356678Y1517D02*
X356537Y1700D01*
G01X356812Y1300D02*
X356678Y1517D01*
G01X356935Y1047D02*
X356812Y1300D01*
G01X362604Y62976D02*
X362504Y63151D01*
G01X362638Y62793D02*
X362604Y62976D01*
G01X360577Y62031D02*
X360179Y62101D01*
G01X360768Y61959D02*
X360577Y62031D01*
G01X360935Y61857D02*
X360768Y61959D01*
G01X361072Y61727D02*
X360935Y61857D01*
G01X361175Y61576D02*
X361072Y61727D01*
G01X361239Y61410D02*
X361175Y61576D01*
G01X361260Y61237D02*
X361239Y61410D01*
G01X361085Y55722D02*
X361260Y55462D01*
G01X360962Y55973D02*
X361085Y55722D01*
G01X360890Y56207D02*
X360962Y55973D01*
G01X360867Y56417D02*
X360890Y56207D01*
G01X360038Y12864D02*
X360036Y12816D01*
G01X360038Y12881D02*
Y12864D01*
G01X359995Y12746D02*
X359983Y12669D01*
G01X359997Y12768D02*
X359995Y12746D01*
G01X361678Y62704D02*
X361457Y62398D01*
G01X361808Y63074D02*
X361678Y62704D01*
G01X360253Y55719D02*
X360079Y55462D01*
G01X360376Y55968D02*
X360253Y55719D01*
G01X360448Y56204D02*
X360376Y55968D01*
G01X360473Y56417D02*
X360448Y56204D01*
G01X360470Y53886D02*
X360276Y53870D01*
G01X360654Y53934D02*
X360470Y53886D01*
G01X360823Y54011D02*
X360654Y53934D01*
G01X360972Y54114D02*
X360823Y54011D01*
G01X361096Y54243D02*
X360972Y54114D01*
G01X361186Y54386D02*
X361096Y54243D01*
G01X361241Y54542D02*
X361186Y54386D01*
G01X361260Y54704D02*
X361241Y54542D01*
G01X360057Y12769D02*
X360029Y12737D01*
G01X360073Y12805D02*
X360057Y12769D01*
G01X360079Y12843D02*
X360073Y12805D01*
G01X360069Y12938D02*
X360038Y12881D01*
G01X360079Y13001D02*
X360069Y12938D01*
G01X360058Y12649D02*
X360079Y12843D01*
G01X359983Y12422D02*
X360058Y12649D01*
G01X360008Y12717D02*
X360029Y12737D01*
G01X359992Y12694D02*
X360008Y12717D01*
G01X359983Y12669D02*
X359992Y12694D01*
G01X359928Y12402D02*
X359811Y12227D01*
G01X359999Y12583D02*
X359928Y12402D01*
G01X359927D02*
X359811Y12227D01*
G01X359999Y12582D02*
X359927Y12402D01*
G01X359881Y12397D02*
X359781Y12253D01*
G01X359949Y12547D02*
X359881Y12397D01*
G01X360010Y12831D02*
X359998Y12775D01*
G01X360038Y12881D02*
X360010Y12831D01*
G01D02*
X359998Y12775D01*
G01X360038Y12881D02*
X360010Y12831D01*
G01X359331Y52014D02*
X359489Y51969D01*
G01X359185Y52059D02*
X359331Y52014D01*
G01X359052Y52105D02*
X359185Y52059D01*
G01X358933Y52151D02*
X359052Y52105D01*
G01X358826Y52197D02*
X358933Y52151D01*
G01X358732Y52243D02*
X358826Y52197D01*
G01X358651Y52291D02*
X358732Y52243D01*
G01X358578Y52343D02*
X358651Y52291D01*
G01X358507Y52409D02*
X358578Y52343D01*
G01X358441Y52481D02*
X358507Y52409D01*
G01X358384Y52553D02*
X358441Y52481D01*
G01X358324Y52643D02*
X358384Y52553D01*
G01X358272Y52750D02*
X358324Y52643D01*
G01X358240Y52861D02*
X358272Y52750D01*
G01X358230Y52972D02*
X358240Y52861D01*
G01X358244Y53082D02*
X358230Y52972D01*
G01X358283Y53192D02*
X358244Y53082D01*
G01X358350Y53305D02*
X358283Y53192D01*
G01X358449Y53419D02*
X358350Y53305D01*
G01X358577Y53530D02*
X358449Y53419D01*
G01X358733Y53638D02*
X358577Y53530D01*
G01X359349Y54489D02*
X359489Y54496D01*
G01X359215Y54468D02*
X359349Y54489D01*
G01X359085Y54435D02*
X359215Y54468D01*
G01X358960Y54390D02*
X359085Y54435D01*
G01X358842Y54332D02*
X358960Y54390D01*
G01X358733Y54264D02*
X358842Y54332D01*
G01X412402Y39370D02*
G03I-6890J0D01*
G01X360079Y42323D02*
G03X360276Y42520I0J197D01*
G01X361260Y41810D02*
G03X361457Y42520I-1181J710D01*
G01X360375Y17731D02*
G03X360265Y16471I696J-696D01*
G01X359540Y18567D02*
G03X359297Y15793I1531J-1532D01*
G01X360279Y11021D02*
G03X360168Y10965I29J-195D01*
G01X360279Y11021D02*
G03X360390Y11076I-28J195D01*
G01X360038Y12881D02*
G03X359998Y12775I157J-120D01*
G01X359499Y10186D02*
G03X359389Y8925I696J-696D01*
G01X359472Y10213D02*
G03X359357Y8902I723J-724D01*
G01X359444Y10241D02*
G03X359325Y8880I751J-751D01*
G01X358664Y11021D02*
G03X358422Y8248I1531J-1531D01*
G01X358636Y11049D02*
G03X358389Y8225I1559J-1559D01*
G01X358609Y11076D02*
G03X358357Y8202I1586J-1587D01*
G01X360079Y14366D02*
G03X359901Y14931I-984J0D01*
G01X361260Y14366D02*
G03X360869Y15608I-2165J1D01*
G01X360038Y12881D02*
G03X360079Y13001I-155J120D01*
G01X359735Y12203D02*
G03X359998Y12775I-640J641D01*
G01X359763Y12175D02*
G03X359811Y12227I-670J666D01*
G01X359791Y12147D02*
G03X360079Y12843I-697J696D01*
G01X360626Y11312D02*
G03X361260Y12843I-1532J1531D01*
G01X361015Y6603D02*
G03X360915Y6677I-161J-113D01*
G01X360815Y6751D02*
G03X360915Y6677I161J113D01*
G01X360570Y5042D02*
G03X360670Y4968I161J113D01*
G01X360770Y4894D02*
G03X360670Y4968I-161J-113D01*
G01X361984Y3846D02*
X361662Y3621D01*
G01X362123Y5021D02*
X361155Y4343D01*
G01X360277Y5461D02*
X360341Y5506D01*
G01X358426Y39685D02*
X357244Y38898D01*
G01X360631Y7151D02*
X360567Y7106D01*
G01X359389Y8925D02*
X358357Y8202D01*
G01X360869Y15608D02*
X359901Y14931D01*
G01X360265Y16471D02*
X359297Y15793D01*
G01X360626Y11312D02*
X359499Y10186D01*
G01X360279Y11021D02*
X359472Y10213D01*
G01X360168Y10965D02*
X359444Y10241D01*
G01X359791Y12147D02*
X358664Y11021D01*
G01X359763Y12175D02*
X358636Y11049D01*
G01X359735Y12203D02*
X358609Y11076D01*
G01X361407Y18763D02*
X360375Y17731D01*
G01X361129Y20155D02*
X359540Y18567D01*
G01X356457Y16063D02*
X355867Y15473D01*
G01X359981Y30433D02*
X358012Y28465D01*
G01X359981Y40867D02*
X358800Y39685D01*
G01X358307Y48544D02*
X358111Y48347D01*
G01X359841Y12201D02*
X359983Y12422D01*
G01X357244Y1103D02*
X355881Y-1259D01*
G01X360069Y12938D02*
X360038Y12881D01*
G01X359928Y12402D02*
X359999Y12584D01*
G01X359983Y12669D02*
X359948Y12544D01*
G01X360768Y45197D02*
X359981Y42259D01*
G01X359999Y12583D02*
X360029Y12737D01*
G01X362177Y4943D02*
X361984Y3846D01*
G01X360035Y12816D02*
X360029Y12737D01*
G01X360038Y12864D02*
X360035Y12816D01*
G01X362638Y62003D02*
Y97445D01*
G01X361457D02*
Y42520D01*
G01X361407Y19877D02*
Y18763D01*
G01X361260Y-2165D02*
Y97245D01*
G01X360886Y51772D02*
Y89522D01*
G01X360867Y97165D02*
Y56417D01*
G01X360768Y45197D02*
Y47756D01*
G01X360473Y56417D02*
Y96319D01*
G01X360374Y61441D02*
Y62067D01*
G01X360276Y49421D02*
Y42520D01*
G01Y54496D02*
Y53870D01*
G01X360079Y-1574D02*
Y97245D01*
G01X359981Y30433D02*
Y51496D01*
G01X359882Y97067D02*
Y45886D01*
G01X359489Y62272D02*
Y62898D01*
G01Y53870D02*
Y54496D01*
G01Y51969D02*
Y-2165D01*
G01X359390Y45788D02*
Y49421D01*
G01X358800Y39685D02*
Y54646D01*
G01X358733Y53638D02*
Y54264D01*
G01X358406Y51595D02*
Y48248D01*
G01X358307Y48544D02*
Y51300D01*
G01X358230Y53335D02*
Y52962D01*
G01X357244Y38898D02*
Y1103D01*
G01X357028Y48248D02*
Y45886D01*
G01X356929Y45788D02*
Y48347D01*
G01X356693Y55532D02*
Y54646D01*
G01X355867Y7835D02*
Y39685D01*
G01X356935Y1047D02*
X357044Y755D01*
G01X360643Y5007D02*
X360670Y4968D01*
G01D02*
X360643Y5008D01*
G01X360566Y5119D02*
X360643Y5007D01*
G01Y5008D02*
X360564Y5121D01*
G01X360265Y16471D02*
X360869Y15608D01*
G01X359297Y15793D02*
X359901Y14931D01*
G01X359389Y8925D02*
X362177Y4943D01*
G01X359357Y8902D02*
X360915Y6677D01*
G01X359325Y8880D02*
X360815Y6751D01*
G01X358422Y8248D02*
X361662Y3621D01*
G01X358389Y8225D02*
X360565Y5119D01*
G01X358357Y8202D02*
X360570Y5042D01*
G01X358111Y51496D02*
X358307Y51300D01*
G01X359390Y45788D02*
X359981Y45197D01*
G01X360570Y5042D02*
X360614Y4997D01*
G01X360570Y5042D02*
X360614Y4997D01*
G01X361129Y20155D02*
X361407Y19877D01*
G01X360493Y19520D02*
X361328Y18685D01*
G01X359540Y18567D02*
X360375Y17731D01*
G01X359735Y12203D02*
X360626Y11312D01*
G01X359861Y10659D02*
X359917Y10603D01*
G01X358609Y11076D02*
X359499Y10186D01*
G01X360079Y-1574D02*
X360670Y-2165D01*
G01X359781Y12253D02*
X359841Y12201D01*
G01X362638Y62480D02*
X361457D01*
G01X362638Y62002D02*
X361457D01*
G01X360867Y56417D02*
X360473D01*
G01X361260Y54828D02*
X360079D01*
G01X360276Y54496D02*
X359489D01*
G01X360886Y53923D02*
X361260D01*
G01X360276Y53870D02*
X359489D01*
G01X360886Y53241D02*
X361260D01*
G01Y51772D02*
X360079D01*
G01X361260Y51705D02*
X360079D01*
G01X359882Y51595D02*
X358800D01*
G01X360079Y50943D02*
X361260D01*
G01Y50182D02*
X360079D01*
G01Y49425D02*
X361260D01*
G01X358307Y49421D02*
X358406D01*
G01X358800D02*
X360276D01*
G01X361260Y48664D02*
X360079D01*
G01X356929Y48347D02*
X358111D01*
G01X358406Y48248D02*
X357028D01*
G01X361260Y47953D02*
X360079D01*
G01Y47902D02*
X361260D01*
G01Y47835D02*
X360079D01*
G01X360768Y47756D02*
X359981D01*
G01X359882Y46870D02*
X358800D01*
G01X361260Y46484D02*
X360079D01*
G01X357028Y45886D02*
X359882D01*
G01X361260Y45802D02*
X360079D01*
G01X359390Y45788D02*
X356929D01*
G01X361457Y44292D02*
X361260D01*
G01X360276D02*
X360079D01*
G01X361260Y41654D02*
X360079D01*
G01X361260Y40867D02*
X360079D01*
G01X356103Y28465D02*
X358012D01*
G01X360079Y27756D02*
X361260D01*
G01Y26697D02*
X360079D01*
G01X361260Y26453D02*
X360079D01*
G01X361260Y22402D02*
X360079D01*
G01X361260Y20066D02*
X360079D01*
G01X355867Y16063D02*
X357244D01*
G01X361260Y14366D02*
X360079D01*
G01X361260Y12843D02*
X360079D01*
G01X361260Y6447D02*
X360079D01*
G01X361260Y6310D02*
X360079D01*
G01Y5591D02*
X361260D01*
G01Y2804D02*
X360079D01*
G01X361260Y-196D02*
X360079D01*
G01X361092Y63083D02*
X361193Y63054D01*
G01X360981Y63100D02*
X361092Y63083D01*
G01X360867Y63106D02*
X360981Y63100D01*
G01X360274Y63715D02*
X360473Y63732D01*
G01X360084Y63664D02*
X360274Y63715D01*
G01X359910Y63582D02*
X360084Y63664D01*
G01X359757Y63470D02*
X359910Y63582D01*
G01X359636Y63337D02*
X359757Y63470D01*
G01X359549Y63185D02*
X359636Y63337D01*
G01X360275Y63089D02*
X360085Y63039D01*
G01X360473Y63106D02*
X360275Y63089D01*
G01X362603Y96412D02*
X362638Y96226D01*
G01X362502Y96587D02*
X362603Y96412D01*
G01X362339Y96749D02*
X362502Y96587D01*
G01X362119Y96890D02*
X362339Y96749D01*
G01X361847Y97008D02*
X362119Y96890D01*
G01X361542Y97094D02*
X361847Y97008D01*
G01X361211Y97147D02*
X361542Y97094D01*
G01X360867Y97165D02*
X361211Y97147D01*
G01X358798Y97567D02*
X358597Y97736D01*
G01X359024Y97425D02*
X358798Y97567D01*
G01X359266Y97314D02*
X359024Y97425D01*
G01X359530Y97231D02*
X359266Y97314D01*
G01X359805Y97181D02*
X359530Y97231D01*
G01X360079Y97165D02*
X359805Y97181D01*
G01X359797Y96557D02*
X360079Y96539D01*
G01X359522Y96608D02*
X359797Y96557D01*
G01X359264Y96689D02*
X359522Y96608D01*
G01X359017Y96803D02*
X359264Y96689D01*
G01X358791Y96946D02*
X359017Y96803D01*
G01X358597Y97110D02*
X358791Y96946D01*
G01X358463Y98027D02*
X358597Y98036D01*
G01X358365Y98002D02*
X358463Y98027D01*
G01X358299Y97960D02*
X358365Y98002D01*
G01X358259Y97903D02*
X358299Y97960D01*
G01X358245Y97828D02*
X358259Y97903D01*
G01X358257Y97733D02*
X358245Y97828D01*
G01X358295Y97617D02*
X358257Y97733D01*
G01X358362Y97476D02*
X358295Y97617D01*
G01X358461Y97308D02*
X358362Y97476D01*
G01X358597Y97110D02*
X358461Y97308D01*
G01X415824Y121386D02*
X415853Y121022D01*
G01X415741Y121736D02*
X415824Y121386D01*
G01X415608Y122057D02*
X415741Y121736D01*
G01X415435Y122335D02*
X415608Y122057D01*
G01X415234Y122563D02*
X415435Y122335D01*
G01X415016Y122737D02*
X415234Y122563D01*
G01X422911Y121386D02*
X422940Y121022D01*
G01X422827Y121736D02*
X422911Y121386D01*
G01X422695Y122057D02*
X422827Y121736D01*
G01X422522Y122335D02*
X422695Y122057D01*
G01X422320Y122563D02*
X422522Y122335D01*
G01X422102Y122737D02*
X422320Y122563D01*
G01X361808Y92026D02*
X361851Y91573D01*
G01X361678Y92534D02*
X361808Y92026D01*
G01X361457Y93075D02*
X361678Y92534D01*
G01X358370Y99165D02*
X358597Y99217D01*
G01X358258Y98997D02*
X358370Y99165D01*
G01X358263Y98696D02*
X358258Y98997D01*
G01X358376Y98281D02*
X358263Y98696D01*
G01X358597Y97736D02*
X358376Y98281D01*
G01X361217Y63714D02*
X360867Y63732D01*
G01X361547Y63660D02*
X361217Y63714D01*
G01X361852Y63574D02*
X361547Y63660D01*
G01X362119Y63457D02*
X361852Y63574D01*
G01X362342Y63313D02*
X362119Y63457D01*
G01X362504Y63151D02*
X362342Y63313D01*
G01X360983Y96533D02*
X360867Y96539D01*
G01X361093Y96515D02*
X360983Y96533D01*
G01X361195Y96486D02*
X361093Y96515D01*
G01X361284Y96448D02*
X361195Y96486D01*
G01X361358Y96399D02*
X361284Y96448D01*
G01X361412Y96346D02*
X361358Y96399D01*
G01X361446Y96287D02*
X361412Y96346D01*
G01X361457Y96226D02*
X361446Y96287D01*
G01X360299Y96913D02*
X360079Y97112D01*
G01X360431Y96639D02*
X360299Y96913D01*
G01X360473Y96319D02*
X360431Y96639D01*
G01X415381Y122515D02*
X415016Y122737D01*
G01X415644Y122234D02*
X415381Y122515D01*
G01X415800Y121921D02*
X415644Y122234D01*
G01X415853Y121593D02*
X415800Y121921D01*
G01X422468Y122515D02*
X422102Y122737D01*
G01X422730Y122234D02*
X422468Y122515D01*
G01X422887Y121921D02*
X422730Y122234D01*
G01X422940Y121593D02*
X422887Y121921D01*
G01X361851Y63482D02*
X361808Y63074D01*
G01X420429Y122563D02*
X420647Y122737D01*
G01X420228Y122335D02*
X420429Y122563D01*
G01X420055Y122057D02*
X420228Y122335D01*
G01X419922Y121736D02*
X420055Y122057D01*
G01X419839Y121386D02*
X419922Y121736D01*
G01X419810Y121022D02*
X419839Y121386D01*
G01X427516Y122563D02*
X427734Y122737D01*
G01X427314Y122335D02*
X427516Y122563D01*
G01X427141Y122057D02*
X427314Y122335D01*
G01X427009Y121736D02*
X427141Y122057D01*
G01X426925Y121386D02*
X427009Y121736D01*
G01X426896Y121022D02*
X426925Y121386D01*
G01X420185Y122429D02*
X420647Y122737D01*
G01X419904Y122029D02*
X420185Y122429D01*
G01X419810Y121593D02*
X419904Y122029D01*
G01X427272Y122429D02*
X427734Y122737D01*
G01X426991Y122029D02*
X427272Y122429D01*
G01X426896Y121593D02*
X426991Y122029D01*
G01X360907Y96633D02*
X360867Y96319D01*
G01X361037Y96909D02*
X360907Y96633D01*
G01X361260Y97112D02*
X361037Y96909D01*
G01X422363Y130709D02*
G03I-709J0D01*
G01Y126378D02*
G03I-709J0D01*
G01X415020Y122745D02*
G03X414288Y122926I-733J-1394D01*
G01X422107Y122745D02*
G03X420643I-732J-1394D01*
G01X361457Y97445D02*
G03X360867Y98036I-591J0D01*
G01X361457Y81496D02*
G03X361260Y82206I-1378J0D01*
G01X362638Y97445D02*
G03X360867Y99217I-1772J0D01*
G01X361654Y86844D02*
G03X361372Y88306I-3937J-1D01*
G01X362835Y86844D02*
G03X362469Y88745I-5118J0D01*
G01X422910Y115256D02*
X421729Y114075D01*
G01X426896Y121593D02*
Y115650D01*
G01X422940Y121593D02*
Y115650D01*
G01X422910Y115256D02*
Y118012D01*
G01X419839D02*
Y115256D01*
G01X419810Y121593D02*
Y115650D01*
G01X417818Y201805D02*
Y113091D01*
G01X415853Y121593D02*
Y115650D01*
G01X414288Y122916D02*
Y138996D01*
G01Y115650D02*
Y118012D01*
G01X362835Y86844D02*
Y84453D01*
G01X361851Y91573D02*
Y63482D01*
G01X361654Y84453D02*
Y86844D01*
G01X360886Y93111D02*
Y90748D01*
G01Y96182D02*
Y95473D01*
G01X360473Y98036D02*
Y99217D01*
G01X359960D02*
Y98036D01*
G01X359489Y99217D02*
Y98036D01*
G01X359449D02*
Y99217D01*
G01X359292Y88742D02*
Y97067D01*
G01X359029Y99217D02*
Y98036D01*
G01X358597D02*
Y99217D01*
G01Y97736D02*
Y97110D01*
G01X358406Y93130D02*
Y97067D01*
G01X358347Y98036D02*
Y99217D01*
G01X358245Y98877D02*
Y97823D01*
G01X356044Y97067D02*
Y93130D01*
G01X362469Y88745D02*
X361260Y91767D01*
G01X360886Y89522D02*
X361372Y88306D01*
G01X359882Y87606D02*
X359292Y88742D01*
G01X419839Y115256D02*
X421020Y114075D01*
G01X361457Y80751D02*
X362048Y79728D01*
G01X359882Y93157D02*
X359292Y94102D01*
G01X473956Y126536D02*
X417818D01*
G01X420647Y122737D02*
X415016D01*
G01X427734D02*
X422102D01*
G01X473956Y120493D02*
X417818D01*
G01X473956Y120020D02*
X417818D01*
G01X559017Y118012D02*
X414288D01*
G01X473956Y116437D02*
X417818D01*
G01X559017Y115650D02*
X414288D01*
G01X422910Y115256D02*
X419839D01*
G01X421729Y114075D02*
X421020D01*
G01X473956Y113091D02*
X417818D01*
G01X361260Y97245D02*
X360079D01*
G01Y97165D02*
X360867D01*
G01X360079Y96539D02*
X360867D01*
G01X360079Y96359D02*
X361260D01*
G01X360473Y96319D02*
X360867D01*
G01X360079Y96287D02*
X361260D01*
G01X360079Y96260D02*
X361260D01*
G01Y96228D02*
X360079D01*
G01X359292Y96182D02*
X360886D01*
G01X361457Y95913D02*
X362638D01*
G01X361260Y95544D02*
X360079D01*
G01X361260Y95473D02*
X360079D01*
G01Y94598D02*
X361260D01*
G01X362638Y94099D02*
X361457D01*
G01X362638Y93311D02*
X361457D01*
G01X356044Y93130D02*
X358406D01*
G01X361260Y93111D02*
X360079D01*
G01X362638Y91573D02*
X361851D01*
G01X361260Y90748D02*
X360079D01*
G01X361260Y89261D02*
X360079D01*
G01X361260Y88386D02*
X360079D01*
G01Y88315D02*
X361260D01*
G01X360079Y87631D02*
X361260D01*
G01Y87572D02*
X360079D01*
G01Y87500D02*
X361260D01*
G01X360886Y86917D02*
X361260D01*
G01Y86235D02*
X360886D01*
G01X362835Y84453D02*
X361654D01*
G01X361260D02*
X360886D01*
G01X362638Y84256D02*
X361457D01*
G01X361260Y83862D02*
X360886D01*
G01X362638D02*
X361457D01*
G01Y83469D02*
X362638D01*
G01X361260Y82484D02*
X360886D01*
G01X361260Y82288D02*
X360886D01*
G01X361260Y82063D02*
X360886D01*
G01X362638Y81697D02*
X361457D01*
G01X361260Y81500D02*
X360886D01*
G01X362638Y79728D02*
X362048D01*
G01X361457Y79725D02*
X361260D01*
G01Y75119D02*
X360886D01*
G01Y73649D02*
X361260D01*
G01Y72967D02*
X360886D01*
G01X361260Y66063D02*
X360886D01*
G01X361260Y65276D02*
X360886D01*
G01X360867Y63732D02*
X360473D01*
G01X361851Y63482D02*
X362638D01*
G01X360867Y63106D02*
X360473D01*
G01X416142Y348379D02*
Y196851D01*
G01D02*
X560237D01*
G01X422695Y190749D02*
X422679Y190748D01*
G01X422710Y190751D02*
X422695Y190749D01*
G01X422726Y190755D02*
X422710Y190751D01*
G01X426388Y200763D02*
X426379Y200821D01*
G01X426411Y200714D02*
X426388Y200763D01*
G01X426444Y200675D02*
X426411Y200714D01*
G01X426485Y200646D02*
X426444Y200675D01*
G01X426530Y200629D02*
X426485Y200646D01*
G01X426576Y200624D02*
X426530Y200629D01*
G01X425176Y202248D02*
X425185Y202247D01*
G01X425168Y202249D02*
X425176Y202248D01*
G01X425160Y202250D02*
X425168Y202249D01*
G01X425152Y202251D02*
X425160Y202250D01*
G01X425144Y202252D02*
X425152Y202251D01*
G01X425137Y202254D02*
X425144Y202252D01*
G01X424869Y196164D02*
X424812Y196457D01*
G01X425041Y195905D02*
X424869Y196164D01*
G01X425304Y195730D02*
X425041Y195905D01*
G01X425611Y195670D02*
X425304Y195730D01*
G01X425252Y196264D02*
X425199Y196457D01*
G01X425403Y196118D02*
X425252Y196264D01*
G01X425611Y196063D02*
X425403Y196118D01*
G01X419474Y190749D02*
X419490Y190748D01*
G01X419458Y190751D02*
X419474Y190749D01*
G01X419443Y190755D02*
X419458Y190751D01*
G01X419402Y190761D02*
X419443Y190755D01*
G01X419361Y190776D02*
X419402Y190761D01*
G01X419324Y190801D02*
X419361Y190776D01*
G01X419293Y190834D02*
X419324Y190801D01*
G01X425574Y196270D02*
X425654Y196260D01*
G01X425499Y196288D02*
X425574Y196270D01*
G01X425430Y196313D02*
X425499Y196288D01*
G01X425370Y196343D02*
X425430Y196313D01*
G01X425321Y196379D02*
X425370Y196343D01*
G01X425286Y196417D02*
X425321Y196379D01*
G01X425267Y196457D02*
X425286Y196417D01*
G01X425649Y197005D02*
X425729Y196995D01*
G01X425574Y197023D02*
X425649Y197005D01*
G01X425504Y197048D02*
X425574Y197023D01*
G01X425444Y197078D02*
X425504Y197048D01*
G01X425396Y197113D02*
X425444Y197078D01*
G01X425361Y197152D02*
X425396Y197113D01*
G01X425341Y197192D02*
X425361Y197152D01*
G01X425053Y202275D02*
X425137Y202254D01*
G01X424975Y202310D02*
X425053Y202275D01*
G01X424908Y202354D02*
X424975Y202310D01*
G01X424855Y202406D02*
X424908Y202354D01*
G01X424817Y202465D02*
X424855Y202406D01*
G01X424797Y202526D02*
X424817Y202465D01*
G01X424923Y201231D02*
X425003Y201218D01*
G01X424846Y201256D02*
X424923Y201231D01*
G01X424775Y201291D02*
X424846Y201256D01*
G01X424715Y201334D02*
X424775Y201291D01*
G01X424667Y201384D02*
X424715Y201334D01*
G01X424634Y201439D02*
X424667Y201384D01*
G01X424616Y201496D02*
X424634Y201439D01*
G01X424199Y201037D02*
X424200Y200940D01*
G01X424199Y201138D02*
Y201037D01*
G01X424198Y201241D02*
X424199Y201138D01*
G01X426501Y190764D02*
X426576Y190748D01*
G01X426437Y190806D02*
X426501Y190764D01*
G01X426395Y190871D02*
X426437Y190806D01*
G01X426379Y190945D02*
X426395Y190871D01*
G01X425567Y196073D02*
X425654Y196063D01*
G01X425486Y196103D02*
X425567Y196073D01*
G01X425412Y196149D02*
X425486Y196103D01*
G01X425351Y196213D02*
X425412Y196149D01*
G01X425305Y196287D02*
X425351Y196213D01*
G01X425276Y196370D02*
X425305Y196287D01*
G01X425267Y196457D02*
X425276Y196370D01*
G01X424582Y201043D02*
Y196457D01*
G01X424583Y201144D02*
X424582Y201043D01*
G01X424586Y201241D02*
X424583Y201144D01*
G01X424981Y201136D02*
X425003Y201218D01*
G01X424968Y201041D02*
X424981Y201136D01*
G01X424963Y200940D02*
X424968Y201041D01*
G01X424604Y201419D02*
X424616Y201496D01*
G01X424594Y201334D02*
X424604Y201419D01*
G01X424586Y201241D02*
X424594Y201334D01*
G01X422767Y190761D02*
X422726Y190755D01*
G01X422807Y190776D02*
X422767Y190761D01*
G01X422844Y190801D02*
X422807Y190776D01*
G01X422876Y190834D02*
X422844Y190801D01*
G01X424569Y196457D02*
G03X424963Y196063I394J0D01*
G01X422364Y195670D02*
G03X421970Y196063I-393J0D01*
G01X420198D02*
G03X419805Y195670I0J-393D01*
G01X427285Y196063D02*
G03X426891Y195670I0J-394D01*
G01X422363Y178741D02*
G03I-709J0D01*
G01Y183071D02*
G03I-709J0D01*
G01X424215Y196457D02*
G03X424963Y195709I748J0D01*
G01X408268Y188977D02*
G03X412205I1968J0D01*
G01X426887Y160650D02*
G03X430036I1574J0D01*
G01X422363Y173229D02*
G03I-709J0D01*
G01Y168898D02*
G03I-709J0D01*
G01Y164567D02*
G03I-709J0D01*
G01X422910Y165421D02*
G03Y167201I-1299J890D01*
G01Y172744D02*
G03Y174523I-1299J889D01*
G01X419839D02*
G03Y172744I1300J-890D01*
G01Y167201D02*
G03Y165421I1300J-890D01*
G01X422363Y159056D02*
G03I-709J0D01*
G01Y154725D02*
G03I-709J0D01*
G01Y150394D02*
G03I-709J0D01*
G01X422753Y156142D02*
G03X423737Y157126I0J984D01*
G01X419013D02*
G03X419997Y156142I984J0D01*
G01X419800Y160650D02*
G03X422950I1575J0D01*
G01X414288Y159075D02*
G03X415863Y160650I0J1575D01*
G01X430430Y140965D02*
G03I-1969J0D01*
G01X422363Y144882D02*
G03I-709J0D01*
G01Y140552D02*
G03I-709J0D01*
G01Y136221D02*
G03I-709J0D01*
G01X414288Y138996D02*
G03Y142933I0J1968D01*
G01X423343Y140965D02*
G03I-1968J0D01*
G01X422910Y163186D02*
X422123Y161822D01*
G01X422950Y177161D02*
X424328Y179548D01*
G01X417241D02*
X415863Y177161D01*
G01X425185Y202247D02*
X425003Y201218D01*
G01X424616Y201496D02*
X424797Y202526D01*
G01X425654Y196260D02*
X425729Y196995D01*
G01X425341Y197192D02*
X425267Y196457D01*
G01X422726Y190755D02*
X422719Y190158D01*
G01X422730Y201805D02*
X422726Y190755D01*
G01X426891Y197192D02*
Y191733D01*
G01X426887Y177161D02*
Y160650D01*
G01X426576Y200624D02*
Y190748D01*
G01X426379Y201043D02*
Y190158D01*
G01X425729Y196995D02*
Y226338D01*
G01X425654Y196260D02*
Y196063D01*
G01X425611D02*
Y195670D01*
G01X425341Y226338D02*
Y197192D01*
G01X425199Y196457D02*
Y226338D01*
G01X425185Y202247D02*
Y224608D01*
G01X424963Y195695D02*
Y200940D01*
G01X424812Y196457D02*
Y226338D01*
G01X424797Y202526D02*
Y224608D01*
G01X424586D02*
Y201241D01*
G01X424200Y200940D02*
Y196457D01*
G01X424198Y224608D02*
Y201241D01*
G01X423737Y180552D02*
Y157126D01*
G01X422950Y174463D02*
Y177161D01*
G01Y167140D02*
Y172804D01*
G01Y160650D02*
Y165481D01*
G01X422910Y165421D02*
Y163186D01*
G01Y172744D02*
Y167201D01*
G01Y180552D02*
Y174523D01*
G01X422876Y190834D02*
Y190158D01*
G01X422679Y190748D02*
Y201805D01*
G01X422364Y195670D02*
Y191733D01*
G01X422265Y195906D02*
Y191969D01*
G01X419903Y195906D02*
Y191969D01*
G01X419839Y174523D02*
Y180552D01*
G01Y167201D02*
Y172744D01*
G01Y163186D02*
Y165421D01*
G01X419805Y195670D02*
Y191733D01*
G01X419800Y165481D02*
Y160650D01*
G01Y172804D02*
Y167140D01*
G01Y177161D02*
Y174463D01*
G01X419490Y201805D02*
Y190748D01*
G01X419293Y190834D02*
Y190158D01*
G01X419013Y180552D02*
Y157126D01*
G01X417329Y228741D02*
Y190158D01*
G01X415863Y160650D02*
Y177161D01*
G01X414288Y142933D02*
Y159075D01*
G01X408268Y723480D02*
Y188977D01*
G01X419439Y201805D02*
X419442Y190755D01*
G01X419450Y190158D02*
X419443Y190755D01*
G01X425509Y179548D02*
X426887Y177161D01*
G01X418422Y179548D02*
X419800Y177161D01*
G01X419839Y163186D02*
X420627Y161822D01*
G01X424797Y202526D02*
X428984D01*
G01X428596Y202247D02*
X425185D01*
G01X419439Y201805D02*
X422730D01*
G01X417818D02*
X417329D01*
G01X424586Y201241D02*
X424198D01*
G01X425003Y201218D02*
X428778D01*
G01X429962Y201043D02*
X426379D01*
G01X424200Y200940D02*
X429581D01*
G01X429765Y200624D02*
X426576D01*
G01X425341Y197192D02*
X426891D01*
G01X425729Y196995D02*
X426891D01*
G01X424200Y196457D02*
X426891D01*
G01X425654Y196260D02*
X426891D01*
G01X424963Y196076D02*
X426891D01*
G01X421970Y196063D02*
X420198D01*
G01X426891D02*
X425611D01*
G01X429057D02*
X427285D01*
G01X422265Y195906D02*
X419903D01*
G01X424963Y195695D02*
X426891D01*
G01Y195670D02*
X425611D01*
G01X419805Y193567D02*
X417329D01*
G01X426891D02*
X422364D01*
G01X422265Y193544D02*
X419903D01*
G01X422364Y193370D02*
X426891D01*
G01X417329D02*
X419805D01*
G01X422265Y191969D02*
X419903D01*
G01X422364Y191733D02*
X419805D01*
G01X429450D02*
X426891D01*
G01X473629Y190748D02*
X417329D01*
G01X429962Y190237D02*
X426379D01*
G01X473956Y190158D02*
X417329D01*
G01X473956Y189370D02*
X417818D01*
G01X412205Y188977D02*
X564174D01*
G01X422910Y180552D02*
X469446D01*
G01X419839D02*
X417818D01*
G01X417241Y179548D02*
X418422D01*
G01X425509D02*
X424328D01*
G01X423146Y177502D02*
X426690D01*
G01X422123Y161822D02*
X420627D01*
G01X423737Y158665D02*
X419013D01*
G01X422753Y156142D02*
X419997D01*
G01X423551Y228514D02*
X423928Y228426D01*
G01X423474Y228533D02*
X423551Y228514D01*
G01X425318Y226991D02*
X425379Y226992D01*
G01X425270Y226997D02*
X425318Y226991D01*
G01X425239Y227012D02*
X425270Y226997D01*
G01X425631Y226582D02*
X425729Y226378D01*
G01X425514Y226786D02*
X425631Y226582D01*
G01X425291Y227127D02*
X425514Y226786D01*
G01X425212Y227262D02*
X425291Y227127D01*
G01X425144Y227395D02*
X425212Y227262D01*
G01X423036Y228734D02*
X422972Y228741D01*
G01X423096Y228715D02*
X423036Y228734D01*
G01X423151Y228683D02*
X423096Y228715D01*
G01X423198Y228641D02*
X423151Y228683D01*
G01X423237Y228591D02*
X423198Y228641D01*
G01X423264Y228533D02*
X423237Y228591D01*
G01X423246Y228734D02*
X423182Y228741D01*
G01X423306Y228715D02*
X423246Y228734D01*
G01X423361Y228683D02*
X423306Y228715D01*
G01X423409Y228641D02*
X423361Y228683D01*
G01X423447Y228591D02*
X423409Y228641D01*
G01X423474Y228533D02*
X423447Y228591D01*
G01X424289Y228734D02*
X424226Y228741D01*
G01X424349Y228715D02*
X424289Y228734D01*
G01X424403Y228684D02*
X424349Y228715D01*
G01X424452Y228641D02*
X424403Y228684D01*
G01X424490Y228591D02*
X424452Y228641D01*
G01X424517Y228533D02*
X424490Y228591D01*
G01X424645Y228734D02*
X424582Y228741D01*
G01X424705Y228715D02*
X424645Y228734D01*
G01X424760Y228684D02*
X424705Y228715D01*
G01X424808Y228641D02*
X424760Y228684D01*
G01X424846Y228591D02*
X424808Y228641D01*
G01X424873Y228533D02*
X424846Y228591D01*
G01X425242Y228650D02*
X425336Y228741D01*
G01X425233Y228383D02*
X425242Y228650D01*
G01X425312Y227957D02*
X425233Y228383D01*
G01X425477Y227395D02*
X425312Y227957D01*
G01X424743Y225061D02*
X424676Y225281D01*
G01X424784Y224836D02*
X424743Y225061D01*
G01X424797Y224608D02*
X424784Y224836D01*
G01X425120Y225152D02*
X425040Y225415D01*
G01X425169Y224882D02*
X425120Y225152D01*
G01X425185Y224608D02*
X425169Y224882D01*
G01X424532Y225062D02*
X424466Y225281D01*
G01X424572Y224836D02*
X424532Y225062D01*
G01X424586Y224608D02*
X424572Y224836D01*
G01X425146Y226792D02*
X425079Y227012D01*
G01X425186Y226567D02*
X425146Y226792D01*
G01X425199Y226338D02*
X425186Y226567D01*
G01X425328Y226585D02*
X425341Y226372D01*
G01X425294Y226800D02*
X425328Y226585D01*
G01X425239Y227012D02*
X425294Y226800D01*
G01X425057Y227630D02*
X425239Y227012D01*
G01X424942Y228113D02*
X425057Y227630D01*
G01X424873Y228533D02*
X424942Y228113D01*
G01X425113Y228710D02*
X425336Y228741D01*
G01X424954Y228633D02*
X425113Y228710D01*
G01X424873Y228533D02*
X424954Y228633D01*
G01X424180Y224608D02*
G03X424085Y225140I-1535J0D01*
G01X424793Y226338D02*
G03X424698Y226871I-1535J1D01*
G01X424517Y228533D02*
X424143Y228426D01*
G01X422889D02*
X423264Y228533D01*
G01X425040Y225416D02*
X424676Y225281D01*
G01X424466D02*
X424102Y225146D01*
G01X425079Y227012D02*
X424715Y226877D01*
G01X424219Y228741D02*
X422874Y227395D01*
G01X424143Y228426D02*
Y228741D01*
G01X423928Y228426D02*
Y228741D01*
G01X422889D02*
Y228426D01*
G01X422743Y228741D02*
Y220867D01*
G01X425341Y226372D02*
Y226338D01*
G01X425729Y226378D02*
Y226338D01*
G01X425079Y227012D02*
X424517Y228533D01*
G01X424143Y228426D02*
X424715Y226877D01*
G01X423928Y228426D02*
X425040Y225416D01*
G01X424676Y225281D02*
X423474Y228533D01*
G01X423264D02*
X424466Y225281D01*
G01X424102Y225146D02*
X422890Y228426D01*
G01X426745Y227395D02*
X425400Y228741D01*
G01X419659Y227395D02*
X418314Y228741D01*
G01X417329D02*
X473629D01*
G01X424517Y228533D02*
X424873D01*
G01X423474D02*
X423264D01*
G01X417329Y228426D02*
X429853D01*
G01X422743Y228253D02*
X417329D01*
G01X422874Y227395D02*
X419659D01*
G01X429961D02*
X425144D01*
G01X425239Y227012D02*
X425079D01*
G01X424812Y226338D02*
X425729D01*
G01X424676Y225281D02*
X424466D01*
G01X424198Y224608D02*
X425185D01*
G01X425729Y226378D02*
X425341Y226372D01*
G01X422743Y220867D02*
X417329D01*
G01X416142Y348379D02*
G03X408268I-3937J0D01*
G01X416142Y688303D02*
Y379088D01*
G01X408268D02*
G03X416142I3937J0D01*
G01Y688303D02*
G03X408268I-3937J0D01*
G01X524242Y763780D02*
X403757D01*
G01D02*
G03X400235Y758082I0J-3937D01*
G01X408268Y719012D02*
G03X416142I3937J0D01*
G01Y723480D02*
G03X414895Y728763I-11811J1D01*
G01X400235Y758082D02*
X414895Y728763D01*
G01X416142Y723480D02*
Y719012D01*
G01X389671Y761604D02*
G03X386150Y763780I-3521J-1761D01*
G01X408268Y723480D02*
G03X407852Y725241I-3937J0D01*
G01X371063Y740158D02*
G03I-6889J0D01*
G01X389671Y761604D02*
X407852Y725241D01*
G01X497623Y122163D02*
X497698Y122540D01*
G01X497409Y121844D02*
X497623Y122163D01*
G01X497090Y121630D02*
X497409Y121844D01*
G01X496714Y121556D02*
X497090Y121630D01*
G01X480056Y128822D02*
X479981Y128445D01*
G01X480269Y129141D02*
X480056Y128822D01*
G01X480589Y129355D02*
X480269Y129141D01*
G01X480965Y129430D02*
X480589Y129355D01*
G01X497449Y122542D02*
X497474Y122763D01*
G01X497376Y122335D02*
X497449Y122542D01*
G01X497259Y122150D02*
X497376Y122335D01*
G01X497101Y121992D02*
X497259Y122150D01*
G01X496915Y121876D02*
X497101Y121992D01*
G01X496708Y121804D02*
X496915Y121876D01*
G01X496490Y121779D02*
X496708Y121804D01*
G01X488274Y132040D02*
X487992Y132042D01*
G01X488557Y132038D02*
X488274Y132040D01*
G01X489122Y132038D02*
X488557D01*
G01X480230Y122542D02*
X480205Y122763D01*
G01X480303Y122335D02*
X480230Y122542D01*
G01X480420Y122150D02*
X480303Y122335D01*
G01X480578Y121992D02*
X480420Y122150D01*
G01X480764Y121876D02*
X480578Y121992D01*
G01X480971Y121804D02*
X480764Y121876D01*
G01X481189Y121779D02*
X480971Y121804D01*
G01X497449Y128443D02*
X497474Y128222D01*
G01X497376Y128650D02*
X497449Y128443D01*
G01X497259Y128836D02*
X497376Y128650D01*
G01X497101Y128993D02*
X497259Y128836D01*
G01X496915Y129109D02*
X497101Y128993D01*
G01X496708Y129181D02*
X496915Y129109D01*
G01X496490Y129206D02*
X496708Y129181D01*
G01X479522Y122058D02*
X479603Y121822D01*
G01X479394Y122273D02*
X479522Y122058D01*
G01X479225Y122459D02*
X479394Y122273D01*
G01X479023Y122614D02*
X479225Y122459D01*
G01X478795Y122737D02*
X479023Y122614D01*
G01X429997Y121386D02*
X430026Y121022D01*
G01X429914Y121736D02*
X429997Y121386D01*
G01X429781Y122057D02*
X429914Y121736D01*
G01X429608Y122335D02*
X429781Y122057D01*
G01X429407Y122563D02*
X429608Y122335D01*
G01X429189Y122737D02*
X429407Y122563D01*
G01X437084Y121386D02*
X437113Y121022D01*
G01X437000Y121736D02*
X437084Y121386D01*
G01X436868Y122057D02*
X437000Y121736D01*
G01X436695Y122335D02*
X436868Y122057D01*
G01X436494Y122563D02*
X436695Y122335D01*
G01X436275Y122737D02*
X436494Y122563D01*
G01X444171Y121386D02*
X444200Y121022D01*
G01X444087Y121736D02*
X444171Y121386D01*
G01X443955Y122057D02*
X444087Y121736D01*
G01X443782Y122335D02*
X443955Y122057D01*
G01X443580Y122563D02*
X443782Y122335D01*
G01X443362Y122737D02*
X443580Y122563D01*
G01X451257Y121386D02*
X451286Y121022D01*
G01X451174Y121736D02*
X451257Y121386D01*
G01X451041Y122057D02*
X451174Y121736D01*
G01X450868Y122335D02*
X451041Y122057D01*
G01X450667Y122563D02*
X450868Y122335D01*
G01X450449Y122737D02*
X450667Y122563D01*
G01X458344Y121386D02*
X458373Y121022D01*
G01X458260Y121736D02*
X458344Y121386D01*
G01X458128Y122057D02*
X458260Y121736D01*
G01X457955Y122335D02*
X458128Y122057D01*
G01X457754Y122563D02*
X457955Y122335D01*
G01X457535Y122737D02*
X457754Y122563D01*
G01X465430Y121386D02*
X465459Y121022D01*
G01X465347Y121736D02*
X465430Y121386D01*
G01X465214Y122057D02*
X465347Y121736D01*
G01X465042Y122335D02*
X465214Y122057D01*
G01X464840Y122563D02*
X465042Y122335D01*
G01X464622Y122737D02*
X464840Y122563D01*
G01X472517Y121386D02*
X472546Y121022D01*
G01X472433Y121736D02*
X472517Y121386D01*
G01X472301Y122057D02*
X472433Y121736D01*
G01X472128Y122335D02*
X472301Y122057D01*
G01X471927Y122563D02*
X472128Y122335D01*
G01X471708Y122737D02*
X471927Y122563D01*
G01X479604Y121386D02*
X479633Y121022D01*
G01X479520Y121736D02*
X479604Y121386D01*
G01X479388Y122057D02*
X479520Y121736D01*
G01X479215Y122335D02*
X479388Y122057D01*
G01X479013Y122563D02*
X479215Y122335D01*
G01X478795Y122737D02*
X479013Y122563D01*
G01X486690Y121386D02*
X486719Y121022D01*
G01X486607Y121736D02*
X486690Y121386D01*
G01X486474Y122057D02*
X486607Y121736D01*
G01X486301Y122335D02*
X486474Y122057D01*
G01X486100Y122563D02*
X486301Y122335D01*
G01X485882Y122737D02*
X486100Y122563D01*
G01X493777Y121386D02*
X493806Y121022D01*
G01X493693Y121736D02*
X493777Y121386D01*
G01X493561Y122057D02*
X493693Y121736D01*
G01X493388Y122335D02*
X493561Y122057D01*
G01X493187Y122563D02*
X493388Y122335D01*
G01X492968Y122737D02*
X493187Y122563D01*
G01X429555Y122515D02*
X429189Y122737D01*
G01X429817Y122234D02*
X429555Y122515D01*
G01X429974Y121921D02*
X429817Y122234D01*
G01X430026Y121593D02*
X429974Y121921D01*
G01X436641Y122515D02*
X436275Y122737D01*
G01X436904Y122234D02*
X436641Y122515D01*
G01X437060Y121921D02*
X436904Y122234D01*
G01X437113Y121593D02*
X437060Y121921D01*
G01X443728Y122515D02*
X443362Y122737D01*
G01X443990Y122234D02*
X443728Y122515D01*
G01X444147Y121921D02*
X443990Y122234D01*
G01X444200Y121593D02*
X444147Y121921D01*
G01X450814Y122515D02*
X450449Y122737D01*
G01X451077Y122234D02*
X450814Y122515D01*
G01X451233Y121921D02*
X451077Y122234D01*
G01X451286Y121593D02*
X451233Y121921D01*
G01X457901Y122515D02*
X457535Y122737D01*
G01X458163Y122234D02*
X457901Y122515D01*
G01X458320Y121921D02*
X458163Y122234D01*
G01X458373Y121593D02*
X458320Y121921D01*
G01X464988Y122515D02*
X464622Y122737D01*
G01X465250Y122234D02*
X464988Y122515D01*
G01X465407Y121921D02*
X465250Y122234D01*
G01X465459Y121593D02*
X465407Y121921D01*
G01X479625Y121717D02*
X479603Y121838D01*
G01X479633Y121593D02*
X479625Y121717D01*
G01X434602Y122563D02*
X434821Y122737D01*
G01X434401Y122335D02*
X434602Y122563D01*
G01X434228Y122057D02*
X434401Y122335D01*
G01X434096Y121736D02*
X434228Y122057D01*
G01X434012Y121386D02*
X434096Y121736D01*
G01X433983Y121022D02*
X434012Y121386D01*
G01X441689Y122563D02*
X441907Y122737D01*
G01X441488Y122335D02*
X441689Y122563D01*
G01X441315Y122057D02*
X441488Y122335D01*
G01X441182Y121736D02*
X441315Y122057D01*
G01X441099Y121386D02*
X441182Y121736D01*
G01X441070Y121022D02*
X441099Y121386D01*
G01X480589Y121630D02*
X480965Y121556D01*
G01X480269Y121844D02*
X480589Y121630D01*
G01X480056Y122163D02*
X480269Y121844D01*
G01X479981Y122540D02*
X480056Y122163D01*
G01X497090Y129355D02*
X496713Y129430D01*
G01X497409Y129141D02*
X497090Y129355D01*
G01X497623Y128822D02*
X497409Y129141D01*
G01X497698Y128445D02*
X497623Y128822D01*
G01X472074Y122515D02*
X471708Y122737D01*
G01X472337Y122234D02*
X472074Y122515D01*
G01X472493Y121921D02*
X472337Y122234D01*
G01X472546Y121593D02*
X472493Y121921D01*
G01X486247Y122515D02*
X485882Y122737D01*
G01X486510Y122234D02*
X486247Y122515D01*
G01X486667Y121921D02*
X486510Y122234D01*
G01X486719Y121593D02*
X486667Y121921D01*
G01X493334Y122515D02*
X492968Y122737D01*
G01X493597Y122234D02*
X493334Y122515D01*
G01X493753Y121921D02*
X493597Y122234D01*
G01X493806Y121593D02*
X493753Y121921D01*
G01X487991Y132178D02*
X487992Y132042D01*
G01X487990Y132314D02*
X487991Y132178D01*
G01X489688D02*
X489686Y132042D01*
G01X489689Y132314D02*
X489688Y132178D01*
G01X489689Y133725D02*
Y132314D01*
G01X476510Y121717D02*
X476532Y121838D01*
G01X476503Y121593D02*
X476510Y121717D01*
G01X448776Y122563D02*
X448994Y122737D01*
G01X448574Y122335D02*
X448776Y122563D01*
G01X448401Y122057D02*
X448574Y122335D01*
G01X448269Y121736D02*
X448401Y122057D01*
G01X448185Y121386D02*
X448269Y121736D01*
G01X448156Y121022D02*
X448185Y121386D01*
G01X455862Y122563D02*
X456080Y122737D01*
G01X455661Y122335D02*
X455862Y122563D01*
G01X455488Y122057D02*
X455661Y122335D01*
G01X455355Y121736D02*
X455488Y122057D01*
G01X455272Y121386D02*
X455355Y121736D01*
G01X455243Y121022D02*
X455272Y121386D01*
G01X462949Y122563D02*
X463167Y122737D01*
G01X462747Y122335D02*
X462949Y122563D01*
G01X462575Y122057D02*
X462747Y122335D01*
G01X462442Y121736D02*
X462575Y122057D01*
G01X462358Y121386D02*
X462442Y121736D01*
G01X462329Y121022D02*
X462358Y121386D01*
G01X470035Y122563D02*
X470254Y122737D01*
G01X469834Y122335D02*
X470035Y122563D01*
G01X469661Y122057D02*
X469834Y122335D01*
G01X469529Y121736D02*
X469661Y122057D01*
G01X469445Y121386D02*
X469529Y121736D01*
G01X469416Y121022D02*
X469445Y121386D01*
G01X477122Y122563D02*
X477340Y122737D01*
G01X476921Y122335D02*
X477122Y122563D01*
G01X476748Y122057D02*
X476921Y122335D01*
G01X476615Y121736D02*
X476748Y122057D01*
G01X476532Y121386D02*
X476615Y121736D01*
G01X476503Y121022D02*
X476532Y121386D01*
G01X484209Y122563D02*
X484427Y122737D01*
G01X484007Y122335D02*
X484209Y122563D01*
G01X483834Y122057D02*
X484007Y122335D01*
G01X483702Y121736D02*
X483834Y122057D01*
G01X483618Y121386D02*
X483702Y121736D01*
G01X483589Y121022D02*
X483618Y121386D01*
G01X480968Y129181D02*
X481189Y129206D01*
G01X480761Y129108D02*
X480968Y129181D01*
G01X480575Y128991D02*
X480761Y129108D01*
G01X480418Y128833D02*
X480575Y128991D01*
G01X480301Y128647D02*
X480418Y128833D01*
G01X480229Y128440D02*
X480301Y128647D01*
G01X480205Y128222D02*
X480229Y128440D01*
G01X434359Y122429D02*
X434821Y122737D01*
G01X434077Y122029D02*
X434359Y122429D01*
G01X433983Y121593D02*
X434077Y122029D01*
G01X441445Y122429D02*
X441907Y122737D01*
G01X441164Y122029D02*
X441445Y122429D01*
G01X441070Y121593D02*
X441164Y122029D01*
G01X448532Y122429D02*
X448994Y122737D01*
G01X448250Y122029D02*
X448532Y122429D01*
G01X448156Y121593D02*
X448250Y122029D01*
G01X497770Y121717D02*
X497792Y121838D01*
G01X497763Y121593D02*
X497770Y121717D01*
G01X491295Y122563D02*
X491514Y122737D01*
G01X491094Y122335D02*
X491295Y122563D01*
G01X490921Y122057D02*
X491094Y122335D01*
G01X490789Y121736D02*
X490921Y122057D01*
G01X490705Y121386D02*
X490789Y121736D01*
G01X490676Y121022D02*
X490705Y121386D01*
G01X498382Y122563D02*
X498600Y122737D01*
G01X498180Y122335D02*
X498382Y122563D01*
G01X498008Y122057D02*
X498180Y122335D01*
G01X497875Y121736D02*
X498008Y122057D01*
G01X497792Y121386D02*
X497875Y121736D01*
G01X497763Y121022D02*
X497792Y121386D01*
G01X455618Y122429D02*
X456080Y122737D01*
G01X455337Y122029D02*
X455618Y122429D01*
G01X455243Y121593D02*
X455337Y122029D01*
G01X462705Y122429D02*
X463167Y122737D01*
G01X462424Y122029D02*
X462705Y122429D01*
G01X462329Y121593D02*
X462424Y122029D01*
G01X469792Y122429D02*
X470254Y122737D01*
G01X469510Y122029D02*
X469792Y122429D01*
G01X469416Y121593D02*
X469510Y122029D01*
G01X483965Y122429D02*
X484427Y122737D01*
G01X483683Y122029D02*
X483965Y122429D01*
G01X483589Y121593D02*
X483683Y122029D01*
G01X491052Y122429D02*
X491514Y122737D01*
G01X490770Y122029D02*
X491052Y122429D01*
G01X490676Y121593D02*
X490770Y122029D01*
G01X477114Y122616D02*
X477340Y122737D01*
G01X476913Y122462D02*
X477114Y122616D01*
G01X476744Y122276D02*
X476913Y122462D01*
G01X476614Y122060D02*
X476744Y122276D01*
G01X476532Y121822D02*
X476614Y122060D01*
G01X498374Y122616D02*
X498600Y122737D01*
G01X498173Y122462D02*
X498374Y122616D01*
G01X498004Y122276D02*
X498173Y122462D01*
G01X497874Y122060D02*
X498004Y122276D01*
G01X497792Y121822D02*
X497874Y122060D01*
G01X492530Y137225D02*
G03I-3691J0D01*
G01X493139D02*
G03I-4300J0D01*
G01X493268D02*
G03I-4429J0D01*
G01X484072Y136376D02*
G03X487991Y132457I4768J849D01*
G01X489688D02*
G03X493607Y136376I-849J4768D01*
G01X493839Y137205D02*
G03I-5020J0D01*
G01X497189Y137225D02*
G03I-8350J0D01*
G01X492973Y122745D02*
G03X491509I-732J-1394D01*
G01X500060D02*
G03X498595I-733J-1394D01*
G01X471969Y131496D02*
G03I-709J0D01*
G01X464882Y130709D02*
G03I-708J0D01*
G01Y126378D02*
G03I-708J0D01*
G01X471969Y125985D02*
G03I-709J0D01*
G01Y121654D02*
G03I-709J0D01*
G01X464626Y122745D02*
G03X463162I-732J-1394D01*
G01X471713D02*
G03X470249I-732J-1394D01*
G01X478800D02*
G03X477336I-732J-1394D01*
G01X485886D02*
G03X484422I-732J-1394D01*
G01X457796Y131496D02*
G03I-709J0D01*
G01X450709Y130709D02*
G03I-709J0D01*
G01Y126378D02*
G03I-709J0D01*
G01X457796Y125985D02*
G03I-709J0D01*
G01Y121654D02*
G03I-709J0D01*
G01X450453Y122745D02*
G03X448989I-732J-1394D01*
G01X457540D02*
G03X456076I-732J-1394D01*
G01X443622Y131496D02*
G03I-708J0D01*
G01X436536Y130709D02*
G03I-709J0D01*
G01Y126378D02*
G03I-709J0D01*
G01X443622Y125985D02*
G03I-708J0D01*
G01Y121654D02*
G03I-708J0D01*
G01X443367Y122745D02*
G03X441903I-732J-1394D01*
G01X429449Y131496D02*
G03I-708J0D01*
G01Y125985D02*
G03I-708J0D01*
G01Y121654D02*
G03I-708J0D01*
G01X429193Y122745D02*
G03X427729I-732J-1394D01*
G01X436280D02*
G03X434816I-732J-1394D01*
G01X497698Y128445D02*
X497474Y128222D01*
G01X496490Y129206D02*
X496713Y129430D01*
G01X479603Y115256D02*
X478422Y114075D01*
G01X481189Y121779D02*
X480965Y121556D01*
G01X479981Y122540D02*
X480205Y122763D01*
G01X472517Y115256D02*
X471335Y114075D01*
G01X490659Y135405D02*
X489689Y133725D01*
G01X487989D02*
X489689Y140725D01*
G01X487992Y132042D02*
X489686Y142407D01*
G01X482910Y187911D02*
X481690Y118012D01*
G01X481926Y187911D02*
X480705Y118012D01*
G01X497792Y115256D02*
Y125886D01*
G01X497763Y115650D02*
Y121593D01*
G01X497698Y122540D02*
Y128445D01*
G01X497474Y122763D02*
Y128222D01*
G01X496490Y121779D02*
Y129206D01*
G01X493806Y121593D02*
Y115650D01*
G01X490676D02*
Y121593D01*
G01X489264Y134625D02*
Y135475D01*
G01X488414D02*
Y134625D01*
G01X487989Y133725D02*
X487990Y132314D01*
G01X486719Y121593D02*
Y115650D01*
G01X483589D02*
Y121593D01*
G01X481189Y121779D02*
Y129206D01*
G01X480205Y128222D02*
Y122763D01*
G01X479981Y128445D02*
Y122540D01*
G01X479633Y121593D02*
Y115650D01*
G01X479603Y125886D02*
Y115256D01*
G01X476532D02*
Y125886D01*
G01X476503Y115650D02*
Y121593D01*
G01X475139Y209646D02*
Y113091D01*
G01X473956Y201805D02*
Y113091D01*
G01X472546Y121593D02*
Y115650D01*
G01X472517Y118012D02*
Y115256D01*
G01X469446Y118012D02*
Y115256D01*
G01X469416Y121593D02*
Y115650D01*
G01X495233Y187911D02*
X496454Y118012D01*
G01X495469D02*
X494249Y187911D01*
G01X489686Y132042D02*
X487992Y142407D01*
G01X489689Y133725D02*
X487989Y140725D01*
G01X465459Y121593D02*
Y115650D01*
G01X462329Y121593D02*
Y115650D01*
G01X458373Y121593D02*
Y115650D01*
G01X455243Y121593D02*
Y115650D01*
G01X451286Y121593D02*
Y115650D01*
G01X448156Y121593D02*
Y115650D01*
G01X444200Y121593D02*
Y115650D01*
G01X441070Y121593D02*
Y115650D01*
G01X437113Y121593D02*
Y115650D01*
G01X433983Y121593D02*
Y115650D01*
G01X430026Y121593D02*
Y115650D01*
G01X487989Y133725D02*
X487019Y135405D01*
G01X497474Y122763D02*
X497698Y122540D01*
G01X496714Y121556D02*
X496490Y121779D01*
G01X497792Y115256D02*
X498973Y114075D01*
G01X480965Y129430D02*
X481189Y129206D01*
G01X480205Y128222D02*
X479981Y128445D01*
G01X476532Y115256D02*
X477713Y114075D01*
G01X469446Y115256D02*
X470627Y114075D01*
G01X488414Y134625D02*
X489264D01*
G01X496714Y129430D02*
X480965D01*
G01X496490Y129206D02*
X481189D01*
G01X480205Y128222D02*
X497474D01*
G01X479603Y125886D02*
X497792D01*
G01X475139D02*
X476532D01*
G01X497474Y122763D02*
X480205D01*
G01X492968Y122737D02*
X498600D01*
G01X478795D02*
X484427D01*
G01X471708D02*
X477340D01*
G01X434821D02*
X429189D01*
G01X441907D02*
X436275D01*
G01X448994D02*
X443362D01*
G01X456080D02*
X450449D01*
G01X463167D02*
X457535D01*
G01X470254D02*
X464622D01*
G01X491514D02*
X485882D01*
G01X496490Y121779D02*
X481189D01*
G01X480965Y121556D02*
X496714D01*
G01X476503Y118085D02*
X475139D01*
G01X483589D02*
X479633D01*
G01X490676D02*
X486719D01*
G01X497763D02*
X493806D01*
G01X501517Y116437D02*
X475139D01*
G01X472517Y115256D02*
X469446D01*
G01X479603D02*
X476532D01*
G01X500863D02*
X497792D01*
G01X477713Y114075D02*
X478422D01*
G01X471335D02*
X470627D01*
G01X499682D02*
X498973D01*
G01X475139Y113091D02*
X501517D01*
G01X489686Y132042D02*
X489122Y132038D01*
G01X497623Y146179D02*
X497698Y146555D01*
G01X497409Y145860D02*
X497623Y146179D01*
G01X497090Y145646D02*
X497409Y145860D01*
G01X496714Y145571D02*
X497090Y145646D01*
G01X493886Y136376D02*
X493750Y136375D01*
G01X494022Y136378D02*
X493886Y136376D01*
G01X483792Y138074D02*
X483657Y138072D01*
G01X483928Y138075D02*
X483792Y138074D01*
G01X489404Y142410D02*
X489686Y142407D01*
G01X489122Y142412D02*
X489404Y142410D01*
G01X488557Y142412D02*
X489122D01*
G01X483928Y136375D02*
X485339D01*
G01X483792Y136376D02*
X483928Y136375D01*
G01X483657Y136378D02*
X483792Y136376D01*
G01X493750Y138075D02*
X492339D01*
G01X493886Y138074D02*
X493750Y138075D01*
G01X494022Y138072D02*
X493886Y138074D01*
G01X480056Y152838D02*
X479981Y152461D01*
G01X480269Y153157D02*
X480056Y152838D01*
G01X480589Y153370D02*
X480269Y153157D01*
G01X480965Y153445D02*
X480589Y153370D01*
G01X497449Y146558D02*
X497474Y146779D01*
G01X497376Y146351D02*
X497449Y146558D01*
G01X497259Y146165D02*
X497376Y146351D01*
G01X497101Y146008D02*
X497259Y146165D01*
G01X496915Y145892D02*
X497101Y146008D01*
G01X496708Y145819D02*
X496915Y145892D01*
G01X496490Y145795D02*
X496708Y145819D01*
G01X480230Y152459D02*
X480205Y152238D01*
G01X480303Y152666D02*
X480230Y152459D01*
G01X480420Y152851D02*
X480303Y152666D01*
G01X480578Y153009D02*
X480420Y152851D01*
G01X480764Y153125D02*
X480578Y153009D01*
G01X480971Y153197D02*
X480764Y153125D01*
G01X481189Y153222D02*
X480971Y153197D01*
G01X497449Y152459D02*
X497474Y152238D01*
G01X497376Y152666D02*
X497449Y152459D01*
G01X497259Y152851D02*
X497376Y152666D01*
G01X497101Y153009D02*
X497259Y152851D01*
G01X496915Y153125D02*
X497101Y153009D01*
G01X496708Y153197D02*
X496915Y153125D01*
G01X496490Y153222D02*
X496708Y153197D01*
G01X471483Y202464D02*
X471504Y202526D01*
G01X471445Y202405D02*
X471483Y202464D01*
G01X471391Y202353D02*
X471445Y202405D01*
G01X471324Y202309D02*
X471391Y202353D01*
G01X471247Y202275D02*
X471324Y202309D01*
G01X471164Y202254D02*
X471247Y202275D01*
G01X457310Y202464D02*
X457330Y202526D01*
G01X457272Y202405D02*
X457310Y202464D01*
G01X457218Y202353D02*
X457272Y202405D01*
G01X457151Y202309D02*
X457218Y202353D01*
G01X457074Y202275D02*
X457151Y202309D01*
G01X456991Y202254D02*
X457074Y202275D01*
G01X443137Y202464D02*
X443157Y202526D01*
G01X443099Y202405D02*
X443137Y202464D01*
G01X443045Y202353D02*
X443099Y202405D01*
G01X442978Y202309D02*
X443045Y202353D01*
G01X442901Y202275D02*
X442978Y202309D01*
G01X442817Y202254D02*
X442901Y202275D01*
G01X428964Y202464D02*
X428984Y202526D01*
G01X428925Y202405D02*
X428964Y202464D01*
G01X428872Y202353D02*
X428925Y202405D01*
G01X428805Y202309D02*
X428872Y202353D01*
G01X428727Y202275D02*
X428805Y202309D01*
G01X428644Y202254D02*
X428727Y202275D01*
G01X472301Y190749D02*
X472285Y190748D01*
G01X472317Y190751D02*
X472301Y190749D01*
G01X472332Y190755D02*
X472317Y190751D01*
G01X458294Y200747D02*
X458309Y200821D01*
G01X458252Y200682D02*
X458294Y200747D01*
G01X458188Y200640D02*
X458252Y200682D01*
G01X458112Y200624D02*
X458188Y200640D01*
G01X444121Y200747D02*
X444135Y200821D01*
G01X444079Y200682D02*
X444121Y200747D01*
G01X444015Y200640D02*
X444079Y200682D01*
G01X443939Y200624D02*
X444015Y200640D01*
G01X429948Y200747D02*
X429962Y200821D01*
G01X429905Y200682D02*
X429948Y200747D01*
G01X429842Y200640D02*
X429905Y200682D01*
G01X429765Y200624D02*
X429842Y200640D01*
G01X497111Y195195D02*
X497186Y195571D01*
G01X496898Y194875D02*
X497111Y195195D01*
G01X496578Y194662D02*
X496898Y194875D01*
G01X496202Y194587D02*
X496578Y194662D01*
G01X479544Y205791D02*
X479469Y205414D01*
G01X479757Y206110D02*
X479544Y205791D01*
G01X480077Y206323D02*
X479757Y206110D01*
G01X480453Y206398D02*
X480077Y206323D01*
G01X482005Y188283D02*
X481926Y187911D01*
G01X482220Y188596D02*
X482005Y188283D01*
G01X482537Y188805D02*
X482220Y188596D01*
G01X482910Y188878D02*
X482537Y188805D01*
G01X471667Y201438D02*
X471685Y201496D01*
G01X471633Y201384D02*
X471667Y201438D01*
G01X471584Y201333D02*
X471633Y201384D01*
G01X471524Y201290D02*
X471584Y201333D01*
G01X471454Y201255D02*
X471524Y201290D01*
G01X471377Y201231D02*
X471454Y201255D01*
G01X471297Y201218D02*
X471377Y201231D01*
G01X429147Y201438D02*
X429165Y201496D01*
G01X429113Y201384D02*
X429147Y201438D01*
G01X429064Y201333D02*
X429113Y201384D01*
G01X429004Y201290D02*
X429064Y201333D01*
G01X428934Y201255D02*
X429004Y201290D01*
G01X428857Y201231D02*
X428934Y201255D01*
G01X428778Y201218D02*
X428857Y201231D01*
G01X489249Y199225D02*
X489336Y199410D01*
G01X489160Y199062D02*
X489249Y199225D01*
G01X489069Y198919D02*
X489160Y199062D01*
G01X488975Y198798D02*
X489069Y198919D01*
G01X488878Y198701D02*
X488975Y198798D01*
G01X488777Y198629D02*
X488878Y198701D01*
G01X488676Y198586D02*
X488777Y198629D01*
G01X488579Y198573D02*
X488676Y198586D01*
G01X497006Y195505D02*
X497031Y195726D01*
G01X496933Y195298D02*
X497006Y195505D01*
G01X496816Y195112D02*
X496933Y195298D01*
G01X496658Y194955D02*
X496816Y195112D01*
G01X496472Y194839D02*
X496658Y194955D01*
G01X496265Y194766D02*
X496472Y194839D01*
G01X496047Y194742D02*
X496265Y194766D01*
G01X471155Y202252D02*
X471164Y202254D01*
G01X471147Y202251D02*
X471155Y202252D01*
G01X471139Y202250D02*
X471147Y202251D01*
G01X471131Y202249D02*
X471139Y202250D01*
G01X471123Y202248D02*
X471131Y202249D01*
G01X471116Y202247D02*
X471123Y202248D01*
G01X456982Y202252D02*
X456991Y202254D01*
G01X456974Y202251D02*
X456982Y202252D01*
G01X456966Y202250D02*
X456974Y202251D01*
G01X456958Y202249D02*
X456966Y202250D01*
G01X456949Y202248D02*
X456958Y202249D01*
G01X456943Y202247D02*
X456949Y202248D01*
G01X442809Y202252D02*
X442817Y202254D01*
G01X442801Y202251D02*
X442809Y202252D01*
G01X442792Y202250D02*
X442801Y202251D01*
G01X442784Y202249D02*
X442792Y202250D01*
G01X442776Y202248D02*
X442784Y202249D01*
G01X442769Y202247D02*
X442776Y202248D01*
G01X428636Y202252D02*
X428644Y202254D01*
G01X428627Y202251D02*
X428636Y202252D01*
G01X428619Y202250D02*
X428627Y202251D01*
G01X428611Y202249D02*
X428619Y202250D01*
G01X428603Y202248D02*
X428611Y202249D01*
G01X428596Y202247D02*
X428603Y202248D01*
G01X482296Y187918D02*
X482482Y187917D01*
G01X482139Y187918D02*
X482296D01*
G01X495208Y187915D02*
X495233Y187911D01*
G01X495135Y187917D02*
X495208Y187915D01*
G01X495018Y187918D02*
X495135Y187917D01*
G01X479649Y195505D02*
X479624Y195726D01*
G01X479722Y195298D02*
X479649Y195505D01*
G01X479839Y195112D02*
X479722Y195298D01*
G01X479997Y194955D02*
X479839Y195112D01*
G01X480183Y194839D02*
X479997Y194955D01*
G01X480390Y194766D02*
X480183Y194839D01*
G01X480608Y194742D02*
X480390Y194766D01*
G01X497006Y205480D02*
X497031Y205259D01*
G01X496933Y205687D02*
X497006Y205480D01*
G01X496816Y205873D02*
X496933Y205687D01*
G01X496658Y206030D02*
X496816Y205873D01*
G01X496472Y206146D02*
X496658Y206030D01*
G01X496265Y206219D02*
X496472Y206146D01*
G01X496047Y206243D02*
X496265Y206219D01*
G01X432323Y190836D02*
X432295Y190882D01*
G01X432357Y190798D02*
X432323Y190836D01*
G01X432397Y190770D02*
X432357Y190798D01*
G01X432442Y190754D02*
X432397Y190770D01*
G01X432487Y190748D02*
X432442Y190754D01*
G01X446496Y190836D02*
X446468Y190882D01*
G01X446530Y190798D02*
X446496Y190836D01*
G01X446570Y190770D02*
X446530Y190798D01*
G01X446615Y190754D02*
X446570Y190770D01*
G01X446660Y190748D02*
X446615Y190754D01*
G01X460670Y190836D02*
X460642Y190882D01*
G01X460703Y190798D02*
X460670Y190836D01*
G01X460744Y190770D02*
X460703Y190798D01*
G01X460788Y190754D02*
X460744Y190770D01*
G01X460833Y190748D02*
X460788Y190754D01*
G01X440561Y200763D02*
X440553Y200821D01*
G01X440584Y200714D02*
X440561Y200763D01*
G01X440617Y200675D02*
X440584Y200714D01*
G01X440658Y200646D02*
X440617Y200675D01*
G01X440703Y200629D02*
X440658Y200646D01*
G01X440750Y200624D02*
X440703Y200629D01*
G01X454735Y200763D02*
X454726Y200821D01*
G01X454757Y200714D02*
X454735Y200763D01*
G01X454790Y200675D02*
X454757Y200714D01*
G01X454831Y200646D02*
X454790Y200675D01*
G01X454877Y200629D02*
X454831Y200646D01*
G01X454923Y200624D02*
X454877Y200629D01*
G01X468908Y200763D02*
X468899Y200821D01*
G01X468930Y200714D02*
X468908Y200763D01*
G01X468963Y200675D02*
X468930Y200714D01*
G01X469004Y200646D02*
X468963Y200675D01*
G01X469050Y200629D02*
X469004Y200646D01*
G01X469096Y200624D02*
X469050Y200629D01*
G01X488483Y198586D02*
X488382Y198629D01*
G01X488579Y198573D02*
X488483Y198586D01*
G01X495181Y188211D02*
X495233Y187911D01*
G01X495039Y188481D02*
X495181Y188211D01*
G01X494822Y188694D02*
X495039Y188481D01*
G01X494550Y188831D02*
X494822Y188694D01*
G01X494249Y188878D02*
X494550Y188831D01*
G01X438807Y201438D02*
X438789Y201496D01*
G01X438841Y201384D02*
X438807Y201438D01*
G01X438890Y201333D02*
X438841Y201384D01*
G01X438950Y201290D02*
X438890Y201333D01*
G01X439020Y201255D02*
X438950Y201290D01*
G01X439097Y201231D02*
X439020Y201255D01*
G01X439177Y201218D02*
X439097Y201231D01*
G01X452981Y201438D02*
X452962Y201496D01*
G01X453014Y201384D02*
X452981Y201438D01*
G01X453063Y201333D02*
X453014Y201384D01*
G01X453124Y201290D02*
X453063Y201333D01*
G01X453194Y201255D02*
X453124Y201290D01*
G01X453270Y201231D02*
X453194Y201255D01*
G01X453350Y201218D02*
X453270Y201231D01*
G01X467154Y201438D02*
X467135Y201496D01*
G01X467188Y201384D02*
X467154Y201438D01*
G01X467237Y201333D02*
X467188Y201384D01*
G01X467297Y201290D02*
X467237Y201333D01*
G01X467367Y201255D02*
X467297Y201290D01*
G01X467443Y201231D02*
X467367Y201255D01*
G01X467523Y201218D02*
X467443Y201231D01*
G01X439350Y202248D02*
X439358Y202247D01*
G01X439341Y202249D02*
X439350Y202248D01*
G01X439333Y202250D02*
X439341Y202249D01*
G01X439325Y202251D02*
X439333Y202250D01*
G01X439317Y202252D02*
X439325Y202251D01*
G01X439310Y202254D02*
X439317Y202252D01*
G01X453523Y202248D02*
X453531Y202247D01*
G01X453515Y202249D02*
X453523Y202248D01*
G01X453507Y202250D02*
X453515Y202249D01*
G01X453498Y202251D02*
X453507Y202250D01*
G01X453490Y202252D02*
X453498Y202251D01*
G01X453483Y202254D02*
X453490Y202252D01*
G01X467696Y202248D02*
X467705Y202247D01*
G01X467688Y202249D02*
X467696Y202248D01*
G01X467680Y202250D02*
X467688Y202249D01*
G01X467672Y202251D02*
X467680Y202250D01*
G01X467663Y202252D02*
X467672Y202251D01*
G01X467657Y202254D02*
X467663Y202252D01*
G01X439042Y196164D02*
X438985Y196457D01*
G01X439214Y195905D02*
X439042Y196164D01*
G01X439477Y195730D02*
X439214Y195905D01*
G01X439784Y195670D02*
X439477Y195730D01*
G01X453215Y196164D02*
X453158Y196457D01*
G01X453387Y195905D02*
X453215Y196164D01*
G01X453650Y195730D02*
X453387Y195905D01*
G01X453958Y195670D02*
X453650Y195730D01*
G01X467389Y196164D02*
X467331Y196457D01*
G01X467560Y195905D02*
X467389Y196164D01*
G01X467824Y195730D02*
X467560Y195905D01*
G01X468131Y195670D02*
X467824Y195730D01*
G01X439426Y196264D02*
X439373Y196457D01*
G01X439576Y196118D02*
X439426Y196264D01*
G01X439784Y196063D02*
X439576Y196118D01*
G01X453599Y196264D02*
X453546Y196457D01*
G01X453749Y196118D02*
X453599Y196264D01*
G01X453958Y196063D02*
X453749Y196118D01*
G01X467772Y196264D02*
X467719Y196457D01*
G01X467922Y196118D02*
X467772Y196264D01*
G01X468131Y196063D02*
X467922Y196118D01*
G01X469080Y190749D02*
X469096Y190748D01*
G01X469064Y190751D02*
X469080Y190749D01*
G01X469049Y190755D02*
X469064Y190751D01*
G01X469008Y190761D02*
X469049Y190755D01*
G01X468968Y190776D02*
X469008Y190761D01*
G01X468931Y190801D02*
X468968Y190776D01*
G01X468899Y190834D02*
X468931Y190801D01*
G01X484546Y198803D02*
X484596Y198923D01*
G01X484491Y198706D02*
X484546Y198803D01*
G01X484430Y198634D02*
X484491Y198706D01*
G01X484367Y198590D02*
X484430Y198634D01*
G01X484299Y198573D02*
X484367Y198590D01*
G01X484226Y198585D02*
X484299Y198573D01*
G01X484149Y198627D02*
X484226Y198585D01*
G01X484068Y198698D02*
X484149Y198627D01*
G01X483987Y198795D02*
X484068Y198698D01*
G01X483904Y198916D02*
X483987Y198795D01*
G01X487999Y199062D02*
X487910Y199225D01*
G01X488090Y198919D02*
X487999Y199062D01*
G01X439748Y196270D02*
X439828Y196260D01*
G01X439672Y196288D02*
X439748Y196270D01*
G01X439603Y196313D02*
X439672Y196288D01*
G01X439543Y196343D02*
X439603Y196313D01*
G01X439494Y196379D02*
X439543Y196343D01*
G01X439460Y196417D02*
X439494Y196379D01*
G01X439440Y196457D02*
X439460Y196417D01*
G01X439823Y197005D02*
X439902Y196995D01*
G01X439747Y197023D02*
X439823Y197005D01*
G01X439678Y197048D02*
X439747Y197023D01*
G01X439618Y197078D02*
X439678Y197048D01*
G01X439569Y197113D02*
X439618Y197078D01*
G01X439534Y197152D02*
X439569Y197113D01*
G01X439515Y197192D02*
X439534Y197152D01*
G01X453921Y196270D02*
X454001Y196260D01*
G01X453845Y196288D02*
X453921Y196270D01*
G01X453776Y196313D02*
X453845Y196288D01*
G01X453716Y196343D02*
X453776Y196313D01*
G01X453668Y196379D02*
X453716Y196343D01*
G01X453633Y196417D02*
X453668Y196379D01*
G01X453613Y196457D02*
X453633Y196417D01*
G01X453996Y197005D02*
X454076Y196995D01*
G01X453920Y197023D02*
X453996Y197005D01*
G01X453851Y197048D02*
X453920Y197023D01*
G01X453791Y197078D02*
X453851Y197048D01*
G01X453742Y197113D02*
X453791Y197078D01*
G01X453708Y197152D02*
X453742Y197113D01*
G01X453688Y197192D02*
X453708Y197152D01*
G01X468094Y196270D02*
X468174Y196260D01*
G01X468019Y196288D02*
X468094Y196270D01*
G01X467949Y196313D02*
X468019Y196288D01*
G01X467889Y196343D02*
X467949Y196313D01*
G01X467841Y196379D02*
X467889Y196343D01*
G01X467806Y196417D02*
X467841Y196379D01*
G01X467786Y196457D02*
X467806Y196417D01*
G01X468169Y197005D02*
X468249Y196995D01*
G01X468093Y197023D02*
X468169Y197005D01*
G01X468024Y197048D02*
X468093Y197023D01*
G01X467964Y197078D02*
X468024Y197048D01*
G01X467916Y197113D02*
X467964Y197078D01*
G01X467881Y197152D02*
X467916Y197113D01*
G01X467861Y197192D02*
X467881Y197152D01*
G01X439226Y202275D02*
X439310Y202254D01*
G01X439148Y202310D02*
X439226Y202275D01*
G01X439081Y202354D02*
X439148Y202310D01*
G01X439028Y202406D02*
X439081Y202354D01*
G01X438990Y202465D02*
X439028Y202406D01*
G01X438970Y202526D02*
X438990Y202465D01*
G01X428813Y201041D02*
X428818Y200940D01*
G01X428800Y201136D02*
X428813Y201041D01*
G01X428778Y201218D02*
X428800Y201136D01*
G01X429198Y201141D02*
X429195Y201241D01*
G01X429199Y201040D02*
X429198Y201141D01*
G01X488483Y198586D02*
X488579Y198573D01*
G01X488382Y198629D02*
X488483Y198586D01*
G01X488281Y198701D02*
X488382Y198629D01*
G01X488184Y198798D02*
X488281Y198701D01*
G01X488090Y198919D02*
X488184Y198798D01*
G01X487999Y199062D02*
X488090Y198919D01*
G01X487910Y199225D02*
X487999Y199062D01*
G01X487823Y199410D02*
X487910Y199225D01*
G01X453399Y202275D02*
X453483Y202254D01*
G01X453321Y202310D02*
X453399Y202275D01*
G01X453254Y202354D02*
X453321Y202310D01*
G01X453201Y202406D02*
X453254Y202354D01*
G01X453163Y202465D02*
X453201Y202406D01*
G01X453144Y202526D02*
X453163Y202465D01*
G01X467573Y202275D02*
X467657Y202254D01*
G01X467494Y202310D02*
X467573Y202275D01*
G01X467428Y202354D02*
X467494Y202310D01*
G01X467374Y202406D02*
X467428Y202354D01*
G01X467337Y202465D02*
X467374Y202406D01*
G01X467317Y202526D02*
X467337Y202465D01*
G01X442987Y201041D02*
X442991Y200940D01*
G01X442973Y201136D02*
X442987Y201041D01*
G01X442951Y201218D02*
X442973Y201136D01*
G01X457160Y201041D02*
X457165Y200940D01*
G01X457146Y201136D02*
X457160Y201041D01*
G01X457124Y201218D02*
X457146Y201136D01*
G01X433588Y190764D02*
X433663Y190748D01*
G01X433524Y190806D02*
X433588Y190764D01*
G01X433481Y190871D02*
X433524Y190806D01*
G01X433466Y190945D02*
X433481Y190871D01*
G01X440675Y190764D02*
X440750Y190748D01*
G01X440610Y190806D02*
X440675Y190764D01*
G01X440568Y190871D02*
X440610Y190806D01*
G01X440553Y190945D02*
X440568Y190871D01*
G01X447761Y190764D02*
X447836Y190748D01*
G01X447697Y190806D02*
X447761Y190764D01*
G01X447655Y190871D02*
X447697Y190806D01*
G01X447639Y190945D02*
X447655Y190871D01*
G01X454848Y190764D02*
X454923Y190748D01*
G01X454783Y190806D02*
X454848Y190764D01*
G01X454741Y190871D02*
X454783Y190806D01*
G01X454726Y190945D02*
X454741Y190871D01*
G01X461934Y190764D02*
X462009Y190748D01*
G01X461870Y190806D02*
X461934Y190764D01*
G01X461828Y190871D02*
X461870Y190806D01*
G01X461813Y190945D02*
X461828Y190871D01*
G01X429187Y201334D02*
X429195Y201241D01*
G01X429177Y201419D02*
X429187Y201334D01*
G01X429165Y201496D02*
X429177Y201419D01*
G01X439740Y196073D02*
X439828Y196063D01*
G01X439659Y196103D02*
X439740Y196073D01*
G01X439586Y196149D02*
X439659Y196103D01*
G01X439524Y196213D02*
X439586Y196149D01*
G01X439478Y196287D02*
X439524Y196213D01*
G01X439449Y196370D02*
X439478Y196287D01*
G01X439440Y196457D02*
X439449Y196370D01*
G01X443351Y201419D02*
X443339Y201496D01*
G01X443361Y201334D02*
X443351Y201419D01*
G01X443369Y201241D02*
X443361Y201334D01*
G01X457524Y201419D02*
X457512Y201496D01*
G01X457534Y201334D02*
X457524Y201419D01*
G01X457542Y201241D02*
X457534Y201334D01*
G01X471697Y201419D02*
X471685Y201496D01*
G01X471707Y201334D02*
X471697Y201419D01*
G01X471715Y201241D02*
X471707Y201334D01*
G01X471319Y201136D02*
X471297Y201218D01*
G01X471333Y201041D02*
X471319Y201136D01*
G01X471338Y200940D02*
X471333Y201041D01*
G01X438373Y201037D02*
X438374Y200940D01*
G01X438372Y201138D02*
X438373Y201037D01*
G01X438371Y201241D02*
X438372Y201138D01*
G01X443371Y201141D02*
X443369Y201241D01*
G01X443372Y201040D02*
X443371Y201141D01*
G01X452546Y201037D02*
X452547Y200940D01*
G01X452546Y201138D02*
Y201037D01*
G01X452544Y201241D02*
X452546Y201138D01*
G01X457544Y201141D02*
X457542Y201241D01*
G01X457546Y201040D02*
X457544Y201141D01*
G01X466719Y201037D02*
X466720Y200940D01*
G01X466719Y201138D02*
Y201037D01*
G01X466718Y201241D02*
X466719Y201138D01*
G01X438755Y201043D02*
Y196457D01*
G01X438756Y201144D02*
X438755Y201043D01*
G01X438759Y201241D02*
X438756Y201144D01*
G01X452928Y201043D02*
Y196457D01*
G01X452930Y201144D02*
X452928Y201043D01*
G01X452932Y201241D02*
X452930Y201144D01*
G01X439155Y201136D02*
X439177Y201218D01*
G01X439141Y201041D02*
X439155Y201136D01*
G01X439136Y200940D02*
X439141Y201041D01*
G01X453328Y201136D02*
X453350Y201218D01*
G01X453314Y201041D02*
X453328Y201136D01*
G01X453309Y200940D02*
X453314Y201041D01*
G01X438767Y201333D02*
X438759Y201241D01*
G01X438777Y201419D02*
X438767Y201333D01*
G01X438789Y201496D02*
X438777Y201419D01*
G01X429841Y190764D02*
X429765Y190748D01*
G01X429905Y190807D02*
X429841Y190764D01*
G01X429948Y190871D02*
X429905Y190807D01*
G01X429962Y190945D02*
X429948Y190871D01*
G01X493423Y199226D02*
X493508Y199410D01*
G01X493341Y199064D02*
X493423Y199226D01*
G01X493259Y198923D02*
X493341Y199064D01*
G01X493179Y198803D02*
X493259Y198923D01*
G01X493099Y198706D02*
X493179Y198803D01*
G01X493020Y198634D02*
X493099Y198706D01*
G01X492945Y198590D02*
X493020Y198634D01*
G01X492874Y198573D02*
X492945Y198590D01*
G01X492804Y198585D02*
X492874Y198573D01*
G01X492737Y198626D02*
X492804Y198585D01*
G01X492674Y198698D02*
X492737Y198626D01*
G01X492617Y198795D02*
X492674Y198698D01*
G01X492565Y198916D02*
X492617Y198795D01*
G01X492519Y199059D02*
X492565Y198916D01*
G01X492477Y199224D02*
X492519Y199059D01*
G01X492439Y199410D02*
X492477Y199224D01*
G01X480589Y145646D02*
X480965Y145571D01*
G01X480269Y145859D02*
X480589Y145646D01*
G01X480056Y146179D02*
X480269Y145859D01*
G01X479981Y146555D02*
X480056Y146179D01*
G01X480077Y194662D02*
X480453Y194587D01*
G01X479757Y194875D02*
X480077Y194662D01*
G01X479544Y195194D02*
X479757Y194875D01*
G01X479469Y195571D02*
X479544Y195194D01*
G01X497090Y153370D02*
X496713Y153445D01*
G01X497409Y153157D02*
X497090Y153370D01*
G01X497623Y152838D02*
X497409Y153157D01*
G01X497698Y152461D02*
X497623Y152838D01*
G01X496578Y206323D02*
X496202Y206398D01*
G01X496898Y206110D02*
X496578Y206323D01*
G01X497111Y205791D02*
X496898Y206110D01*
G01X497186Y205414D02*
X497111Y205791D01*
G01X469001Y199979D02*
X469045Y199961D01*
G01X468961Y200008D02*
X469001Y199979D01*
G01X468929Y200047D02*
X468961Y200008D01*
G01X468907Y200095D02*
X468929Y200047D01*
G01X468899Y200151D02*
X468907Y200095D01*
G01X480968Y145820D02*
X481189Y145795D01*
G01X480761Y145893D02*
X480968Y145820D01*
G01X480575Y146010D02*
X480761Y145893D01*
G01X480418Y146168D02*
X480575Y146010D01*
G01X480301Y146354D02*
X480418Y146168D01*
G01X480229Y146561D02*
X480301Y146354D01*
G01X480205Y146779D02*
X480229Y146561D01*
G01X453914Y196073D02*
X454001Y196063D01*
G01X453832Y196103D02*
X453914Y196073D01*
G01X453759Y196149D02*
X453832Y196103D01*
G01X453697Y196213D02*
X453759Y196149D01*
G01X453651Y196287D02*
X453697Y196213D01*
G01X453623Y196370D02*
X453651Y196287D01*
G01X453613Y196457D02*
X453623Y196370D01*
G01X468087Y196073D02*
X468174Y196063D01*
G01X468005Y196103D02*
X468087Y196073D01*
G01X467932Y196149D02*
X468005Y196103D01*
G01X467870Y196213D02*
X467932Y196149D01*
G01X467824Y196287D02*
X467870Y196213D01*
G01X467796Y196370D02*
X467824Y196287D01*
G01X467786Y196457D02*
X467796Y196370D01*
G01X471718Y201141D02*
X471715Y201241D01*
G01X471719Y201040D02*
X471718Y201141D01*
G01X483652Y137507D02*
X483657Y138072D01*
G01X483652Y136942D02*
Y137507D01*
G01X483657Y136378D02*
X483652Y136942D01*
G01X494026D02*
X494022Y136378D01*
G01X494026Y137507D02*
Y136942D01*
G01X494022Y138072D02*
X494026Y137507D01*
G01X489688Y142272D02*
X489686Y142407D01*
G01X489689Y142136D02*
X489688Y142272D01*
G01X487990Y142136D02*
X487989Y140725D01*
G01X487991Y142272D02*
X487990Y142136D01*
G01X487992Y142407D02*
X487991Y142272D01*
G01X467102Y201043D02*
X467101Y196457D01*
G01X467103Y201144D02*
X467102Y201043D01*
G01X467105Y201241D02*
X467103Y201144D01*
G01X467501Y201136D02*
X467523Y201218D01*
G01X467487Y201041D02*
X467501Y201136D01*
G01X467482Y200940D02*
X467487Y201041D01*
G01X480387Y206218D02*
X480608Y206243D01*
G01X480180Y206145D02*
X480387Y206218D01*
G01X479995Y206028D02*
X480180Y206145D01*
G01X479837Y205870D02*
X479995Y206028D01*
G01X479721Y205684D02*
X479837Y205870D01*
G01X479649Y205477D02*
X479721Y205684D01*
G01X479624Y205259D02*
X479649Y205477D01*
G01X452940Y201333D02*
X452932Y201241D01*
G01X452950Y201419D02*
X452940Y201333D01*
G01X452962Y201496D02*
X452950Y201419D01*
G01X467113Y201333D02*
X467105Y201241D01*
G01X467123Y201419D02*
X467113Y201333D01*
G01X467135Y201496D02*
X467123Y201419D01*
G01X436928Y190764D02*
X436852Y190748D01*
G01X436992Y190807D02*
X436928Y190764D01*
G01X437034Y190871D02*
X436992Y190807D01*
G01X437049Y190945D02*
X437034Y190871D01*
G01X444014Y190764D02*
X443939Y190748D01*
G01X444078Y190807D02*
X444014Y190764D01*
G01X444121Y190871D02*
X444078Y190807D01*
G01X444135Y190945D02*
X444121Y190871D01*
G01X451101Y190764D02*
X451025Y190748D01*
G01X451165Y190807D02*
X451101Y190764D01*
G01X451207Y190871D02*
X451165Y190807D01*
G01X451222Y190945D02*
X451207Y190871D01*
G01X458187Y190764D02*
X458112Y190748D01*
G01X458251Y190807D02*
X458187Y190764D01*
G01X458294Y190871D02*
X458251Y190807D01*
G01X458309Y190945D02*
X458294Y190871D01*
G01X465274Y190764D02*
X465198Y190748D01*
G01X465338Y190807D02*
X465274Y190764D01*
G01X465381Y190871D02*
X465338Y190807D01*
G01X465395Y190945D02*
X465381Y190871D01*
G01X472360Y200639D02*
X472285Y200624D01*
G01X472424Y200682D02*
X472360Y200639D01*
G01X472467Y200747D02*
X472424Y200682D01*
G01X472482Y200821D02*
X472467Y200747D01*
G01X443032Y201231D02*
X442951Y201218D01*
G01X443108Y201256D02*
X443032Y201231D01*
G01X443179Y201291D02*
X443108Y201256D01*
G01X443239Y201334D02*
X443179Y201291D01*
G01X443287Y201384D02*
X443239Y201334D01*
G01X443321Y201439D02*
X443287Y201384D01*
G01X443339Y201496D02*
X443321Y201439D01*
G01X457205Y201231D02*
X457124Y201218D01*
G01X457281Y201256D02*
X457205Y201231D01*
G01X457352Y201291D02*
X457281Y201256D01*
G01X457412Y201334D02*
X457352Y201291D01*
G01X457460Y201384D02*
X457412Y201334D01*
G01X457494Y201439D02*
X457460Y201384D01*
G01X457512Y201496D02*
X457494Y201439D01*
G01X483981Y198803D02*
X483900Y198923D01*
G01X484061Y198706D02*
X483981Y198803D01*
G01X484139Y198634D02*
X484061Y198706D01*
G01X484214Y198590D02*
X484139Y198634D01*
G01X484285Y198573D02*
X484214Y198590D01*
G01X484355Y198585D02*
X484285Y198573D01*
G01X484422Y198627D02*
X484355Y198585D01*
G01X484485Y198698D02*
X484422Y198627D01*
G01X484542Y198795D02*
X484485Y198698D01*
G01X484594Y198916D02*
X484542Y198795D01*
G01X484642Y199064D02*
X484594Y198916D01*
G01X436937Y190767D02*
X436852Y190748D01*
G01X437000Y190815D02*
X436937Y190767D01*
G01X437044Y190882D02*
X437000Y190815D01*
G01X493340Y199064D02*
X493423Y199226D01*
G01X493259Y198923D02*
X493340Y199064D01*
G01X451110Y190767D02*
X451025Y190748D01*
G01X451173Y190815D02*
X451110Y190767D01*
G01X451217Y190882D02*
X451173Y190815D01*
G01X465283Y190767D02*
X465198Y190748D01*
G01X465346Y190815D02*
X465283Y190767D01*
G01X465390Y190882D02*
X465346Y190815D01*
G01X472373Y190761D02*
X472332Y190755D01*
G01X472413Y190776D02*
X472373Y190761D01*
G01X472450Y190801D02*
X472413Y190776D01*
G01X472482Y190834D02*
X472450Y190801D01*
G01X472474Y200095D02*
X472482Y200151D01*
G01X472452Y200046D02*
X472474Y200095D01*
G01X472420Y200008D02*
X472452Y200046D01*
G01X472380Y199979D02*
X472420Y200008D01*
G01X472336Y199961D02*
X472380Y199979D01*
G01X495233Y187911D02*
G03X494249Y188878I-984J-17D01*
G01X497753Y160650D02*
G03X500902I1574J0D01*
G01X467089Y196457D02*
G03X467482Y196063I394J0D01*
G01X462718D02*
G03X462324Y195670I0J-394D01*
G01X464883D02*
G03X464490Y196063I-393J0D01*
G01X469805D02*
G03X469411Y195670I0J-394D01*
G01X471970D02*
G03X471576Y196063I-393J0D01*
G01X466734Y196457D02*
G03X467482Y195709I748J0D01*
G01X482910Y188878D02*
G03X481926Y187911I0J-984D01*
G01X490666Y160650D02*
G03X493816I1575J0D01*
G01X483579D02*
G03X486729I1575J0D01*
G01X476493D02*
G03X479642I1574J0D01*
G01X493563Y164725D02*
G03I-4744J0D01*
G01X496713Y164745D02*
G03I-7874J0D01*
G01X464882Y183071D02*
G03I-708J0D01*
G01Y178741D02*
G03I-708J0D01*
G01X471969Y174016D02*
G03I-709J0D01*
G01X472517Y173164D02*
G03Y174944I-1300J890D01*
G01X469446D02*
G03Y173164I1299J-890D01*
G01X471969Y168504D02*
G03I-709J0D01*
G01X472517Y165842D02*
G03Y167621I-1300J890D01*
G01X469446D02*
G03Y165842I1299J-889D01*
G01X471969Y164174D02*
G03I-709J0D01*
G01Y159843D02*
G03I-709J0D01*
G01X469406Y160650D02*
G03X472556I1575J0D01*
G01X464882Y173229D02*
G03I-708J0D01*
G01Y168898D02*
G03I-708J0D01*
G01Y164567D02*
G03I-708J0D01*
G01Y159056D02*
G03I-708J0D01*
G01X462320Y160650D02*
G03X465469I1574J0D01*
G01X501296Y140965D02*
G03I-1968J0D01*
G01X494209D02*
G03I-1968J0D01*
G01X475532Y157264D02*
G03X476123Y156674I590J0D01*
G01X471969Y154331D02*
G03I-709J0D01*
G01X464882Y154725D02*
G03I-708J0D01*
G01X471969Y150000D02*
G03I-709J0D01*
G01X464882Y150394D02*
G03I-708J0D01*
G01X475139Y157264D02*
G03X476123Y156280I984J0D01*
G01X472359Y156142D02*
G03X473343Y157126I0J984D01*
G01X468619D02*
G03X469603Y156142I984J0D01*
G01X471969Y145670D02*
G03I-709J0D01*
G01X464882Y144882D02*
G03I-708J0D01*
G01Y140552D02*
G03I-708J0D01*
G01X471969Y140158D02*
G03I-709J0D01*
G01X472950Y140965D02*
G03I-1969J0D01*
G01X465863D02*
G03I-1969J0D01*
G01X487123D02*
G03I-1969J0D01*
G01X480036D02*
G03I-1968J0D01*
G01X487991Y141992D02*
G03X484072Y138073I848J-4767D01*
G01X493607D02*
G03X489688Y141992I-4768J-849D01*
G01X471969Y135827D02*
G03I-709J0D01*
G01X464882Y136221D02*
G03I-708J0D01*
G01X452916Y196457D02*
G03X453309Y196063I394J0D01*
G01X448545D02*
G03X448151Y195670I0J-394D01*
G01X450710D02*
G03X450317Y196063I-393J0D01*
G01X455631D02*
G03X455238Y195670I0J-393D01*
G01X457797D02*
G03X457403Y196063I-393J0D01*
G01X452561Y196457D02*
G03X453309Y195709I748J0D01*
G01X450709Y183071D02*
G03I-709J0D01*
G01Y178741D02*
G03I-709J0D01*
G01X457796Y174016D02*
G03I-709J0D01*
G01X438742Y196457D02*
G03X439136Y196063I394J0D01*
G01X436537Y195670D02*
G03X436143Y196063I-393J0D01*
G01X441458D02*
G03X441065Y195670I0J-393D01*
G01X443624D02*
G03X443230Y196063I-393J0D01*
G01X438388Y196457D02*
G03X439136Y195709I748J0D01*
G01X436536Y183071D02*
G03I-709J0D01*
G01Y178741D02*
G03I-709J0D01*
G01X443622Y174016D02*
G03I-708J0D01*
G01X434372Y196063D02*
G03X433978Y195670I0J-394D01*
G01X429450D02*
G03X429057Y196063I-393J0D01*
G01X429449Y174016D02*
G03I-708J0D01*
G01X450709Y173229D02*
G03I-709J0D01*
G01X457796Y168504D02*
G03I-709J0D01*
G01X450709Y168898D02*
G03I-709J0D01*
G01X457796Y164174D02*
G03I-709J0D01*
G01X450709Y164567D02*
G03I-709J0D01*
G01Y159056D02*
G03I-709J0D01*
G01X457796Y159843D02*
G03I-709J0D01*
G01Y154331D02*
G03I-709J0D01*
G01X450709Y154725D02*
G03I-709J0D01*
G01X457796Y150000D02*
G03I-709J0D01*
G01X450709Y150394D02*
G03I-709J0D01*
G01X455233Y160650D02*
G03X458383I1575J0D01*
G01X448146D02*
G03X451296I1575J0D01*
G01X436536Y173229D02*
G03I-709J0D01*
G01X443622Y168504D02*
G03I-708J0D01*
G01X436536Y168898D02*
G03I-709J0D01*
G01X443622Y164174D02*
G03I-708J0D01*
G01X436536Y164567D02*
G03I-709J0D01*
G01Y159056D02*
G03I-709J0D01*
G01X443622Y159843D02*
G03I-708J0D01*
G01Y154331D02*
G03I-708J0D01*
G01X436536Y154725D02*
G03I-709J0D01*
G01X443622Y150000D02*
G03I-708J0D01*
G01X436536Y150394D02*
G03I-709J0D01*
G01X441060Y160650D02*
G03X444209I1574J0D01*
G01X457796Y145670D02*
G03I-709J0D01*
G01X450709Y144882D02*
G03I-709J0D01*
G01Y140552D02*
G03I-709J0D01*
G01X457796Y140158D02*
G03I-709J0D01*
G01Y135827D02*
G03I-709J0D01*
G01X450709Y136221D02*
G03I-709J0D01*
G01X458776Y140965D02*
G03I-1968J0D01*
G01X451690D02*
G03I-1969J0D01*
G01X443622Y145670D02*
G03I-708J0D01*
G01X436536Y144882D02*
G03I-709J0D01*
G01Y140552D02*
G03I-709J0D01*
G01X443622Y140158D02*
G03I-708J0D01*
G01Y135827D02*
G03I-708J0D01*
G01X436536Y136221D02*
G03I-709J0D01*
G01X444603Y140965D02*
G03I-1968J0D01*
G01X429449Y168504D02*
G03I-708J0D01*
G01Y164174D02*
G03I-708J0D01*
G01Y159843D02*
G03I-708J0D01*
G01Y154331D02*
G03I-708J0D01*
G01Y150000D02*
G03I-708J0D01*
G01X433973Y160650D02*
G03X437123I1575J0D01*
G01X429449Y145670D02*
G03I-708J0D01*
G01Y140158D02*
G03I-708J0D01*
G01Y135827D02*
G03I-708J0D01*
G01X437517Y140965D02*
G03I-1969J0D01*
G01X492339Y136375D02*
X490659Y135405D01*
G01X489749Y136315D02*
X490589Y136800D01*
G01X487929Y138135D02*
X487089Y137650D01*
G01X485339Y138075D02*
X487019Y139045D01*
G01X493776Y162719D02*
X492989Y162264D01*
G01X486690Y162719D02*
X485902Y162264D01*
G01X479702Y162719D02*
X478914Y162264D01*
G01X487019Y135405D02*
X490659Y139045D01*
G01X497698Y152461D02*
X497474Y152238D01*
G01X496490Y153222D02*
X496713Y153445D01*
G01X481189Y145795D02*
X480965Y145571D01*
G01X479981Y146555D02*
X480205Y146779D01*
G01X494675Y164745D02*
X488839Y158909D01*
G01X493839Y164745D02*
X488839Y159745D01*
G01Y163170D02*
X490414Y164745D01*
G01X488839Y166319D02*
X487265Y164745D01*
G01X488839Y169745D02*
X483839Y164745D01*
G01X488878Y198701D02*
X488777Y198629D01*
G01X483004Y164745D02*
X488839Y170580D01*
G01X497186Y205414D02*
X497031Y205259D01*
G01X496047Y206243D02*
X496202Y206398D01*
G01X480608Y194742D02*
X480453Y194587D01*
G01X479469Y195571D02*
X479624Y195726D01*
G01X489749Y136315D02*
X489264Y135475D01*
G01X487929Y138135D02*
X488414Y138975D01*
G01X487019Y139045D02*
X487989Y140725D01*
G01X493816Y177161D02*
X495194Y179548D01*
G01X486729Y177161D02*
X488107Y179548D01*
G01X472517Y163607D02*
X471729Y162243D01*
G01X479702Y177263D02*
X481020Y179548D01*
G01X472556Y177161D02*
X473945Y179567D01*
G01X465469Y177161D02*
X466847Y179548D01*
G01X458383Y177161D02*
X459761Y179548D01*
G01X451296Y177161D02*
X452674Y179548D01*
G01X444209Y177161D02*
X445587Y179548D01*
G01X437123Y177161D02*
X438501Y179548D01*
G01X430036Y177161D02*
X431414Y179548D01*
G01X484683Y199226D02*
X484640Y199059D01*
G01X493265Y192717D02*
X494643Y198575D01*
G01X484720Y199410D02*
X484682Y199224D01*
G01X494794Y199410D02*
X494731Y199064D01*
G01X494759Y199224D02*
X494643Y198573D01*
G01X467705Y202247D02*
X467523Y201218D01*
G01X467135Y201496D02*
X467317Y202526D01*
G01X453531Y202247D02*
X453350Y201218D01*
G01X452962Y201496D02*
X453144Y202526D01*
G01X439358Y202247D02*
X439177Y201218D01*
G01X438789Y201496D02*
X438970Y202526D01*
G01X468174Y196260D02*
X468249Y196995D01*
G01X467861Y197192D02*
X467786Y196457D01*
G01X454001Y196260D02*
X454076Y196995D01*
G01X453688Y197192D02*
X453613Y196457D01*
G01X472332Y190755D02*
X472324Y190158D01*
G01X472100Y200940D02*
X472103Y201241D01*
G01X471976Y195644D02*
X471977Y196063D01*
G01X472336Y199961D02*
X472332Y190755D01*
G01X497753Y162685D02*
Y160650D01*
G01X497698Y146555D02*
Y152461D01*
G01X497694Y180729D02*
Y162719D01*
G01X497474Y146779D02*
Y152238D01*
G01X497186Y195571D02*
Y205414D01*
G01X497031Y195726D02*
Y205259D01*
G01X496490Y145795D02*
Y153222D01*
G01X496047Y194742D02*
Y206243D01*
G01X494856Y230906D02*
Y184646D01*
G01X494851D02*
Y230906D01*
G01X494821D02*
Y184646D01*
G01X494794Y230906D02*
Y199410D01*
G01X494642Y184646D02*
Y198575D01*
G01X494249Y188878D02*
Y187911D01*
G01X493816Y160650D02*
Y177161D01*
G01X493776Y180729D02*
Y162719D01*
G01X493754Y230906D02*
Y184646D01*
G01X493571Y230906D02*
Y184646D01*
G01X493520Y188878D02*
Y222874D01*
G01X493508Y199410D02*
Y230906D01*
G01X492439Y231300D02*
Y199410D01*
G01X492414Y230906D02*
Y184646D01*
G01X492274Y230906D02*
Y184646D01*
G01X491439Y137650D02*
Y136800D01*
G01X490705Y180729D02*
Y162719D01*
G01X490666Y177161D02*
Y160650D01*
G01X489689Y140725D02*
Y142136D01*
G01X489626Y230906D02*
Y184646D01*
G01X489398Y230906D02*
Y184646D01*
G01X489336Y199410D02*
Y230906D01*
G01X489264Y138975D02*
Y139825D01*
G01X488839Y166319D02*
Y170580D01*
G01Y163170D02*
Y158909D01*
G01X488414Y139825D02*
Y138975D01*
G01X487823Y230906D02*
Y199410D01*
G01X487761Y230906D02*
Y184646D01*
G01X487533D02*
Y230906D01*
G01X486729Y160650D02*
Y177161D01*
G01X486690Y162719D02*
Y180729D01*
G01X486239Y137650D02*
Y136800D01*
G01X484885Y230906D02*
Y184646D01*
G01X484745Y230906D02*
Y184646D01*
G01X484720Y231300D02*
Y199410D01*
G01X483651Y230906D02*
Y199410D01*
G01X483639Y188878D02*
Y222874D01*
G01X483619Y180729D02*
Y162719D01*
G01X483588Y230906D02*
Y184646D01*
G01X483579Y177161D02*
Y160650D01*
G01X483405Y230906D02*
Y184646D01*
G01X482910Y188878D02*
Y187911D01*
G01X482517Y184646D02*
Y198575D01*
G01X482365Y230906D02*
Y199410D01*
G01X482338Y184646D02*
Y230906D01*
G01X482308D02*
Y184646D01*
G01X482303Y230906D02*
Y184646D01*
G01X481189Y145795D02*
Y153222D01*
G01X480608Y194742D02*
Y206243D01*
G01X480205Y146779D02*
Y152238D01*
G01X479981Y152461D02*
Y146555D01*
G01X479702Y162719D02*
Y180729D01*
G01X479642Y160650D02*
Y162685D01*
G01X479624Y205259D02*
Y195726D01*
G01X479469Y205414D02*
Y195571D01*
G01X476493Y162685D02*
Y160650D01*
G01X476434Y180729D02*
Y162719D01*
G01X476123Y156674D02*
Y156280D01*
G01X475926Y189863D02*
Y210433D01*
G01X475532Y157264D02*
Y209646D01*
G01X473629Y190158D02*
Y228741D01*
G01X473343Y180552D02*
Y157126D01*
G01X472556Y174884D02*
Y177161D01*
G01Y167561D02*
Y173225D01*
G01Y160650D02*
Y165902D01*
G01X472517Y165842D02*
Y163607D01*
G01Y173164D02*
Y167621D01*
G01Y180552D02*
Y174944D01*
G01X472482Y190834D02*
Y190158D01*
G01Y201043D02*
Y200151D01*
G01X472285Y190748D02*
Y200624D01*
G01X472103Y201241D02*
Y224608D01*
G01X472100Y196063D02*
Y200940D01*
G01X471970Y195670D02*
Y191733D01*
G01X471872Y195906D02*
Y191969D01*
G01X471719Y196037D02*
Y201040D01*
G01X471715Y224608D02*
Y201241D01*
G01X471529Y226338D02*
Y196063D01*
G01X471504Y224608D02*
Y202526D01*
G01X471338Y196063D02*
Y200940D01*
G01X471141Y226338D02*
Y196063D01*
G01X471116Y202247D02*
Y224608D01*
G01X470999Y226338D02*
Y196063D01*
G01X470611D02*
Y226338D01*
G01X469509Y195906D02*
Y191969D01*
G01X469446Y165842D02*
Y163607D01*
G01Y173164D02*
Y167621D01*
G01Y180552D02*
Y174944D01*
G01X469411Y197192D02*
Y191733D01*
G01X469406Y165902D02*
Y160650D01*
G01Y173225D02*
Y167561D01*
G01Y177161D02*
Y174884D01*
G01X469096Y200624D02*
Y190748D01*
G01X468899Y190834D02*
Y190158D01*
G01Y201043D02*
Y200151D01*
G01X468619Y180552D02*
Y157126D01*
G01X468249Y196995D02*
Y226338D01*
G01X468174Y196260D02*
Y196063D01*
G01X468131D02*
Y195670D01*
G01X469045Y199961D02*
X469049Y190755D01*
G01X471504Y202526D02*
X471685Y201496D01*
G01X471297Y201218D02*
X471116Y202247D01*
G01X482516Y198573D02*
X482494Y198698D01*
G01X482506Y198634D02*
X482365Y199410D01*
G01X483894Y192717D02*
X482516Y198575D01*
G01X492477Y199224D02*
X492519Y199059D01*
G01X439828Y196260D02*
X439902Y196995D01*
G01X439515Y197192D02*
X439440Y196457D01*
G01X457927Y200940D02*
X457929Y201241D01*
G01X443754Y200940D02*
X443756Y201241D01*
G01X429581Y200940D02*
X429583Y201241D01*
G01X457803Y195644D02*
Y196063D01*
G01X443629Y195644D02*
X443630Y196063D01*
G01X429456Y195644D02*
X429457Y196063D01*
G01X467861Y226338D02*
Y197192D01*
G01X467719Y196457D02*
Y226338D01*
G01X467705Y202247D02*
Y224608D01*
G01X467482Y195695D02*
Y200940D01*
G01X467331Y196457D02*
Y226338D01*
G01X467317Y202526D02*
Y224608D01*
G01X467105D02*
Y201241D01*
G01X466720Y200940D02*
Y196457D01*
G01X466718Y224608D02*
Y201241D01*
G01X465469Y160650D02*
Y177161D01*
G01X465395Y190158D02*
Y201805D01*
G01X465384D02*
X465385Y190882D01*
G01X465198Y201805D02*
Y190748D01*
G01X464883Y195670D02*
Y191733D01*
G01X464574Y225788D02*
Y201805D01*
G01X462324Y195670D02*
Y191733D01*
G01X462320Y177161D02*
Y160650D01*
G01X462009Y201805D02*
Y190748D01*
G01X461813Y201805D02*
Y190158D01*
G01X460833Y190748D02*
Y225788D01*
G01X460647D02*
Y190882D01*
G01X460637D02*
Y190158D01*
G01X458383Y160650D02*
Y177161D01*
G01X458309Y190158D02*
Y201043D01*
G01X458112Y190748D02*
Y200624D01*
G01X457930Y201241D02*
Y224608D01*
G01X457927Y196063D02*
Y200940D01*
G01X457797Y195670D02*
Y191733D01*
G01X457546Y201040D02*
Y196037D01*
G01X457542Y201241D02*
Y224608D01*
G01X457355Y226338D02*
Y196063D01*
G01X457330Y224608D02*
Y202526D01*
G01X457165Y196063D02*
Y200940D01*
G01X456968Y226338D02*
Y196063D01*
G01X456943Y202247D02*
Y224608D01*
G01X456825Y226338D02*
Y196063D01*
G01X456438D02*
Y226338D01*
G01X455238Y197192D02*
Y191733D01*
G01X455233Y177161D02*
Y160650D01*
G01X454923Y200624D02*
Y190748D01*
G01X454726Y201043D02*
Y190158D01*
G01X454076Y196995D02*
Y226338D01*
G01X454001Y196260D02*
Y196063D01*
G01X453958D02*
Y195670D01*
G01X453688Y226338D02*
Y197192D01*
G01X453546Y196457D02*
Y226338D01*
G01X453531Y202247D02*
Y224608D01*
G01X453309Y195695D02*
Y200940D01*
G01X453158Y196457D02*
Y226338D01*
G01X453144Y202526D02*
Y224608D01*
G01X452932D02*
Y201241D01*
G01X452547Y200940D02*
Y196457D01*
G01X452544Y224608D02*
Y201241D01*
G01X451296Y160650D02*
Y177161D01*
G01X451222Y190158D02*
Y201805D01*
G01X451211D02*
X451212Y190882D01*
G01X451025Y201805D02*
Y190748D01*
G01X450710Y195670D02*
Y191733D01*
G01X450400Y225788D02*
Y201805D01*
G01X448151Y195670D02*
Y191733D01*
G01X448146Y177161D02*
Y160650D01*
G01X447836Y201805D02*
Y190748D01*
G01X447639Y201805D02*
Y190158D01*
G01X446660Y190748D02*
Y225788D01*
G01X446474D02*
Y190882D01*
G01X446463D02*
Y190158D01*
G01X444209Y160650D02*
Y177161D01*
G01X444135Y190158D02*
Y201043D01*
G01X443939Y190748D02*
Y200624D01*
G01X443756Y201241D02*
Y224608D01*
G01X443754Y196063D02*
Y200940D01*
G01X443624Y195670D02*
Y191733D01*
G01X443372Y201040D02*
X443373Y196037D01*
G01X443369Y201241D02*
Y224608D01*
G01X443182Y226338D02*
Y196063D01*
G01X443157Y224608D02*
Y202526D01*
G01X442991Y196063D02*
Y200940D01*
G01X442794Y226338D02*
Y196063D01*
G01X442769Y202247D02*
Y224608D01*
G01X442652Y226338D02*
Y196063D01*
G01X442264D02*
Y226338D01*
G01X441065Y197192D02*
Y191733D01*
G01X441060Y177161D02*
Y160650D01*
G01X440750Y200624D02*
Y190748D01*
G01X440553Y201043D02*
Y190158D01*
G01X439902Y196995D02*
Y226338D01*
G01X439828Y196260D02*
Y196063D01*
G01X439784D02*
Y195670D01*
G01X439515Y226338D02*
Y197192D01*
G01X439373Y196457D02*
Y226338D01*
G01X439358Y202247D02*
Y224608D01*
G01X439136Y195695D02*
Y200940D01*
G01X438985Y196457D02*
Y226338D01*
G01X438970Y202526D02*
Y224608D01*
G01X438759D02*
Y201241D01*
G01X438374Y200940D02*
Y196457D01*
G01X438371Y224608D02*
Y201241D01*
G01X437123Y160650D02*
Y177161D01*
G01X437049Y190158D02*
Y201805D01*
G01X437038D02*
X437039Y190882D01*
G01X436852Y201805D02*
Y190748D01*
G01X436537Y195670D02*
Y191733D01*
G01X436227Y225788D02*
Y201805D01*
G01X433978Y195670D02*
Y191733D01*
G01X433973Y177161D02*
Y160650D01*
G01X433663Y201805D02*
Y190748D01*
G01X433466Y201805D02*
Y190158D01*
G01X432487Y190748D02*
Y225788D01*
G01X432301D02*
Y190882D01*
G01X432290D02*
Y190158D01*
G01X430036Y160650D02*
Y177161D01*
G01X429962Y190158D02*
Y201043D01*
G01X429765Y190748D02*
Y200624D01*
G01X429583Y201241D02*
Y224608D01*
G01X429581Y196063D02*
Y200940D01*
G01X429450Y195670D02*
Y191733D01*
G01X429199Y201040D02*
Y196037D01*
G01X429195Y201241D02*
Y224608D01*
G01X429009Y226338D02*
Y196063D01*
G01X428984Y202526D02*
Y224608D01*
G01X428818Y196063D02*
Y200940D01*
G01X428621Y226338D02*
Y196063D01*
G01X428596Y202247D02*
Y224608D01*
G01X428479Y226338D02*
Y196063D01*
G01X428091D02*
Y226338D01*
G01X469057Y190158D02*
X469049Y190755D01*
G01X457330Y202526D02*
X457512Y201496D01*
G01X457124Y201218D02*
X456943Y202247D01*
G01X443157Y202526D02*
X443339Y201496D01*
G01X442951Y201218D02*
X442769Y202247D01*
G01X428984Y202526D02*
X429165Y201496D01*
G01X428778Y201218D02*
X428596Y202247D01*
G01X483651Y199410D02*
X483737Y199224D01*
G01X483821Y199059D02*
X483736Y199226D01*
G01X496375Y179548D02*
X497694Y177263D01*
G01X483904Y198916D02*
X483819Y199064D01*
G01X489288Y179548D02*
X490666Y177161D01*
G01X482202Y179548D02*
X483579Y177161D01*
G01X475115Y179548D02*
X476434Y177263D01*
G01X468028Y179548D02*
X469406Y177161D01*
G01X489689Y140725D02*
X490659Y139045D01*
G01X489749Y138135D02*
X489264Y138975D01*
G01X487929Y136315D02*
X488414Y135475D01*
G01X460942Y179548D02*
X462320Y177161D01*
G01X469446Y163607D02*
X470233Y162243D01*
G01X453855Y179548D02*
X455233Y177161D01*
G01X446768Y179548D02*
X448146Y177161D01*
G01X497031Y195726D02*
X497186Y195571D01*
G01X496202Y194587D02*
X496047Y194742D01*
G01X480453Y206398D02*
X480608Y206243D01*
G01X479624Y205259D02*
X479469Y205414D01*
G01X439682Y179548D02*
X441060Y177161D01*
G01X432595Y179548D02*
X433973Y177161D01*
G01X488839Y170580D02*
X494675Y164745D01*
G01X488839Y169745D02*
X493839Y164745D01*
G01X490414D02*
X488839Y166319D01*
G01X487265Y164745D02*
X488839Y163170D01*
G01X483839Y164745D02*
X488839Y159745D01*
G01Y158909D02*
X483004Y164745D01*
G01X497474Y146779D02*
X497698Y146555D01*
G01X496714Y145571D02*
X496490Y145795D01*
G01X480965Y153445D02*
X481189Y153222D01*
G01X480205Y152238D02*
X479981Y152461D01*
G01X490659Y135405D02*
X487019Y139045D01*
G01X498481Y162264D02*
X497694Y162719D01*
G01X491493Y162264D02*
X490705Y162719D01*
G01X484406Y162264D02*
X483619Y162719D01*
G01X477221Y162264D02*
X476434Y162719D01*
G01X490659Y139045D02*
X492339Y138075D01*
G01X490589Y137650D02*
X489749Y138135D01*
G01X482482Y187917D02*
X482910Y187911D01*
G01X495020Y187918D02*
X494861D01*
G01X496202Y206398D02*
X480453D01*
G01X496047Y206243D02*
X480608D01*
G01X479624Y205259D02*
X497031D01*
G01X467317Y202526D02*
X471504D01*
G01X453144D02*
X457330D01*
G01X438970D02*
X443157D01*
G01X442769Y202247D02*
X439358D01*
G01X456943D02*
X453531D01*
G01X471116D02*
X467705D01*
G01X437049Y201805D02*
X433466D01*
G01X451222D02*
X447639D01*
G01X465395D02*
X461813D01*
G01X473956D02*
X473629D01*
G01X457542Y201241D02*
X457930D01*
G01X443369D02*
X443756D01*
G01X429195D02*
X429583D01*
G01X438759D02*
X438371D01*
G01X452932D02*
X452544D01*
G01X467105D02*
X466718D01*
G01X472103D02*
X471715D01*
G01X467523Y201218D02*
X471297D01*
G01X453350D02*
X457124D01*
G01X439177D02*
X442951D01*
G01X444135Y201043D02*
X440553D01*
G01X458309D02*
X454726D01*
G01X472482D02*
X468899D01*
G01X452547Y200940D02*
X457927D01*
G01X438374D02*
X443754D01*
G01X472100D02*
X466720D01*
G01X443939Y200624D02*
X440750D01*
G01X458112D02*
X454923D01*
G01X472285D02*
X469096D01*
G01X468899Y200374D02*
X472482D01*
G01X469045Y199961D02*
X472336D01*
G01X483651Y199410D02*
X482365D01*
G01X487823D02*
X484720D01*
G01X492439D02*
X489336D01*
G01X494794D02*
X493508D01*
G01X467861Y197192D02*
X469411D01*
G01X453688D02*
X455238D01*
G01X439515D02*
X441065D01*
G01X468249Y196995D02*
X469411D01*
G01X454076D02*
X455238D01*
G01X439902D02*
X441065D01*
G01Y196457D02*
X438374D01*
G01X455238D02*
X452547D01*
G01X469411D02*
X466720D01*
G01X468174Y196260D02*
X469411D01*
G01X454001D02*
X455238D01*
G01X439828D02*
X441065D01*
G01X467482Y196076D02*
X469411D01*
G01X453309D02*
X455238D01*
G01X439136D02*
X441065D01*
G01X469805Y196063D02*
X471576D01*
G01X429581D02*
X429450D01*
G01X436143D02*
X434372D01*
G01X443230D02*
X441458D01*
G01X441065D02*
X439784D01*
G01X443754D02*
X443624D01*
G01X450317D02*
X448545D01*
G01X457403D02*
X455631D01*
G01X455238D02*
X453958D01*
G01X457927D02*
X457797D01*
G01X464490D02*
X462718D01*
G01X469411D02*
X468131D01*
G01X472100D02*
X471970D01*
G01X471872Y195906D02*
X469509D01*
G01X497031Y195726D02*
X479624D01*
G01X467482Y195695D02*
X469411D01*
G01X453309D02*
X455238D01*
G01X439136D02*
X441065D01*
G01Y195670D02*
X439784D01*
G01X455238D02*
X453958D01*
G01X469411D02*
X468131D01*
G01X469509Y195048D02*
X471872D01*
G01X496047Y194742D02*
X480608D01*
G01X480453Y194587D02*
X496202D01*
G01X471970Y193567D02*
X473629D01*
G01X433978D02*
X429450D01*
G01X441065D02*
X436537D01*
G01X448151D02*
X443624D01*
G01X455238D02*
X450710D01*
G01X462324D02*
X457797D01*
G01X469411D02*
X464883D01*
G01X471872Y193544D02*
X469509D01*
G01X471970Y193370D02*
X473629D01*
G01X464883D02*
X469411D01*
G01X457797D02*
X462324D01*
G01X450710D02*
X455238D01*
G01X443624D02*
X448151D01*
G01X436537D02*
X441065D01*
G01X433978D02*
X429450D01*
G01X483894Y192717D02*
X493265D01*
G01X471872Y191969D02*
X469509D01*
G01X436537Y191733D02*
X433978D01*
G01X443624D02*
X441065D01*
G01X450710D02*
X448151D01*
G01X457797D02*
X455238D01*
G01X464883D02*
X462324D01*
G01X471970D02*
X469411D01*
G01X468899Y190237D02*
X472482D01*
G01X440553D02*
X444135D01*
G01X458309D02*
X454726D01*
G01X501517Y189863D02*
X475139D01*
G01Y189075D02*
X501517D01*
G01X494249Y188878D02*
X482910D01*
G01X494249Y187911D02*
X482910D01*
G01X494856Y184646D02*
X482303D01*
G01X494863Y187918D02*
X494675Y187917D01*
G01X482022D02*
X482139Y187918D01*
G01X494677Y187917D02*
X494249Y187911D01*
G01X481950Y187915D02*
X482022Y187917D01*
G01X481926Y187911D02*
X481950Y187915D01*
G01X487929Y136315D02*
X487089Y136800D01*
G01X487019Y135405D02*
X485339Y136375D01*
G01Y138075D02*
X492339Y136375D01*
G01X483657Y138072D02*
X494022Y136378D01*
G01X476434Y180729D02*
X475139D01*
G01X483619D02*
X479702D01*
G01X490705D02*
X486690D01*
G01X497694D02*
X493776D01*
G01X473956Y180552D02*
X472517D01*
G01X473934Y179548D02*
X475115D01*
G01X452674D02*
X453855D01*
G01X432595D02*
X431414D01*
G01X439682D02*
X438501D01*
G01X446768D02*
X445587D01*
G01X460942D02*
X459761D01*
G01X468028D02*
X466847D01*
G01X482202D02*
X481020D01*
G01X489288D02*
X488107D01*
G01X496375D02*
X495194D01*
G01X451493Y177502D02*
X455036D01*
G01X444406D02*
X447950D01*
G01X437320D02*
X440863D01*
G01X430233D02*
X433776D01*
G01X490414Y164745D02*
X494675D01*
G01X483004D02*
X487265D01*
G01X478914Y162264D02*
X477221D01*
G01X485902D02*
X484406D01*
G01X492989D02*
X491493D01*
G01X500174D02*
X498481D01*
G01X471729Y162243D02*
X470233D01*
G01X475139Y158803D02*
X501517D01*
G01X473343Y158665D02*
X468619D01*
G01X475139Y157264D02*
X475532D01*
G01X476123Y156674D02*
X500532D01*
G01Y156280D02*
X476123D01*
G01X472359Y156142D02*
X469603D01*
G01X496714Y153445D02*
X480965D01*
G01X481189Y153222D02*
X496490D01*
G01X480205Y152238D02*
X497474D01*
G01Y146779D02*
X480205D01*
G01X496490Y145795D02*
X481189D01*
G01X480965Y145571D02*
X496714D01*
G01X489264Y139825D02*
X488414D01*
G01X485339Y138075D02*
X483928D01*
G01X487089Y137650D02*
X486239D01*
G01X491439D02*
X490589D01*
G01Y136800D02*
X491439D01*
G01X486239D02*
X487089D01*
G01X492339Y136375D02*
X493750D01*
G01X487992Y142407D02*
X488557Y142412D01*
G01X483657Y136378D02*
X494022Y138072D01*
G01X485339Y136375D02*
X492339Y138075D01*
G01X475168Y209858D02*
X475139Y209646D01*
G01X475257Y210062D02*
X475168Y209858D01*
G01X475412Y210243D02*
X475257Y210062D01*
G01X475635Y210378D02*
X475412Y210243D01*
G01X475926Y210433D02*
X475635Y210378D01*
G01X478420Y211396D02*
X478344Y211401D01*
G01X478634Y211394D02*
X478420Y211396D01*
G01X498993Y211100D02*
X498941Y211401D01*
G01X499135Y210830D02*
X498993Y211100D01*
G01X499352Y210617D02*
X499135Y210830D01*
G01X499624Y210480D02*
X499352Y210617D01*
G01X483902Y231055D02*
X483651Y230906D01*
G01X484153Y231103D02*
X483902Y231055D01*
G01X493006Y231103D02*
X493257Y231055D01*
G01X492740D02*
X493006Y231103D01*
G01X478727Y230633D02*
X478675Y230333D01*
G01X478869Y230902D02*
X478727Y230633D01*
G01X479086Y231116D02*
X478869Y230902D01*
G01X479358Y231253D02*
X479086Y231116D01*
G01X479659Y231300D02*
X479358Y231253D01*
G01X479045Y230340D02*
X479231Y230338D01*
G01X478888Y230340D02*
X479045D01*
G01X478772Y230338D02*
X478888Y230340D01*
G01X478699Y230336D02*
X478772Y230338D01*
G01X478675Y230333D02*
X478699Y230336D01*
G01X473065Y228592D02*
X473037Y228533D01*
G01X473103Y228642D02*
X473065Y228592D01*
G01X473151Y228684D02*
X473103Y228642D01*
G01X473206Y228715D02*
X473151Y228684D01*
G01X473266Y228734D02*
X473206Y228715D01*
G01X473328Y228741D02*
X473266Y228734D01*
G01X471495Y228592D02*
X471467Y228533D01*
G01X471533Y228642D02*
X471495Y228592D01*
G01X471581Y228684D02*
X471533Y228642D01*
G01X471636Y228715D02*
X471581Y228684D01*
G01X471696Y228734D02*
X471636Y228715D01*
G01X471758Y228741D02*
X471696Y228734D01*
G01X458892Y228592D02*
X458864Y228533D01*
G01X458930Y228642D02*
X458892Y228592D01*
G01X458978Y228684D02*
X458930Y228642D01*
G01X459033Y228715D02*
X458978Y228684D01*
G01X459093Y228734D02*
X459033Y228715D01*
G01X459155Y228741D02*
X459093Y228734D01*
G01X457322Y228592D02*
X457294Y228533D01*
G01X457360Y228642D02*
X457322Y228592D01*
G01X457408Y228684D02*
X457360Y228642D01*
G01X457463Y228715D02*
X457408Y228684D01*
G01X457523Y228734D02*
X457463Y228715D01*
G01X457585Y228741D02*
X457523Y228734D01*
G01X444718Y228592D02*
X444690Y228533D01*
G01X444757Y228642D02*
X444718Y228592D01*
G01X444805Y228684D02*
X444757Y228642D01*
G01X444860Y228715D02*
X444805Y228684D01*
G01X444920Y228734D02*
X444860Y228715D01*
G01X444982Y228741D02*
X444920Y228734D01*
G01X443148Y228592D02*
X443120Y228533D01*
G01X443187Y228642D02*
X443148Y228592D01*
G01X443235Y228684D02*
X443187Y228642D01*
G01X443290Y228715D02*
X443235Y228684D01*
G01X443350Y228734D02*
X443290Y228715D01*
G01X443412Y228741D02*
X443350Y228734D01*
G01X430545Y228592D02*
X430517Y228533D01*
G01X430583Y228642D02*
X430545Y228592D01*
G01X430632Y228684D02*
X430583Y228642D01*
G01X430687Y228715D02*
X430632Y228684D01*
G01X430746Y228734D02*
X430687Y228715D01*
G01X430809Y228741D02*
X430746Y228734D01*
G01X428975Y228592D02*
X428947Y228533D01*
G01X429013Y228642D02*
X428975Y228592D01*
G01X429062Y228684D02*
X429013Y228642D01*
G01X429116Y228715D02*
X429062Y228684D01*
G01X429176Y228734D02*
X429116Y228715D01*
G01X429239Y228741D02*
X429176Y228734D01*
G01X498512Y230338D02*
X498585Y230336D01*
G01X498395Y230340D02*
X498512Y230338D01*
G01X498237Y230340D02*
X498395D01*
G01X498051Y230338D02*
X498237Y230340D01*
G01X497626Y230333D02*
X498051Y230338D01*
G01X428550Y226997D02*
X428581Y227012D01*
G01X428502Y226991D02*
X428550Y226997D01*
G01X428441Y226992D02*
X428502Y226991D01*
G01X442724Y226997D02*
X442754Y227012D01*
G01X442676Y226991D02*
X442724Y226997D01*
G01X442614Y226992D02*
X442676Y226991D01*
G01X456897Y226997D02*
X456927Y227012D01*
G01X456849Y226991D02*
X456897Y226997D01*
G01X456787Y226992D02*
X456849Y226991D01*
G01X471070Y226997D02*
X471101Y227012D01*
G01X471022Y226991D02*
X471070Y226997D01*
G01X470961Y226992D02*
X471022Y226991D01*
G01X498558Y230633D02*
X498610Y230333D01*
G01X498416Y230902D02*
X498558Y230633D01*
G01X498199Y231116D02*
X498416Y230902D01*
G01X497927Y231253D02*
X498199Y231116D01*
G01X497626Y231300D02*
X497927Y231253D01*
G01X437724Y228514D02*
X438101Y228426D01*
G01X437647Y228533D02*
X437724Y228514D01*
G01X451897D02*
X452274Y228426D01*
G01X451820Y228533D02*
X451897Y228514D01*
G01X466070D02*
X466447Y228426D01*
G01X465994Y228533D02*
X466070Y228514D01*
G01X439491Y226991D02*
X439553Y226992D01*
G01X439443Y226997D02*
X439491Y226991D01*
G01X439413Y227012D02*
X439443Y226997D01*
G01X453665Y226991D02*
X453726Y226992D01*
G01X453617Y226997D02*
X453665Y226991D01*
G01X453586Y227012D02*
X453617Y226997D01*
G01X467838Y226991D02*
X467899Y226992D01*
G01X467790Y226997D02*
X467838Y226991D01*
G01X467759Y227012D02*
X467790Y226997D01*
G01X428507Y227953D02*
X428343Y227395D01*
G01X428587Y228378D02*
X428507Y227953D01*
G01X428579Y228647D02*
X428587Y228378D01*
G01X428485Y228741D02*
X428579Y228647D01*
G01X442680Y227953D02*
X442517Y227395D01*
G01X442760Y228378D02*
X442680Y227953D01*
G01X442752Y228647D02*
X442760Y228378D01*
G01X442658Y228741D02*
X442752Y228647D01*
G01X428712Y228709D02*
X428485Y228741D01*
G01X428859Y228639D02*
X428712Y228709D01*
G01X428947Y228533D02*
X428859Y228639D01*
G01X456853Y227953D02*
X456690Y227395D01*
G01X456934Y228378D02*
X456853Y227953D01*
G01X456926Y228647D02*
X456934Y228378D01*
G01X456831Y228741D02*
X456926Y228647D01*
G01X471027Y227953D02*
X470863Y227395D01*
G01X471107Y228378D02*
X471027Y227953D01*
G01X471099Y228647D02*
X471107Y228378D01*
G01X471004Y228741D02*
X471099Y228647D01*
G01X442885Y228709D02*
X442658Y228741D01*
G01X443032Y228639D02*
X442885Y228709D01*
G01X443120Y228533D02*
X443032Y228639D01*
G01X457058Y228709D02*
X456831Y228741D01*
G01X457205Y228639D02*
X457058Y228709D01*
G01X457294Y228533D02*
X457205Y228639D01*
G01X471231Y228709D02*
X471004Y228741D01*
G01X471378Y228639D02*
X471231Y228709D01*
G01X471467Y228533D02*
X471378Y228639D01*
G01X439805Y226582D02*
X439902Y226378D01*
G01X439688Y226786D02*
X439805Y226582D01*
G01X439464Y227127D02*
X439688Y226786D01*
G01X453978Y226582D02*
X454075Y226378D01*
G01X453861Y226786D02*
X453978Y226582D01*
G01X453638Y227127D02*
X453861Y226786D01*
G01X468151Y226582D02*
X468248Y226378D01*
G01X468034Y226786D02*
X468151Y226582D01*
G01X467811Y227127D02*
X468034Y226786D01*
G01X439386Y227262D02*
X439464Y227127D01*
G01X439317Y227395D02*
X439386Y227262D01*
G01X453559D02*
X453638Y227127D01*
G01X453491Y227395D02*
X453559Y227262D01*
G01X437209Y228734D02*
X437146Y228741D01*
G01X437269Y228715D02*
X437209Y228734D01*
G01X437324Y228683D02*
X437269Y228715D01*
G01X437372Y228641D02*
X437324Y228683D01*
G01X437410Y228591D02*
X437372Y228641D01*
G01X437437Y228533D02*
X437410Y228591D01*
G01X437419Y228734D02*
X437356Y228741D01*
G01X437479Y228715D02*
X437419Y228734D01*
G01X437534Y228683D02*
X437479Y228715D01*
G01X437582Y228641D02*
X437534Y228683D01*
G01X437620Y228591D02*
X437582Y228641D01*
G01X437647Y228533D02*
X437620Y228591D01*
G01X438462Y228734D02*
X438399Y228741D01*
G01X438522Y228715D02*
X438462Y228734D01*
G01X438577Y228684D02*
X438522Y228715D01*
G01X438625Y228641D02*
X438577Y228684D01*
G01X438663Y228591D02*
X438625Y228641D01*
G01X438690Y228533D02*
X438663Y228591D01*
G01X438818Y228734D02*
X438755Y228741D01*
G01X438878Y228715D02*
X438818Y228734D01*
G01X438933Y228684D02*
X438878Y228715D01*
G01X438981Y228641D02*
X438933Y228684D01*
G01X439019Y228591D02*
X438981Y228641D01*
G01X439046Y228533D02*
X439019Y228591D01*
G01X467732Y227262D02*
X467811Y227127D01*
G01X467664Y227395D02*
X467732Y227262D01*
G01X451382Y228734D02*
X451319Y228741D01*
G01X451442Y228715D02*
X451382Y228734D01*
G01X451498Y228683D02*
X451442Y228715D01*
G01X451545Y228641D02*
X451498Y228683D01*
G01X451583Y228591D02*
X451545Y228641D01*
G01X451610Y228533D02*
X451583Y228591D01*
G01X451592Y228734D02*
X451529Y228741D01*
G01X451652Y228715D02*
X451592Y228734D01*
G01X451708Y228683D02*
X451652Y228715D01*
G01X451755Y228641D02*
X451708Y228683D01*
G01X451793Y228591D02*
X451755Y228641D01*
G01X451820Y228533D02*
X451793Y228591D01*
G01X452635Y228734D02*
X452572Y228741D01*
G01X452695Y228715D02*
X452635Y228734D01*
G01X452750Y228684D02*
X452695Y228715D01*
G01X452798Y228641D02*
X452750Y228684D01*
G01X452836Y228591D02*
X452798Y228641D01*
G01X452864Y228533D02*
X452836Y228591D01*
G01X452992Y228734D02*
X452928Y228741D01*
G01X453051Y228715D02*
X452992Y228734D01*
G01X453106Y228684D02*
X453051Y228715D01*
G01X453154Y228641D02*
X453106Y228684D01*
G01X453192Y228591D02*
X453154Y228641D01*
G01X453220Y228533D02*
X453192Y228591D01*
G01X465555Y228734D02*
X465492Y228741D01*
G01X465615Y228715D02*
X465555Y228734D01*
G01X465671Y228683D02*
X465615Y228715D01*
G01X465718Y228641D02*
X465671Y228683D01*
G01X465756Y228591D02*
X465718Y228641D01*
G01X465783Y228533D02*
X465756Y228591D01*
G01X465766Y228734D02*
X465702Y228741D01*
G01X465825Y228715D02*
X465766Y228734D01*
G01X465881Y228683D02*
X465825Y228715D01*
G01X465928Y228641D02*
X465881Y228683D01*
G01X465966Y228591D02*
X465928Y228641D01*
G01X465994Y228533D02*
X465966Y228591D01*
G01X466809Y228734D02*
X466745Y228741D01*
G01X466868Y228715D02*
X466809Y228734D01*
G01X466923Y228684D02*
X466868Y228715D01*
G01X466971Y228641D02*
X466923Y228684D01*
G01X467009Y228591D02*
X466971Y228641D01*
G01X467037Y228533D02*
X467009Y228591D01*
G01X467165Y228734D02*
X467101Y228741D01*
G01X467225Y228715D02*
X467165Y228734D01*
G01X467279Y228684D02*
X467225Y228715D01*
G01X467328Y228641D02*
X467279Y228684D01*
G01X467366Y228591D02*
X467328Y228641D01*
G01X467393Y228533D02*
X467366Y228591D01*
G01X439415Y228650D02*
X439509Y228741D01*
G01X439406Y228383D02*
X439415Y228650D01*
G01X439486Y227957D02*
X439406Y228383D01*
G01X439650Y227395D02*
X439486Y227957D01*
G01X453588Y228650D02*
X453682Y228741D01*
G01X453579Y228383D02*
X453588Y228650D01*
G01X453659Y227957D02*
X453579Y228383D01*
G01X453824Y227395D02*
X453659Y227957D01*
G01X467762Y228650D02*
X467855Y228741D01*
G01X467752Y228383D02*
X467762Y228650D01*
G01X467832Y227957D02*
X467752Y228383D01*
G01X467997Y227395D02*
X467832Y227957D01*
G01X439501Y226585D02*
X439514Y226372D01*
G01X439467Y226800D02*
X439501Y226585D01*
G01X439413Y227012D02*
X439467Y226800D01*
G01X453674Y226585D02*
X453688Y226372D01*
G01X453640Y226800D02*
X453674Y226585D01*
G01X453586Y227012D02*
X453640Y226800D01*
G01X439231Y227630D02*
X439413Y227012D01*
G01X439115Y228113D02*
X439231Y227630D01*
G01X439046Y228533D02*
X439115Y228113D01*
G01X438916Y225061D02*
X438849Y225281D01*
G01X438957Y224836D02*
X438916Y225061D01*
G01X438970Y224608D02*
X438957Y224836D01*
G01X453090Y225061D02*
X453022Y225281D01*
G01X453130Y224836D02*
X453090Y225061D01*
G01X453144Y224608D02*
X453130Y224836D01*
G01X467263Y225061D02*
X467196Y225281D01*
G01X467303Y224836D02*
X467263Y225061D01*
G01X467317Y224608D02*
X467303Y224836D01*
G01X439294Y225152D02*
X439214Y225415D01*
G01X439342Y224882D02*
X439294Y225152D01*
G01X439358Y224608D02*
X439342Y224882D01*
G01X453467Y225152D02*
X453387Y225415D01*
G01X453515Y224882D02*
X453467Y225152D01*
G01X453531Y224608D02*
X453515Y224882D01*
G01X467640Y225152D02*
X467560Y225415D01*
G01X467688Y224882D02*
X467640Y225152D01*
G01X467705Y224608D02*
X467688Y224882D01*
G01X438705Y225062D02*
X438639Y225281D01*
G01X438745Y224836D02*
X438705Y225062D01*
G01X438759Y224608D02*
X438745Y224836D01*
G01X452879Y225062D02*
X452812Y225281D01*
G01X452919Y224836D02*
X452879Y225062D01*
G01X452932Y224608D02*
X452919Y224836D01*
G01X467052Y225062D02*
X466986Y225281D01*
G01X467092Y224836D02*
X467052Y225062D01*
G01X467105Y224608D02*
X467092Y224836D01*
G01X439319Y226792D02*
X439253Y227012D01*
G01X439359Y226567D02*
X439319Y226792D01*
G01X439373Y226338D02*
X439359Y226567D01*
G01X453492Y226792D02*
X453426Y227012D01*
G01X453532Y226567D02*
X453492Y226792D01*
G01X453546Y226338D02*
X453532Y226567D01*
G01X467665Y226792D02*
X467599Y227012D01*
G01X467706Y226567D02*
X467665Y226792D01*
G01X467719Y226338D02*
X467706Y226567D01*
G01X429249Y225061D02*
X429315Y225281D01*
G01X429209Y224836D02*
X429249Y225061D01*
G01X429195Y224608D02*
X429209Y224836D01*
G01X443422Y225061D02*
X443488Y225281D01*
G01X443382Y224836D02*
X443422Y225061D01*
G01X443369Y224608D02*
X443382Y224836D01*
G01X457595Y225061D02*
X457662Y225281D01*
G01X457555Y224836D02*
X457595Y225061D01*
G01X457542Y224608D02*
X457555Y224836D01*
G01X428527Y226800D02*
X428581Y227012D01*
G01X428493Y226585D02*
X428527Y226800D01*
G01X428479Y226372D02*
X428493Y226585D01*
G01X442700Y226800D02*
X442754Y227012D01*
G01X442666Y226585D02*
X442700Y226800D01*
G01X442653Y226372D02*
X442666Y226585D01*
G01X456873Y226800D02*
X456927Y227012D01*
G01X456839Y226585D02*
X456873Y226800D01*
G01X456826Y226372D02*
X456839Y226585D01*
G01X428762Y227627D02*
X428581Y227012D01*
G01X428878Y228109D02*
X428762Y227627D01*
G01X428947Y228533D02*
X428878Y228109D01*
G01X442935Y227627D02*
X442754Y227012D01*
G01X443051Y228109D02*
X442935Y227627D01*
G01X443120Y228533D02*
X443051Y228109D01*
G01X467847Y226585D02*
X467861Y226372D01*
G01X467814Y226800D02*
X467847Y226585D01*
G01X467759Y227012D02*
X467814Y226800D01*
G01X482339Y231015D02*
X482365Y230906D01*
G01X482325Y231081D02*
X482339Y231015D01*
G01X482320Y231103D02*
X482325Y231081D01*
G01X497999Y231226D02*
X497626Y231300D01*
G01X498316Y231017D02*
X497999Y231226D01*
G01X498530Y230704D02*
X498316Y231017D01*
G01X498610Y230333D02*
X498530Y230704D01*
G01X487489Y231168D02*
X487533Y230906D01*
G01X487467Y231300D02*
X487489Y231168D01*
G01X453404Y227630D02*
X453586Y227012D01*
G01X453288Y228113D02*
X453404Y227630D01*
G01X453220Y228533D02*
X453288Y228113D01*
G01X467577Y227630D02*
X467759Y227012D01*
G01X467462Y228113D02*
X467577Y227630D01*
G01X467393Y228533D02*
X467462Y228113D01*
G01X471769Y225061D02*
X471835Y225281D01*
G01X471728Y224836D02*
X471769Y225061D01*
G01X471715Y224608D02*
X471728Y224836D01*
G01X471046Y226800D02*
X471101Y227012D01*
G01X471012Y226585D02*
X471046Y226800D01*
G01X470999Y226372D02*
X471012Y226585D01*
G01X457108Y227627D02*
X456927Y227012D01*
G01X457224Y228109D02*
X457108Y227627D01*
G01X457294Y228533D02*
X457224Y228109D01*
G01X471282Y227627D02*
X471101Y227012D01*
G01X471397Y228109D02*
X471282Y227627D01*
G01X471467Y228533D02*
X471397Y228109D01*
G01X477933Y210617D02*
X477661Y210480D01*
G01X478150Y210830D02*
X477933Y210617D01*
G01X478292Y211100D02*
X478150Y210830D01*
G01X478344Y211401D02*
X478292Y211100D01*
G01X428635Y226567D02*
X428621Y226338D01*
G01X428675Y226792D02*
X428635Y226567D01*
G01X428741Y227012D02*
X428675Y226792D01*
G01X442808Y226567D02*
X442794Y226338D01*
G01X442848Y226792D02*
X442808Y226567D01*
G01X442914Y227012D02*
X442848Y226792D01*
G01X456981Y226567D02*
X456968Y226338D01*
G01X457021Y226792D02*
X456981Y226567D01*
G01X457087Y227012D02*
X457021Y226792D01*
G01X428612Y224882D02*
X428596Y224608D01*
G01X428661Y225152D02*
X428612Y224882D01*
G01X428741Y225415D02*
X428661Y225152D01*
G01X442786Y224882D02*
X442769Y224608D01*
G01X442834Y225152D02*
X442786Y224882D01*
G01X442914Y225415D02*
X442834Y225152D01*
G01X456959Y224882D02*
X456943Y224608D01*
G01X457007Y225152D02*
X456959Y224882D01*
G01X457087Y225415D02*
X457007Y225152D01*
G01X428997Y224836D02*
X428984Y224608D01*
G01X429038Y225061D02*
X428997Y224836D01*
G01X429105Y225281D02*
X429038Y225061D01*
G01X443171Y224836D02*
X443157Y224608D01*
G01X443211Y225061D02*
X443171Y224836D01*
G01X443278Y225281D02*
X443211Y225061D01*
G01X457344Y224836D02*
X457330Y224608D01*
G01X457384Y225061D02*
X457344Y224836D01*
G01X457452Y225281D02*
X457384Y225061D01*
G01X429531Y228734D02*
X429595Y228741D01*
G01X429472Y228715D02*
X429531Y228734D01*
G01X429416Y228683D02*
X429472Y228715D01*
G01X429369Y228641D02*
X429416Y228683D01*
G01X429331Y228591D02*
X429369Y228641D01*
G01X429303Y228533D02*
X429331Y228591D01*
G01X430535Y228734D02*
X430599Y228741D01*
G01X430475Y228715D02*
X430535Y228734D01*
G01X430420Y228683D02*
X430475Y228715D01*
G01X430373Y228641D02*
X430420Y228683D01*
G01X430334Y228591D02*
X430373Y228641D01*
G01X430307Y228533D02*
X430334Y228591D01*
G01X428189Y226582D02*
X428306Y226786D01*
G01X428092Y226378D02*
X428189Y226582D01*
G01X479286Y231226D02*
X479659Y231300D01*
G01X478969Y231017D02*
X479286Y231226D01*
G01X478755Y230704D02*
X478969Y231017D01*
G01X478675Y230333D02*
X478755Y230704D01*
G01X494835Y231081D02*
X494839Y231103D01*
G01X494820Y231017D02*
X494835Y231081D01*
G01X494794Y230906D02*
X494820Y231017D01*
G01X471154Y226567D02*
X471141Y226338D01*
G01X471194Y226792D02*
X471154Y226567D01*
G01X471261Y227012D02*
X471194Y226792D01*
G01X471132Y224882D02*
X471116Y224608D01*
G01X471180Y225152D02*
X471132Y224882D01*
G01X471260Y225415D02*
X471180Y225152D01*
G01X471517Y224836D02*
X471504Y224608D01*
G01X471558Y225061D02*
X471517Y224836D01*
G01X471625Y225281D02*
X471558Y225061D01*
G01X443705Y228734D02*
X443768Y228741D01*
G01X443645Y228715D02*
X443705Y228734D01*
G01X443589Y228683D02*
X443645Y228715D01*
G01X443542Y228641D02*
X443589Y228683D01*
G01X443504Y228591D02*
X443542Y228641D01*
G01X443477Y228533D02*
X443504Y228591D01*
G01X444708Y228734D02*
X444772Y228741D01*
G01X444649Y228715D02*
X444708Y228734D01*
G01X444593Y228683D02*
X444649Y228715D01*
G01X444546Y228641D02*
X444593Y228683D01*
G01X444508Y228591D02*
X444546Y228641D01*
G01X444480Y228533D02*
X444508Y228591D01*
G01X457878Y228734D02*
X457941Y228741D01*
G01X457818Y228715D02*
X457878Y228734D01*
G01X457762Y228683D02*
X457818Y228715D01*
G01X457715Y228641D02*
X457762Y228683D01*
G01X457677Y228591D02*
X457715Y228641D01*
G01X457650Y228533D02*
X457677Y228591D01*
G01X458882Y228734D02*
X458945Y228741D01*
G01X458822Y228715D02*
X458882Y228734D01*
G01X458766Y228683D02*
X458822Y228715D01*
G01X458719Y228641D02*
X458766Y228683D01*
G01X458681Y228591D02*
X458719Y228641D01*
G01X458654Y228533D02*
X458681Y228591D01*
G01X472051Y228734D02*
X472115Y228741D01*
G01X471991Y228715D02*
X472051Y228734D01*
G01X471936Y228683D02*
X471991Y228715D01*
G01X471888Y228641D02*
X471936Y228683D01*
G01X471850Y228591D02*
X471888Y228641D01*
G01X471823Y228533D02*
X471850Y228591D01*
G01X473055Y228734D02*
X473118Y228741D01*
G01X472995Y228715D02*
X473055Y228734D01*
G01X472940Y228683D02*
X472995Y228715D01*
G01X472892Y228641D02*
X472940Y228683D01*
G01X472854Y228591D02*
X472892Y228641D01*
G01X472827Y228533D02*
X472854Y228591D01*
G01X442362Y226582D02*
X442479Y226786D01*
G01X442265Y226378D02*
X442362Y226582D01*
G01X456535D02*
X456653Y226786D01*
G01X456438Y226378D02*
X456535Y226582D01*
G01X470709D02*
X470826Y226786D01*
G01X470611Y226378D02*
X470709Y226582D01*
G01X428608Y227262D02*
X428676Y227395D01*
G01X428529Y227127D02*
X428608Y227262D01*
G01X428306Y226786D02*
X428529Y227127D01*
G01X442781Y227262D02*
X442849Y227395D01*
G01X442702Y227127D02*
X442781Y227262D01*
G01X442479Y226786D02*
X442702Y227127D01*
G01X456954Y227262D02*
X457023Y227395D01*
G01X456876Y227127D02*
X456954Y227262D01*
G01X456653Y226786D02*
X456876Y227127D01*
G01X439286Y228710D02*
X439509Y228741D01*
G01X439128Y228633D02*
X439286Y228710D01*
G01X439046Y228533D02*
X439128Y228633D01*
G01X471128Y227262D02*
X471196Y227395D01*
G01X471049Y227127D02*
X471128Y227262D01*
G01X470826Y226786D02*
X471049Y227127D01*
G01X453459Y228710D02*
X453682Y228741D01*
G01X453301Y228633D02*
X453459Y228710D01*
G01X453220Y228533D02*
X453301Y228633D01*
G01X467632Y228710D02*
X467855Y228741D01*
G01X467474Y228633D02*
X467632Y228710D01*
G01X467393Y228533D02*
X467474Y228633D01*
G01X475560Y209930D02*
X475532Y209646D01*
G01X475642Y210184D02*
X475560Y209930D01*
G01X475769Y210367D02*
X475642Y210184D01*
G01X475926Y210433D02*
X475769Y210367D01*
G01X498610Y230333D02*
G03X497626Y231300I-984J-17D01*
G01X498941Y211401D02*
G03X499925Y210433I984J16D01*
G01X475926D02*
G03X475139Y209646I0J-787D01*
G01X477360Y210433D02*
G03X478344Y211401I0J984D01*
G01X479659Y231300D02*
G03X478675Y230333I0J-984D01*
G01X471642Y226871D02*
G03X471546Y226338I1440J-534D01*
G01X466700Y224608D02*
G03X466604Y225140I-1536J-2D01*
G01X467313Y226338D02*
G03X467218Y226871I-1535J1D01*
G01X472216Y225140D02*
G03X472121Y224608I1441J-532D01*
G01X457468Y226871D02*
G03X457373Y226338I1441J-532D01*
G01X443295Y226871D02*
G03X443200Y226338I1440J-532D01*
G01X438353Y224608D02*
G03X438258Y225140I-1535J0D01*
G01X452527Y224608D02*
G03X452431Y225140I-1536J-2D01*
G01X453140Y226338D02*
G03X453044Y226871I-1536J-1D01*
G01X438967Y226338D02*
G03X438871Y226871I-1536J-1D01*
G01X443870Y225140D02*
G03X443775Y224608I1440J-532D01*
G01X458043Y225140D02*
G03X457948Y224608I1440J-532D01*
G01X429122Y226871D02*
G03X429027Y226338I1440J-532D01*
G01X429697Y225140D02*
G03X429601Y224608I1440J-534D01*
G01X467037Y228533D02*
X466662Y228426D01*
G01X465409D02*
X465783Y228533D01*
G01X452863D02*
X452489Y228426D01*
G01X451236D02*
X451610Y228533D01*
G01X438690D02*
X438316Y228426D01*
G01X437063D02*
X437437Y228533D01*
G01X467560Y225416D02*
X467196Y225281D01*
G01X466986D02*
X466621Y225146D01*
G01X467599Y227012D02*
X467235Y226877D01*
G01X453387Y225416D02*
X453022Y225281D01*
G01X452812D02*
X452448Y225146D01*
G01X453426Y227012D02*
X453062Y226877D01*
G01X439214Y225416D02*
X438849Y225281D01*
G01X438639D02*
X438275Y225146D01*
G01X439253Y227012D02*
X438888Y226877D01*
G01X487823Y230906D02*
X488087Y231017D01*
G01X492740Y231055D02*
X492439Y230906D01*
G01X493520Y222874D02*
X494308Y223662D01*
G01X494856Y230906D02*
X495250Y231300D01*
G01X495036D02*
X494839Y231103D01*
G01X494851Y230906D02*
X495239Y231300D01*
G01X473235Y228741D02*
X471890Y227395D01*
G01X466739Y228741D02*
X465394Y227395D01*
G01X459652Y228741D02*
X458307Y227395D01*
G01X452566Y228741D02*
X451221Y227395D01*
G01X445479Y228741D02*
X444134Y227395D01*
G01X438392Y228741D02*
X437047Y227395D01*
G01X492414Y230906D02*
X492783Y231300D01*
G01X494821Y230906D02*
X495179Y231300D01*
G01X493754Y230906D02*
X494075Y231300D01*
G01X492274Y230906D02*
X492502Y231300D01*
G01X431306Y228741D02*
X429961Y227395D01*
G01X487761Y230906D02*
X487925Y231300D01*
G01X473411Y228426D02*
X472199Y225146D01*
G01X471835Y225281D02*
X473037Y228533D01*
G01X472827D02*
X471625Y225281D01*
G01X471260Y225416D02*
X472373Y228426D01*
G01X471625Y226877D02*
X472186Y228394D01*
G01X471823Y228533D02*
X471261Y227012D01*
G01X459238Y228426D02*
X458026Y225146D01*
G01X457662Y225281D02*
X458864Y228533D01*
G01X458654D02*
X457452Y225281D01*
G01X457087Y225416D02*
X458200Y228426D01*
G01X457452Y226877D02*
X458013Y228394D01*
G01X457650Y228533D02*
X457087Y227012D01*
G01X493571Y230906D02*
X493709Y231300D01*
G01X494834Y231081D02*
X494820Y231016D01*
G01X489670Y231168D02*
X489692Y231300D01*
G01X489626Y230906D02*
X489692Y231300D01*
G01X445065Y228426D02*
X443853Y225146D01*
G01X443488Y225281D02*
X444690Y228533D01*
G01X444480D02*
X443278Y225281D01*
G01X442914Y225416D02*
X444026Y228426D01*
G01X443279Y226877D02*
X443839Y228394D01*
G01X443477Y228533D02*
X442914Y227012D01*
G01X430892Y228426D02*
X429680Y225146D01*
G01X429315Y225281D02*
X430517Y228533D01*
G01X430307D02*
X429105Y225281D01*
G01X428741Y225416D02*
X429853Y228426D01*
G01X429105Y226877D02*
X429666Y228394D01*
G01X429303Y228533D02*
X428741Y227012D01*
G01X479659Y230333D02*
X479329Y211401D01*
G01X478675Y230333D02*
X478344Y211401D01*
G01X470999Y226372D02*
Y226338D01*
G01X470611D02*
Y226378D01*
G01X497956Y211401D02*
Y210433D01*
G01X497930Y223662D02*
Y231252D01*
G01X497626Y230333D02*
Y231300D01*
G01X496385Y230906D02*
Y231300D01*
G01X496344Y230906D02*
Y231300D01*
G01X496262D02*
Y230906D01*
G01X496221Y231300D02*
Y230906D01*
G01X496139Y231300D02*
Y230906D01*
G01X496098Y231300D02*
Y230906D01*
G01X496016Y231300D02*
Y230906D01*
G01X495975Y231300D02*
Y230906D01*
G01X495934Y231300D02*
Y230906D01*
G01X495893Y231300D02*
Y230906D01*
G01X495829Y231300D02*
Y307325D01*
G01X495770Y231300D02*
Y230906D01*
G01X495729Y231300D02*
Y230906D01*
G01X494991Y231300D02*
Y230906D01*
G01X494839Y231103D02*
Y231300D01*
G01X494745D02*
Y230906D01*
G01X489299D02*
Y231300D01*
G01X489135Y230906D02*
Y231300D01*
G01X489053Y230906D02*
Y231300D01*
G01X488971D02*
Y230906D01*
G01X488889D02*
Y231300D01*
G01X488848D02*
Y230906D01*
G01X488642D02*
Y231300D01*
G01X488478Y230906D02*
Y231300D01*
G01X488314D02*
Y230906D01*
G01X488109Y231300D02*
Y230906D01*
G01X488068D02*
Y231300D01*
G01X487904D02*
Y230906D01*
G01X487658Y231300D02*
Y230906D01*
G01X482999D02*
Y231300D01*
G01X482835Y230906D02*
Y231300D01*
G01X482753D02*
Y230906D01*
G01X482671Y231300D02*
Y230906D01*
G01X482320Y231103D02*
Y231300D01*
G01X481605D02*
Y230906D01*
G01X481359D02*
Y231300D01*
G01X481329D02*
Y307325D01*
G01X479659Y230333D02*
Y231300D01*
G01X479329Y211401D02*
Y210433D01*
G01X479229Y231201D02*
Y223662D01*
G01X473411Y228426D02*
Y228741D01*
G01X472373Y228426D02*
Y228741D01*
G01X472186D02*
Y220867D01*
G01X498610Y230333D02*
X498941Y211401D01*
G01X497626Y230333D02*
X497956Y211401D01*
G01X487489Y231168D02*
X487467Y231300D01*
G01X482324Y231081D02*
X482320Y231103D01*
G01X482365Y230906D02*
X482339Y231017D01*
G01X483588Y230906D02*
X483450Y231300D01*
G01X489398Y230906D02*
X489234Y231300D01*
G01X456826Y226372D02*
X456825Y226338D01*
G01X456438D02*
Y226378D01*
G01X442653Y226372D02*
X442652Y226338D01*
G01X442264D02*
X442265Y226378D01*
G01X428479Y226372D02*
Y226338D01*
G01X428091D02*
X428092Y226378D01*
G01X466662Y228741D02*
Y228426D01*
G01X466447D02*
Y228741D01*
G01X465409D02*
Y228426D01*
G01X465263Y228741D02*
Y220867D01*
G01X460735D02*
Y228741D01*
G01X460375D02*
Y220867D01*
G01X459238Y228426D02*
Y228741D01*
G01X458200Y228426D02*
Y228741D01*
G01X458013D02*
Y220867D01*
G01X452489Y228741D02*
Y228426D01*
G01X452274D02*
Y228741D01*
G01X451236D02*
Y228426D01*
G01X451089Y228741D02*
Y220867D01*
G01X446562D02*
Y228741D01*
G01X446202D02*
Y220867D01*
G01X445065Y228426D02*
Y228741D01*
G01X444026Y228426D02*
Y228741D01*
G01X443839D02*
Y220867D01*
G01X438316Y228741D02*
Y228426D01*
G01X438101D02*
Y228741D01*
G01X437063D02*
Y228426D01*
G01X436916Y228741D02*
Y220867D01*
G01X432389D02*
Y228741D01*
G01X432028D02*
Y220867D01*
G01X430892Y228426D02*
Y228741D01*
G01X429853Y228426D02*
Y228741D01*
G01X429666D02*
Y220867D01*
G01X467861Y226372D02*
Y226338D01*
G01X453688Y226372D02*
Y226338D01*
G01X439514Y226372D02*
X439515Y226338D01*
G01X468248Y226378D02*
X468249Y226338D01*
G01X454075Y226378D02*
X454076Y226338D01*
G01X439902Y226378D02*
Y226338D01*
G01X467599Y227012D02*
X467037Y228533D01*
G01X466662Y228426D02*
X467235Y226877D01*
G01X466447Y228426D02*
X467560Y225416D01*
G01X467196Y225281D02*
X465994Y228533D01*
G01X465783D02*
X466986Y225281D01*
G01X466621Y225146D02*
X465409Y228426D01*
G01X453426Y227012D02*
X452864Y228533D01*
G01X452489Y228426D02*
X453062Y226877D01*
G01X452274Y228426D02*
X453387Y225416D01*
G01X453022Y225281D02*
X451820Y228533D01*
G01X451610D02*
X452812Y225281D01*
G01X452448Y225146D02*
X451236Y228426D01*
G01X439253Y227012D02*
X438690Y228533D01*
G01X484885Y230906D02*
X484657Y231300D01*
G01X484885Y230906D02*
X484657Y231300D01*
G01X438316Y228426D02*
X438888Y226877D01*
G01X438101Y228426D02*
X439214Y225416D01*
G01X438849Y225281D02*
X437647Y228533D01*
G01X437437D02*
X438639Y225281D01*
G01X438275Y225146D02*
X437063Y228426D01*
G01X483405Y230906D02*
X483084Y231300D01*
G01X482338Y230906D02*
X481980Y231300D01*
G01X484745Y230906D02*
X484376Y231300D01*
G01X481920D02*
X482308Y230906D01*
G01X482123Y231300D02*
X482320Y231103D01*
G01X482303Y230906D02*
X481909Y231300D01*
G01X483639Y222874D02*
X482851Y223662D01*
G01X467920Y228741D02*
X469265Y227395D01*
G01X460833Y228741D02*
X462179Y227395D01*
G01X455092D02*
X453747Y228741D01*
G01X493508Y230906D02*
X493257Y231055D01*
G01X448005Y227395D02*
X446660Y228741D01*
G01X440919Y227395D02*
X439574Y228741D01*
G01X433832Y227395D02*
X432487Y228741D01*
G01X484720Y230906D02*
X484419Y231055D01*
G01X489336Y230906D02*
X489071Y231017D01*
G01X471261Y227012D02*
X471625Y226877D01*
G01X472199Y225146D02*
X471835Y225281D01*
G01X471625D02*
X471260Y225415D01*
G01X457087Y227012D02*
X457452Y226877D01*
G01X458026Y225146D02*
X457662Y225281D01*
G01X457452D02*
X457087Y225415D01*
G01X442914Y227012D02*
X443278Y226877D01*
G01X443853Y225146D02*
X443488Y225281D01*
G01X443278D02*
X442914Y225415D01*
G01X428741Y227012D02*
X429105Y226877D01*
G01X473411Y228426D02*
X473037Y228533D01*
G01X471823D02*
X472186Y228429D01*
G01X458864Y228533D02*
X459238Y228426D01*
G01X457650Y228533D02*
X458013Y228429D01*
G01X444690Y228533D02*
X445065Y228426D01*
G01X443477Y228533D02*
X443839Y228429D01*
G01X430517Y228533D02*
X430892Y228426D01*
G01X429303Y228533D02*
X429666Y228429D01*
G01X488822Y231082D02*
X489075Y231016D01*
G01X484153Y231103D02*
X484419Y231055D01*
G01X498585Y230336D02*
X498610Y230333D01*
G01X488579Y231103D02*
X488826Y231081D01*
G01X470611Y226378D02*
X470999Y226372D01*
G01X456438Y226378D02*
X456826Y226372D01*
G01X442265Y226378D02*
X442653Y226372D01*
G01X428092Y226378D02*
X428479Y226372D01*
G01X479231Y230338D02*
X479659Y230333D01*
G01X497626Y231300D02*
X479659D01*
G01X489299Y230906D02*
X484720D01*
G01X483651D02*
X481359D01*
G01X492439D02*
X489336D01*
G01X496385D02*
X493508D01*
G01X497626Y230333D02*
X479659D01*
G01X452864Y228533D02*
X453220D01*
G01X438690D02*
X439046D01*
G01X471467D02*
X471823D01*
G01X467037D02*
X467393D01*
G01X457294D02*
X457650D01*
G01X443120D02*
X443477D01*
G01X428947D02*
X429303D01*
G01X430517D02*
X430307D01*
G01X437647D02*
X437437D01*
G01X444690D02*
X444480D01*
G01X451820D02*
X451610D01*
G01X458864D02*
X458654D01*
G01X465994D02*
X465783D01*
G01X473037D02*
X472827D01*
G01X444026Y228426D02*
X430892D01*
G01X458200D02*
X445065D01*
G01X472373D02*
X459238D01*
G01X473629D02*
X473411D01*
G01X436916Y228253D02*
X432389D01*
G01X432028D02*
X429666D01*
G01X446202D02*
X443839D01*
G01X451089D02*
X446562D01*
G01X460375D02*
X458013D01*
G01X465263D02*
X460735D01*
G01X473629D02*
X472186D01*
G01X437047Y227395D02*
X433832D01*
G01X444134D02*
X439317D01*
G01X451221D02*
X448005D01*
G01X458307D02*
X453491D01*
G01X465394D02*
X462179D01*
G01X471890D02*
X467664D01*
G01X471101Y227012D02*
X471261D01*
G01X456927D02*
X457087D01*
G01X442754D02*
X442914D01*
G01X428581D02*
X428741D01*
G01X439413D02*
X439253D01*
G01X453586D02*
X453426D01*
G01X467759D02*
X467599D01*
G01X470611Y226338D02*
X471529D01*
G01X467331D02*
X468249D01*
G01X456438D02*
X457355D01*
G01X453158D02*
X454076D01*
G01X442264D02*
X443182D01*
G01X438985D02*
X439902D01*
G01X428091D02*
X429009D01*
G01X436227Y225788D02*
X432301D01*
G01X450400D02*
X446475D01*
G01X464574D02*
X460648D01*
G01X438849Y225281D02*
X438639D01*
G01X453022D02*
X452812D01*
G01X429315D02*
X429105D01*
G01X443488D02*
X443278D01*
G01X457662D02*
X457452D01*
G01X467196D02*
X466986D01*
G01X471835D02*
X471625D01*
G01X466718Y224608D02*
X467705D01*
G01X456943D02*
X457930D01*
G01X452544D02*
X453531D01*
G01X442769D02*
X443756D01*
G01X438371D02*
X439358D01*
G01X428596D02*
X429583D01*
G01X472103D02*
X471116D01*
G01X439902Y226378D02*
X439514Y226372D01*
G01X454075Y226378D02*
X453688Y226372D01*
G01X468248Y226378D02*
X467861Y226372D01*
G01X488579Y231103D02*
X488332Y231081D01*
G01X429853Y228426D02*
X430230Y228514D01*
G01X444026Y228426D02*
X444404Y228514D01*
G01X458200Y228426D02*
X458577Y228514D01*
G01X472373Y228426D02*
X472750Y228514D01*
G01X430230D02*
X430307Y228533D01*
G01X444404Y228514D02*
X444480Y228533D01*
G01X458577Y228514D02*
X458654Y228533D01*
G01X472750Y228514D02*
X472827Y228533D01*
G01X488083Y231016D02*
X488336Y231081D01*
G01X429315Y225281D02*
X429680Y225146D01*
G01X429105Y225281D02*
X428741Y225415D01*
G01X498334Y211396D02*
X497956Y211401D01*
G01X498331Y211396D02*
X498654Y211394D01*
G01X478558Y223662D02*
X498727D01*
G01X493520Y222874D02*
X483639D01*
G01X473629Y220866D02*
X472186D01*
G01X436916Y220867D02*
X432389D01*
G01X432028D02*
X429666D01*
G01X446202D02*
X443839D01*
G01X451089D02*
X446562D01*
G01X460375D02*
X458013D01*
G01X465263D02*
X460735D01*
G01X497956Y211401D02*
X479329D01*
G01X500729Y210433D02*
X475926D01*
G01X475139Y209646D02*
X501517D01*
G01X478631Y211394D02*
X478954Y211396D01*
G01X498651Y211394D02*
X498865Y211396D01*
G01X478951D02*
X479329Y211401D01*
G01X498941D02*
X498866Y211396D01*
G01X477661Y210480D02*
X477360Y210433D01*
G01X490284Y316930D02*
G03X486875I-1705J-985D01*
G01D02*
X481329Y307325D01*
G01X490284Y316930D02*
X495829Y307325D01*
G01X486875Y316930D02*
X490284D01*
G01X481329Y307325D02*
X495829D01*
G01X490789Y356293D02*
G03I-4291J0D01*
G01X518086Y-714465D02*
Y-733402D01*
G01X533288Y-714465D02*
X1183722D01*
G01X500782Y122058D02*
X500863Y121822D01*
G01X500654Y122273D02*
X500782Y122058D01*
G01X500485Y122459D02*
X500654Y122273D01*
G01X500283Y122614D02*
X500485Y122459D01*
G01X500055Y122737D02*
X500283Y122614D01*
G01X500863Y121386D02*
X500892Y121022D01*
G01X500780Y121736D02*
X500863Y121386D01*
G01X500647Y122057D02*
X500780Y121736D01*
G01X500475Y122335D02*
X500647Y122057D01*
G01X500273Y122563D02*
X500475Y122335D01*
G01X500055Y122737D02*
X500273Y122563D01*
G01X507950Y121386D02*
X507979Y121022D01*
G01X507866Y121736D02*
X507950Y121386D01*
G01X507734Y122057D02*
X507866Y121736D01*
G01X507561Y122335D02*
X507734Y122057D01*
G01X507360Y122563D02*
X507561Y122335D01*
G01X507142Y122737D02*
X507360Y122563D01*
G01X515037Y121386D02*
X515066Y121022D01*
G01X514953Y121736D02*
X515037Y121386D01*
G01X514821Y122057D02*
X514953Y121736D01*
G01X514648Y122335D02*
X514821Y122057D01*
G01X514446Y122563D02*
X514648Y122335D01*
G01X514228Y122737D02*
X514446Y122563D01*
G01X522123Y121386D02*
X522152Y121022D01*
G01X522040Y121736D02*
X522123Y121386D01*
G01X521907Y122057D02*
X522040Y121736D01*
G01X521734Y122335D02*
X521907Y122057D01*
G01X521533Y122563D02*
X521734Y122335D01*
G01X521315Y122737D02*
X521533Y122563D01*
G01X529210Y121386D02*
X529239Y121022D01*
G01X529126Y121736D02*
X529210Y121386D01*
G01X528994Y122057D02*
X529126Y121736D01*
G01X528821Y122335D02*
X528994Y122057D01*
G01X528620Y122563D02*
X528821Y122335D01*
G01X528401Y122737D02*
X528620Y122563D01*
G01X536297Y121386D02*
X536326Y121022D01*
G01X536213Y121736D02*
X536297Y121386D01*
G01X536080Y122057D02*
X536213Y121736D01*
G01X535908Y122335D02*
X536080Y122057D01*
G01X535706Y122563D02*
X535908Y122335D01*
G01X535488Y122737D02*
X535706Y122563D01*
G01X543383Y121386D02*
X543412Y121022D01*
G01X543300Y121736D02*
X543383Y121386D01*
G01X543167Y122057D02*
X543300Y121736D01*
G01X542994Y122335D02*
X543167Y122057D01*
G01X542793Y122563D02*
X542994Y122335D01*
G01X542575Y122737D02*
X542793Y122563D01*
G01X550470Y121386D02*
X550499Y121022D01*
G01X550386Y121736D02*
X550470Y121386D01*
G01X550254Y122057D02*
X550386Y121736D01*
G01X550081Y122335D02*
X550254Y122057D01*
G01X549879Y122563D02*
X550081Y122335D01*
G01X549661Y122737D02*
X549879Y122563D01*
G01X557556Y121386D02*
X557585Y121022D01*
G01X557473Y121736D02*
X557556Y121386D01*
G01X557340Y122057D02*
X557473Y121736D01*
G01X557168Y122335D02*
X557340Y122057D01*
G01X556966Y122563D02*
X557168Y122335D01*
G01X556748Y122737D02*
X556966Y122563D01*
G01X507507Y122515D02*
X507142Y122737D01*
G01X507770Y122234D02*
X507507Y122515D01*
G01X507926Y121921D02*
X507770Y122234D01*
G01X507979Y121593D02*
X507926Y121921D01*
G01X500885Y121717D02*
X500863Y121838D01*
G01X500892Y121593D02*
X500885Y121717D01*
G01X514594Y122515D02*
X514228Y122737D01*
G01X514856Y122234D02*
X514594Y122515D01*
G01X515013Y121921D02*
X514856Y122234D01*
G01X515066Y121593D02*
X515013Y121921D01*
G01X521681Y122515D02*
X521315Y122737D01*
G01X521943Y122234D02*
X521681Y122515D01*
G01X522100Y121921D02*
X521943Y122234D01*
G01X522152Y121593D02*
X522100Y121921D01*
G01X528767Y122515D02*
X528401Y122737D01*
G01X529030Y122234D02*
X528767Y122515D01*
G01X529186Y121921D02*
X529030Y122234D01*
G01X529239Y121593D02*
X529186Y121921D01*
G01X535854Y122515D02*
X535488Y122737D01*
G01X536116Y122234D02*
X535854Y122515D01*
G01X536273Y121921D02*
X536116Y122234D01*
G01X536326Y121593D02*
X536273Y121921D01*
G01X542940Y122515D02*
X542575Y122737D01*
G01X543203Y122234D02*
X542940Y122515D01*
G01X543359Y121921D02*
X543203Y122234D01*
G01X543412Y121593D02*
X543359Y121921D01*
G01X505468Y122563D02*
X505687Y122737D01*
G01X505267Y122335D02*
X505468Y122563D01*
G01X505094Y122057D02*
X505267Y122335D01*
G01X504962Y121736D02*
X505094Y122057D01*
G01X504878Y121386D02*
X504962Y121736D01*
G01X504849Y121022D02*
X504878Y121386D01*
G01X512555Y122563D02*
X512773Y122737D01*
G01X512354Y122335D02*
X512555Y122563D01*
G01X512181Y122057D02*
X512354Y122335D01*
G01X512048Y121736D02*
X512181Y122057D01*
G01X511965Y121386D02*
X512048Y121736D01*
G01X511936Y121022D02*
X511965Y121386D01*
G01X519642Y122563D02*
X519860Y122737D01*
G01X519440Y122335D02*
X519642Y122563D01*
G01X519267Y122057D02*
X519440Y122335D01*
G01X519135Y121736D02*
X519267Y122057D01*
G01X519051Y121386D02*
X519135Y121736D01*
G01X519022Y121022D02*
X519051Y121386D01*
G01X526728Y122563D02*
X526947Y122737D01*
G01X526527Y122335D02*
X526728Y122563D01*
G01X526354Y122057D02*
X526527Y122335D01*
G01X526222Y121736D02*
X526354Y122057D01*
G01X526138Y121386D02*
X526222Y121736D01*
G01X526109Y121022D02*
X526138Y121386D01*
G01X550027Y122515D02*
X549661Y122737D01*
G01X550289Y122234D02*
X550027Y122515D01*
G01X550446Y121921D02*
X550289Y122234D01*
G01X550499Y121593D02*
X550446Y121921D01*
G01X557114Y122515D02*
X556748Y122737D01*
G01X557376Y122234D02*
X557114Y122515D01*
G01X557533Y121921D02*
X557376Y122234D01*
G01X557585Y121593D02*
X557533Y121921D01*
G01X533815Y122563D02*
X534033Y122737D01*
G01X533614Y122335D02*
X533815Y122563D01*
G01X533441Y122057D02*
X533614Y122335D01*
G01X533308Y121736D02*
X533441Y122057D01*
G01X533225Y121386D02*
X533308Y121736D01*
G01X533196Y121022D02*
X533225Y121386D01*
G01X540902Y122563D02*
X541120Y122737D01*
G01X540700Y122335D02*
X540902Y122563D01*
G01X540527Y122057D02*
X540700Y122335D01*
G01X540395Y121736D02*
X540527Y122057D01*
G01X540311Y121386D02*
X540395Y121736D01*
G01X540282Y121022D02*
X540311Y121386D01*
G01X547988Y122563D02*
X548206Y122737D01*
G01X547787Y122335D02*
X547988Y122563D01*
G01X547614Y122057D02*
X547787Y122335D01*
G01X547481Y121736D02*
X547614Y122057D01*
G01X547398Y121386D02*
X547481Y121736D01*
G01X547369Y121022D02*
X547398Y121386D01*
G01X555075Y122563D02*
X555293Y122737D01*
G01X554873Y122335D02*
X555075Y122563D01*
G01X554701Y122057D02*
X554873Y122335D01*
G01X554568Y121736D02*
X554701Y122057D01*
G01X554484Y121386D02*
X554568Y121736D01*
G01X554455Y121022D02*
X554484Y121386D01*
G01X505225Y122429D02*
X505687Y122737D01*
G01X504943Y122029D02*
X505225Y122429D01*
G01X504849Y121593D02*
X504943Y122029D01*
G01X512311Y122429D02*
X512773Y122737D01*
G01X512030Y122029D02*
X512311Y122429D01*
G01X511936Y121593D02*
X512030Y122029D01*
G01X519398Y122429D02*
X519860Y122737D01*
G01X519117Y122029D02*
X519398Y122429D01*
G01X519022Y121593D02*
X519117Y122029D01*
G01X526485Y122429D02*
X526947Y122737D01*
G01X526203Y122029D02*
X526485Y122429D01*
G01X526109Y121593D02*
X526203Y122029D01*
G01X533571Y122429D02*
X534033Y122737D01*
G01X533290Y122029D02*
X533571Y122429D01*
G01X533196Y121593D02*
X533290Y122029D01*
G01X540658Y122429D02*
X541120Y122737D01*
G01X540376Y122029D02*
X540658Y122429D01*
G01X540282Y121593D02*
X540376Y122029D01*
G01X547744Y122429D02*
X548206Y122737D01*
G01X547463Y122029D02*
X547744Y122429D01*
G01X547369Y121593D02*
X547463Y122029D01*
G01X554831Y122429D02*
X555293Y122737D01*
G01X554550Y122029D02*
X554831Y122429D01*
G01X554455Y121593D02*
X554550Y122029D01*
G01X542835Y131496D02*
G03I-709J0D01*
G01X535748Y130709D02*
G03I-708J0D01*
G01X557008Y131496D02*
G03I-708J0D01*
G01X549922Y130709D02*
G03I-709J0D01*
G01X535748Y126378D02*
G03I-708J0D01*
G01X542835Y125985D02*
G03I-709J0D01*
G01Y121654D02*
G03I-709J0D01*
G01X549922Y126378D02*
G03I-709J0D01*
G01X557008Y125985D02*
G03I-708J0D01*
G01Y121654D02*
G03I-708J0D01*
G01X542579Y122745D02*
G03X541115I-732J-1394D01*
G01X549666D02*
G03X548202I-732J-1394D01*
G01X556752D02*
G03X555288I-732J-1394D01*
G01X514489Y131496D02*
G03I-709J0D01*
G01X528662D02*
G03I-709J0D01*
G01X521575Y130709D02*
G03I-708J0D01*
G01X514489Y125985D02*
G03I-709J0D01*
G01Y121654D02*
G03I-709J0D01*
G01X521575Y126378D02*
G03I-708J0D01*
G01X528662Y125985D02*
G03I-709J0D01*
G01Y121654D02*
G03I-709J0D01*
G01X514233Y122745D02*
G03X512769I-732J-1394D01*
G01X521319D02*
G03X519855I-732J-1394D01*
G01X528406D02*
G03X526942I-732J-1394D01*
G01X535493D02*
G03X534029I-732J-1394D01*
G01X507402Y130709D02*
G03I-709J0D01*
G01Y126378D02*
G03I-709J0D01*
G01X507146Y122745D02*
G03X505682I-732J-1394D01*
G01X557556Y115256D02*
X556375Y114075D01*
G01X507950Y115256D02*
X506768Y114075D01*
G01X500863Y115256D02*
X499682Y114075D01*
G01X559017Y113091D02*
Y190158D01*
G01X558996Y116437D02*
Y113091D01*
G01Y120493D02*
Y118012D01*
G01X557585Y121593D02*
Y115650D01*
G01X557556Y118012D02*
Y115256D01*
G01X554485Y118012D02*
Y115256D01*
G01X554455Y121593D02*
Y115650D01*
G01X550499Y121593D02*
Y115650D01*
G01X547369Y121593D02*
Y115650D01*
G01X543412Y121593D02*
Y115650D01*
G01X540282Y121593D02*
Y115650D01*
G01X536326Y121593D02*
Y115650D01*
G01X533196Y121593D02*
Y115650D01*
G01X529239Y121593D02*
Y115650D01*
G01X526109Y121593D02*
Y115650D01*
G01X522152Y121593D02*
Y115650D01*
G01X519022Y121593D02*
Y115650D01*
G01X515066Y121593D02*
Y115650D01*
G01X511936Y121593D02*
Y115650D01*
G01X507979Y121593D02*
Y115650D01*
G01X507950Y115256D02*
Y118012D01*
G01X504879D02*
Y115256D01*
G01X504849Y121593D02*
Y115650D01*
G01X502858Y201805D02*
Y113091D01*
G01X501517D02*
Y209646D01*
G01X500892Y121593D02*
Y115650D01*
G01X500863Y125886D02*
Y115256D01*
G01X554485D02*
X555666Y114075D01*
G01X504879Y115256D02*
X506060Y114075D01*
G01X558996Y126536D02*
X502858D01*
G01X500863Y125886D02*
X501517D01*
G01X500055Y122737D02*
X505687D01*
G01X512773D02*
X507142D01*
G01X519860D02*
X514228D01*
G01X526947D02*
X521315D01*
G01X534033D02*
X528401D01*
G01X541120D02*
X535488D01*
G01X548206D02*
X542575D01*
G01X555293D02*
X549661D01*
G01X559017D02*
X556748D01*
G01X558996Y120493D02*
X502858D01*
G01X558996Y120020D02*
X502858D01*
G01X501517Y118085D02*
X500892D01*
G01X558996Y116437D02*
X502858D01*
G01X507950Y115256D02*
X504879D01*
G01X557556D02*
X554485D01*
G01X506768Y114075D02*
X506060D01*
G01X556375D02*
X555666D01*
G01X558996Y113091D02*
X502858D01*
G01X560237Y261975D02*
Y196851D01*
G01X557340Y190749D02*
X557324Y190748D01*
G01X557356Y190751D02*
X557340Y190749D01*
G01X557372Y190755D02*
X557356Y190751D01*
G01X556523Y202464D02*
X556543Y202526D01*
G01X556484Y202405D02*
X556523Y202464D01*
G01X556431Y202353D02*
X556484Y202405D01*
G01X556364Y202309D02*
X556431Y202353D01*
G01X556287Y202275D02*
X556364Y202309D01*
G01X556203Y202254D02*
X556287Y202275D01*
G01X542350Y202464D02*
X542370Y202526D01*
G01X542311Y202405D02*
X542350Y202464D01*
G01X542257Y202353D02*
X542311Y202405D01*
G01X542190Y202309D02*
X542257Y202353D01*
G01X542113Y202275D02*
X542190Y202309D01*
G01X542030Y202254D02*
X542113Y202275D01*
G01X528176Y202464D02*
X528196Y202526D01*
G01X528138Y202405D02*
X528176Y202464D01*
G01X528084Y202353D02*
X528138Y202405D01*
G01X528017Y202309D02*
X528084Y202353D01*
G01X527940Y202275D02*
X528017Y202309D01*
G01X527857Y202254D02*
X527940Y202275D01*
G01X514003Y202464D02*
X514023Y202526D01*
G01X513965Y202405D02*
X514003Y202464D01*
G01X513911Y202353D02*
X513965Y202405D01*
G01X513844Y202309D02*
X513911Y202353D01*
G01X513767Y202275D02*
X513844Y202309D01*
G01X513683Y202254D02*
X513767Y202275D01*
G01X507734Y190749D02*
X507718Y190748D01*
G01X507750Y190751D02*
X507734Y190749D01*
G01X507766Y190755D02*
X507750Y190751D01*
G01X543333Y200747D02*
X543348Y200821D01*
G01X543291Y200682D02*
X543333Y200747D01*
G01X543228Y200640D02*
X543291Y200682D01*
G01X543151Y200624D02*
X543228Y200640D01*
G01X529160Y200747D02*
X529175Y200821D01*
G01X529118Y200682D02*
X529160Y200747D01*
G01X529055Y200640D02*
X529118Y200682D01*
G01X528978Y200624D02*
X529055Y200640D01*
G01X514987Y200747D02*
X515002Y200821D01*
G01X514945Y200682D02*
X514987Y200747D01*
G01X514881Y200640D02*
X514945Y200682D01*
G01X514805Y200624D02*
X514881Y200640D01*
G01X556706Y201438D02*
X556724Y201496D01*
G01X556672Y201384D02*
X556706Y201438D01*
G01X556623Y201333D02*
X556672Y201384D01*
G01X556563Y201290D02*
X556623Y201333D01*
G01X556493Y201255D02*
X556563Y201290D01*
G01X556417Y201231D02*
X556493Y201255D01*
G01X556337Y201218D02*
X556417Y201231D01*
G01X514186Y201438D02*
X514205Y201496D01*
G01X514153Y201384D02*
X514186Y201438D01*
G01X514104Y201333D02*
X514153Y201384D01*
G01X514043Y201290D02*
X514104Y201333D01*
G01X513973Y201255D02*
X514043Y201290D01*
G01X513897Y201231D02*
X513973Y201255D01*
G01X513817Y201218D02*
X513897Y201231D01*
G01X556195Y202252D02*
X556203Y202254D01*
G01X556186Y202251D02*
X556195Y202252D01*
G01X556178Y202250D02*
X556186Y202251D01*
G01X556170Y202249D02*
X556178Y202250D01*
G01X556162Y202248D02*
X556170Y202249D01*
G01X556155Y202247D02*
X556162Y202248D01*
G01X542021Y202252D02*
X542030Y202254D01*
G01X542013Y202251D02*
X542021Y202252D01*
G01X542005Y202250D02*
X542013Y202251D01*
G01X541997Y202249D02*
X542005Y202250D01*
G01X541989Y202248D02*
X541997Y202249D01*
G01X541982Y202247D02*
X541989Y202248D01*
G01X527848Y202252D02*
X527857Y202254D01*
G01X527840Y202251D02*
X527848Y202252D01*
G01X527832Y202250D02*
X527840Y202251D01*
G01X527824Y202249D02*
X527832Y202250D01*
G01X527816Y202248D02*
X527824Y202249D01*
G01X527809Y202247D02*
X527816Y202248D01*
G01X513675Y202252D02*
X513683Y202254D01*
G01X513667Y202251D02*
X513675Y202252D01*
G01X513659Y202250D02*
X513667Y202251D01*
G01X513650Y202249D02*
X513659Y202250D01*
G01X513642Y202248D02*
X513650Y202249D01*
G01X513635Y202247D02*
X513642Y202248D01*
G01X517363Y190836D02*
X517334Y190882D01*
G01X517396Y190798D02*
X517363Y190836D01*
G01X517436Y190770D02*
X517396Y190798D01*
G01X517481Y190754D02*
X517436Y190770D01*
G01X517526Y190748D02*
X517481Y190754D01*
G01X531536Y190836D02*
X531508Y190882D01*
G01X531569Y190798D02*
X531536Y190836D01*
G01X531610Y190770D02*
X531569Y190798D01*
G01X531655Y190754D02*
X531610Y190770D01*
G01X531700Y190748D02*
X531655Y190754D01*
G01X545709Y190836D02*
X545681Y190882D01*
G01X545742Y190798D02*
X545709Y190836D01*
G01X545783Y190770D02*
X545742Y190798D01*
G01X545828Y190754D02*
X545783Y190770D01*
G01X545873Y190748D02*
X545828Y190754D01*
G01X511427Y200763D02*
X511419Y200821D01*
G01X511450Y200714D02*
X511427Y200763D01*
G01X511483Y200675D02*
X511450Y200714D01*
G01X511524Y200646D02*
X511483Y200675D01*
G01X511570Y200629D02*
X511524Y200646D01*
G01X511616Y200624D02*
X511570Y200629D01*
G01X525601Y200763D02*
X525592Y200821D01*
G01X525623Y200714D02*
X525601Y200763D01*
G01X525656Y200675D02*
X525623Y200714D01*
G01X525697Y200646D02*
X525656Y200675D01*
G01X525743Y200629D02*
X525697Y200646D01*
G01X525789Y200624D02*
X525743Y200629D01*
G01X539774Y200763D02*
X539765Y200821D01*
G01X539796Y200714D02*
X539774Y200763D01*
G01X539830Y200675D02*
X539796Y200714D01*
G01X539870Y200646D02*
X539830Y200675D01*
G01X539916Y200629D02*
X539870Y200646D01*
G01X539962Y200624D02*
X539916Y200629D01*
G01X553947Y200763D02*
X553939Y200821D01*
G01X553970Y200714D02*
X553947Y200763D01*
G01X554003Y200675D02*
X553970Y200714D01*
G01X554044Y200646D02*
X554003Y200675D01*
G01X554089Y200629D02*
X554044Y200646D01*
G01X554135Y200624D02*
X554089Y200629D01*
G01X523847Y201438D02*
X523828Y201496D01*
G01X523880Y201384D02*
X523847Y201438D01*
G01X523929Y201333D02*
X523880Y201384D01*
G01X523990Y201290D02*
X523929Y201333D01*
G01X524060Y201255D02*
X523990Y201290D01*
G01X524136Y201231D02*
X524060Y201255D01*
G01X524216Y201218D02*
X524136Y201231D01*
G01X538020Y201438D02*
X538002Y201496D01*
G01X538054Y201384D02*
X538020Y201438D01*
G01X538103Y201333D02*
X538054Y201384D01*
G01X538163Y201290D02*
X538103Y201333D01*
G01X538233Y201255D02*
X538163Y201290D01*
G01X538309Y201231D02*
X538233Y201255D01*
G01X538389Y201218D02*
X538309Y201231D01*
G01X552193Y201438D02*
X552175Y201496D01*
G01X552227Y201384D02*
X552193Y201438D01*
G01X552276Y201333D02*
X552227Y201384D01*
G01X552336Y201290D02*
X552276Y201333D01*
G01X552406Y201255D02*
X552336Y201290D01*
G01X552483Y201231D02*
X552406Y201255D01*
G01X552563Y201218D02*
X552483Y201231D01*
G01X510216Y202248D02*
X510224Y202247D01*
G01X510208Y202249D02*
X510216Y202248D01*
G01X510199Y202250D02*
X510208Y202249D01*
G01X510191Y202251D02*
X510199Y202250D01*
G01X510183Y202252D02*
X510191Y202251D01*
G01X510176Y202254D02*
X510183Y202252D01*
G01X524389Y202248D02*
X524398Y202247D01*
G01X524381Y202249D02*
X524389Y202248D01*
G01X524373Y202250D02*
X524381Y202249D01*
G01X524364Y202251D02*
X524373Y202250D01*
G01X524356Y202252D02*
X524364Y202251D01*
G01X524350Y202254D02*
X524356Y202252D01*
G01X538562Y202248D02*
X538571Y202247D01*
G01X538554Y202249D02*
X538562Y202248D01*
G01X538546Y202250D02*
X538554Y202249D01*
G01X538538Y202251D02*
X538546Y202250D01*
G01X538530Y202252D02*
X538538Y202251D01*
G01X538523Y202254D02*
X538530Y202252D01*
G01X552735Y202248D02*
X552744Y202247D01*
G01X552727Y202249D02*
X552735Y202248D01*
G01X552719Y202250D02*
X552727Y202249D01*
G01X552711Y202251D02*
X552719Y202250D01*
G01X552703Y202252D02*
X552711Y202251D01*
G01X552696Y202254D02*
X552703Y202252D01*
G01X509908Y196164D02*
X509851Y196457D01*
G01X510080Y195905D02*
X509908Y196164D01*
G01X510343Y195730D02*
X510080Y195905D01*
G01X510650Y195670D02*
X510343Y195730D01*
G01X524082Y196164D02*
X524024Y196457D01*
G01X524253Y195905D02*
X524082Y196164D01*
G01X524517Y195730D02*
X524253Y195905D01*
G01X524824Y195670D02*
X524517Y195730D01*
G01X538255Y196164D02*
X538197Y196457D01*
G01X538426Y195905D02*
X538255Y196164D01*
G01X538690Y195730D02*
X538426Y195905D01*
G01X538997Y195670D02*
X538690Y195730D01*
G01X552428Y196164D02*
X552371Y196457D01*
G01X552600Y195905D02*
X552428Y196164D01*
G01X552863Y195730D02*
X552600Y195905D01*
G01X553170Y195670D02*
X552863Y195730D01*
G01X510292Y196264D02*
X510239Y196457D01*
G01X510442Y196118D02*
X510292Y196264D01*
G01X510650Y196063D02*
X510442Y196118D01*
G01X524465Y196264D02*
X524412Y196457D01*
G01X524615Y196118D02*
X524465Y196264D01*
G01X524824Y196063D02*
X524615Y196118D01*
G01X538638Y196264D02*
X538585Y196457D01*
G01X538788Y196118D02*
X538638Y196264D01*
G01X538997Y196063D02*
X538788Y196118D01*
G01X554120Y190749D02*
X554135Y190748D01*
G01X554104Y190751D02*
X554120Y190749D01*
G01X554088Y190755D02*
X554104Y190751D01*
G01X504513Y190749D02*
X504529Y190748D01*
G01X504497Y190751D02*
X504513Y190749D01*
G01X504482Y190755D02*
X504497Y190751D01*
G01X552811Y196264D02*
X552758Y196457D01*
G01X552962Y196118D02*
X552811Y196264D01*
G01X553170Y196063D02*
X552962Y196118D01*
G01X504441Y190761D02*
X504482Y190755D01*
G01X504401Y190776D02*
X504441Y190761D01*
G01X504364Y190801D02*
X504401Y190776D01*
G01X504332Y190834D02*
X504364Y190801D01*
G01X554048Y190761D02*
X554088Y190755D01*
G01X554007Y190776D02*
X554048Y190761D01*
G01X553970Y190801D02*
X554007Y190776D01*
G01X553939Y190834D02*
X553970Y190801D01*
G01X510614Y196270D02*
X510694Y196260D01*
G01X510538Y196288D02*
X510614Y196270D01*
G01X510469Y196313D02*
X510538Y196288D01*
G01X510409Y196343D02*
X510469Y196313D01*
G01X510361Y196379D02*
X510409Y196343D01*
G01X510326Y196417D02*
X510361Y196379D01*
G01X510306Y196457D02*
X510326Y196417D01*
G01X510689Y197005D02*
X510769Y196995D01*
G01X510613Y197023D02*
X510689Y197005D01*
G01X510544Y197048D02*
X510613Y197023D01*
G01X510484Y197078D02*
X510544Y197048D01*
G01X510435Y197113D02*
X510484Y197078D01*
G01X510401Y197152D02*
X510435Y197113D01*
G01X510381Y197192D02*
X510401Y197152D01*
G01X524787Y196270D02*
X524867Y196260D01*
G01X524712Y196288D02*
X524787Y196270D01*
G01X524642Y196313D02*
X524712Y196288D01*
G01X524582Y196343D02*
X524642Y196313D01*
G01X524534Y196379D02*
X524582Y196343D01*
G01X524499Y196417D02*
X524534Y196379D01*
G01X524479Y196457D02*
X524499Y196417D01*
G01X524862Y197005D02*
X524942Y196995D01*
G01X524786Y197023D02*
X524862Y197005D01*
G01X524717Y197048D02*
X524786Y197023D01*
G01X524657Y197078D02*
X524717Y197048D01*
G01X524609Y197113D02*
X524657Y197078D01*
G01X524574Y197152D02*
X524609Y197113D01*
G01X524554Y197192D02*
X524574Y197152D01*
G01X538960Y196270D02*
X539040Y196260D01*
G01X538885Y196288D02*
X538960Y196270D01*
G01X538816Y196313D02*
X538885Y196288D01*
G01X538755Y196343D02*
X538816Y196313D01*
G01X538707Y196379D02*
X538755Y196343D01*
G01X538672Y196417D02*
X538707Y196379D01*
G01X538652Y196457D02*
X538672Y196417D01*
G01X539035Y197005D02*
X539115Y196995D01*
G01X538960Y197023D02*
X539035Y197005D01*
G01X538890Y197048D02*
X538960Y197023D01*
G01X538830Y197078D02*
X538890Y197048D01*
G01X538782Y197113D02*
X538830Y197078D01*
G01X538747Y197152D02*
X538782Y197113D01*
G01X538727Y197192D02*
X538747Y197152D01*
G01X553134Y196270D02*
X553213Y196260D01*
G01X553058Y196288D02*
X553134Y196270D01*
G01X552989Y196313D02*
X553058Y196288D01*
G01X552929Y196343D02*
X552989Y196313D01*
G01X552880Y196379D02*
X552929Y196343D01*
G01X552845Y196417D02*
X552880Y196379D01*
G01X552826Y196457D02*
X552845Y196417D01*
G01X553208Y197005D02*
X553288Y196995D01*
G01X553133Y197023D02*
X553208Y197005D01*
G01X553064Y197048D02*
X553133Y197023D01*
G01X553003Y197078D02*
X553064Y197048D01*
G01X552955Y197113D02*
X553003Y197078D01*
G01X552920Y197152D02*
X552955Y197113D01*
G01X552900Y197192D02*
X552920Y197152D01*
G01X510092Y202275D02*
X510176Y202254D01*
G01X510014Y202310D02*
X510092Y202275D01*
G01X509947Y202354D02*
X510014Y202310D01*
G01X509894Y202406D02*
X509947Y202354D01*
G01X509856Y202465D02*
X509894Y202406D01*
G01X509837Y202526D02*
X509856Y202465D01*
G01X524266Y202275D02*
X524350Y202254D01*
G01X524187Y202310D02*
X524266Y202275D01*
G01X524121Y202354D02*
X524187Y202310D01*
G01X524067Y202406D02*
X524121Y202354D01*
G01X524030Y202465D02*
X524067Y202406D01*
G01X524010Y202526D02*
X524030Y202465D01*
G01X509962Y201231D02*
X510043Y201218D01*
G01X509886Y201256D02*
X509962Y201231D01*
G01X509815Y201291D02*
X509886Y201256D01*
G01X509755Y201334D02*
X509815Y201291D01*
G01X509707Y201384D02*
X509755Y201334D01*
G01X509673Y201439D02*
X509707Y201384D01*
G01X509655Y201496D02*
X509673Y201439D01*
G01X513853Y201041D02*
X513858Y200940D01*
G01X513839Y201136D02*
X513853Y201041D01*
G01X513817Y201218D02*
X513839Y201136D01*
G01X509239Y201037D02*
X509240Y200940D01*
G01X509239Y201138D02*
Y201037D01*
G01X509237Y201241D02*
X509239Y201138D01*
G01X538439Y202275D02*
X538523Y202254D01*
G01X538361Y202310D02*
X538439Y202275D01*
G01X538294Y202354D02*
X538361Y202310D01*
G01X538240Y202406D02*
X538294Y202354D01*
G01X538203Y202465D02*
X538240Y202406D01*
G01X538183Y202526D02*
X538203Y202465D01*
G01X552612Y202275D02*
X552696Y202254D01*
G01X552534Y202310D02*
X552612Y202275D01*
G01X552467Y202354D02*
X552534Y202310D01*
G01X552414Y202406D02*
X552467Y202354D01*
G01X552376Y202465D02*
X552414Y202406D01*
G01X552356Y202526D02*
X552376Y202465D01*
G01X528026Y201041D02*
X528031Y200940D01*
G01X528012Y201136D02*
X528026Y201041D01*
G01X527990Y201218D02*
X528012Y201136D01*
G01X542199Y201041D02*
X542204Y200940D01*
G01X542186Y201136D02*
X542199Y201041D01*
G01X542163Y201218D02*
X542186Y201136D01*
G01X511541Y190764D02*
X511616Y190748D01*
G01X511476Y190806D02*
X511541Y190764D01*
G01X511434Y190871D02*
X511476Y190806D01*
G01X511419Y190945D02*
X511434Y190871D01*
G01X518627Y190764D02*
X518702Y190748D01*
G01X518563Y190806D02*
X518627Y190764D01*
G01X518521Y190871D02*
X518563Y190806D01*
G01X518505Y190945D02*
X518521Y190871D01*
G01X525714Y190764D02*
X525789Y190748D01*
G01X525650Y190806D02*
X525714Y190764D01*
G01X525607Y190871D02*
X525650Y190806D01*
G01X525592Y190945D02*
X525607Y190871D01*
G01X532801Y190764D02*
X532876Y190748D01*
G01X532736Y190806D02*
X532801Y190764D01*
G01X532694Y190871D02*
X532736Y190806D01*
G01X532679Y190945D02*
X532694Y190871D01*
G01X539887Y190764D02*
X539962Y190748D01*
G01X539823Y190806D02*
X539887Y190764D01*
G01X539781Y190871D02*
X539823Y190806D01*
G01X539765Y190945D02*
X539781Y190871D01*
G01X546974Y190764D02*
X547049Y190748D01*
G01X546909Y190806D02*
X546974Y190764D01*
G01X546867Y190871D02*
X546909Y190806D01*
G01X546852Y190945D02*
X546867Y190871D01*
G01X514227Y201334D02*
X514235Y201241D01*
G01X514217Y201419D02*
X514227Y201334D01*
G01X514205Y201496D02*
X514217Y201419D01*
G01X510607Y196073D02*
X510694Y196063D01*
G01X510525Y196103D02*
X510607Y196073D01*
G01X510452Y196149D02*
X510525Y196103D01*
G01X510390Y196213D02*
X510452Y196149D01*
G01X510344Y196287D02*
X510390Y196213D01*
G01X510316Y196370D02*
X510344Y196287D01*
G01X510306Y196457D02*
X510316Y196370D01*
G01X524780Y196073D02*
X524867Y196063D01*
G01X524698Y196103D02*
X524780Y196073D01*
G01X524625Y196149D02*
X524698Y196103D01*
G01X524563Y196213D02*
X524625Y196149D01*
G01X524517Y196287D02*
X524563Y196213D01*
G01X524489Y196370D02*
X524517Y196287D01*
G01X524479Y196457D02*
X524489Y196370D01*
G01X528390Y201419D02*
X528378Y201496D01*
G01X528400Y201334D02*
X528390Y201419D01*
G01X528408Y201241D02*
X528400Y201334D01*
G01X542563Y201419D02*
X542551Y201496D01*
G01X542573Y201334D02*
X542563Y201419D01*
G01X542581Y201241D02*
X542573Y201334D01*
G01X556736Y201419D02*
X556724Y201496D01*
G01X556746Y201334D02*
X556736Y201419D01*
G01X556754Y201241D02*
X556746Y201334D01*
G01X556359Y201136D02*
X556337Y201218D01*
G01X556373Y201041D02*
X556359Y201136D01*
G01X556377Y200940D02*
X556373Y201041D01*
G01X514237Y201141D02*
X514235Y201241D01*
G01X514238Y201040D02*
X514237Y201141D01*
G01X523412Y201037D02*
X523413Y200940D01*
G01X523412Y201138D02*
Y201037D01*
G01X523411Y201241D02*
X523412Y201138D01*
G01X528410Y201141D02*
X528408Y201241D01*
G01X528412Y201040D02*
X528410Y201141D01*
G01X537585Y201037D02*
X537586Y200940D01*
G01X537585Y201138D02*
Y201037D01*
G01X537584Y201241D02*
X537585Y201138D01*
G01X542584Y201141D02*
X542581Y201241D01*
G01X542585Y201040D02*
X542584Y201141D01*
G01X509621Y201043D02*
Y196457D01*
G01X509623Y201144D02*
X509621Y201043D01*
G01X509625Y201241D02*
X509623Y201144D01*
G01X523795Y201043D02*
X523794Y196457D01*
G01X523796Y201144D02*
X523795Y201043D01*
G01X523798Y201241D02*
X523796Y201144D01*
G01X537968Y201043D02*
X537967Y196457D01*
G01X537969Y201144D02*
X537968Y201043D01*
G01X537972Y201241D02*
X537969Y201144D01*
G01X510021Y201136D02*
X510043Y201218D01*
G01X510007Y201041D02*
X510021Y201136D01*
G01X510002Y200940D02*
X510007Y201041D01*
G01X524194Y201136D02*
X524216Y201218D01*
G01X524180Y201041D02*
X524194Y201136D01*
G01X524175Y200940D02*
X524180Y201041D01*
G01X538367Y201136D02*
X538389Y201218D01*
G01X538353Y201041D02*
X538367Y201136D01*
G01X538349Y200940D02*
X538353Y201041D01*
G01X509643Y201419D02*
X509655Y201496D01*
G01X509633Y201334D02*
X509643Y201419D01*
G01X509625Y201241D02*
X509633Y201334D01*
G01X554040Y199979D02*
X554084Y199961D01*
G01X554001Y200008D02*
X554040Y199979D01*
G01X553969Y200047D02*
X554001Y200008D01*
G01X553947Y200095D02*
X553969Y200047D01*
G01X553939Y200151D02*
X553947Y200095D01*
G01X538953Y196073D02*
X539040Y196063D01*
G01X538871Y196103D02*
X538953Y196073D01*
G01X538798Y196149D02*
X538871Y196103D01*
G01X538736Y196213D02*
X538798Y196149D01*
G01X538691Y196287D02*
X538736Y196213D01*
G01X538662Y196370D02*
X538691Y196287D01*
G01X538652Y196457D02*
X538662Y196370D01*
G01X553126Y196073D02*
X553213Y196063D01*
G01X553045Y196103D02*
X553126Y196073D01*
G01X552972Y196149D02*
X553045Y196103D01*
G01X552910Y196213D02*
X552972Y196149D01*
G01X552864Y196287D02*
X552910Y196213D01*
G01X552835Y196370D02*
X552864Y196287D01*
G01X552826Y196457D02*
X552835Y196370D01*
G01X551758Y201037D02*
X551759Y200940D01*
G01X551758Y201138D02*
Y201037D01*
G01X551757Y201241D02*
X551758Y201138D01*
G01X556757Y201141D02*
X556754Y201241D01*
G01X556758Y201040D02*
X556757Y201141D01*
G01X552141Y201043D02*
Y196457D01*
G01X552142Y201144D02*
X552141Y201043D01*
G01X552145Y201241D02*
X552142Y201144D01*
G01X552540Y201136D02*
X552563Y201218D01*
G01X552527Y201041D02*
X552540Y201136D01*
G01X552522Y200940D02*
X552527Y201041D01*
G01X523806Y201333D02*
X523798Y201241D01*
G01X523816Y201419D02*
X523806Y201333D01*
G01X523828Y201496D02*
X523816Y201419D01*
G01X537980Y201333D02*
X537972Y201241D01*
G01X537990Y201419D02*
X537980Y201333D01*
G01X538002Y201496D02*
X537990Y201419D01*
G01X552153Y201333D02*
X552145Y201241D01*
G01X552163Y201419D02*
X552153Y201333D01*
G01X552175Y201496D02*
X552163Y201419D01*
G01X514880Y190764D02*
X514805Y190748D01*
G01X514944Y190807D02*
X514880Y190764D01*
G01X514987Y190871D02*
X514944Y190807D01*
G01X515002Y190945D02*
X514987Y190871D01*
G01X521967Y190764D02*
X521891Y190748D01*
G01X522031Y190807D02*
X521967Y190764D01*
G01X522074Y190871D02*
X522031Y190807D01*
G01X522088Y190945D02*
X522074Y190871D01*
G01X529053Y190764D02*
X528978Y190748D01*
G01X529118Y190807D02*
X529053Y190764D01*
G01X529160Y190871D02*
X529118Y190807D01*
G01X529175Y190945D02*
X529160Y190871D01*
G01X536140Y190764D02*
X536065Y190748D01*
G01X536204Y190807D02*
X536140Y190764D01*
G01X536247Y190871D02*
X536204Y190807D01*
G01X536261Y190945D02*
X536247Y190871D01*
G01X543227Y190764D02*
X543151Y190748D01*
G01X543291Y190807D02*
X543227Y190764D01*
G01X543333Y190871D02*
X543291Y190807D01*
G01X543348Y190945D02*
X543333Y190871D01*
G01X550313Y190764D02*
X550238Y190748D01*
G01X550377Y190807D02*
X550313Y190764D01*
G01X550420Y190871D02*
X550377Y190807D01*
G01X550435Y190945D02*
X550420Y190871D01*
G01X528071Y201231D02*
X527990Y201218D01*
G01X528147Y201256D02*
X528071Y201231D01*
G01X528218Y201291D02*
X528147Y201256D01*
G01X528278Y201334D02*
X528218Y201291D01*
G01X528326Y201384D02*
X528278Y201334D01*
G01X528360Y201439D02*
X528326Y201384D01*
G01X528378Y201496D02*
X528360Y201439D01*
G01X557399Y200639D02*
X557324Y200624D01*
G01X557464Y200682D02*
X557399Y200639D01*
G01X557506Y200747D02*
X557464Y200682D01*
G01X557521Y200821D02*
X557506Y200747D01*
G01X542244Y201231D02*
X542163Y201218D01*
G01X542321Y201256D02*
X542244Y201231D01*
G01X542392Y201291D02*
X542321Y201256D01*
G01X542452Y201334D02*
X542392Y201291D01*
G01X542499Y201384D02*
X542452Y201334D01*
G01X542533Y201439D02*
X542499Y201384D01*
G01X542551Y201496D02*
X542533Y201439D01*
G01X521976Y190767D02*
X521891Y190748D01*
G01X522039Y190815D02*
X521976Y190767D01*
G01X522083Y190882D02*
X522039Y190815D01*
G01X536149Y190767D02*
X536065Y190748D01*
G01X536213Y190815D02*
X536149Y190767D01*
G01X536256Y190882D02*
X536213Y190815D01*
G01X507806Y190761D02*
X507765Y190755D01*
G01X507846Y190776D02*
X507806Y190761D01*
G01X507883Y190801D02*
X507846Y190776D01*
G01X507915Y190834D02*
X507883Y190801D01*
G01X550322Y190767D02*
X550238Y190748D01*
G01X550386Y190815D02*
X550322Y190767D01*
G01X550430Y190882D02*
X550386Y190815D01*
G01X557412Y190761D02*
X557371Y190755D01*
G01X557453Y190776D02*
X557412Y190761D01*
G01X557490Y190801D02*
X557453Y190776D01*
G01X557521Y190834D02*
X557490Y190801D01*
G01X557513Y200095D02*
X557521Y200151D01*
G01X557491Y200046D02*
X557513Y200095D01*
G01X557459Y200008D02*
X557491Y200046D01*
G01X557419Y199979D02*
X557459Y200008D01*
G01X557376Y199961D02*
X557419Y199979D01*
G01X552128Y196457D02*
G03X552522Y196063I394J0D01*
G01X547757D02*
G03X547364Y195670I0J-393D01*
G01X549923D02*
G03X549529Y196063I-393J0D01*
G01X554844D02*
G03X554450Y195670I0J-394D01*
G01X557009D02*
G03X556616Y196063I-393J0D01*
G01X551774Y196457D02*
G03X552522Y195709I748J0D01*
G01X564174Y188977D02*
G03X568111I1969J0D01*
G01X549922Y183071D02*
G03I-709J0D01*
G01Y178741D02*
G03I-709J0D01*
G01X557008Y174016D02*
G03I-708J0D01*
G01X554485Y174944D02*
G03Y173164I1299J-890D01*
G01X557556D02*
G03Y174944I-1299J890D01*
G01X557008Y168504D02*
G03I-708J0D01*
G01X554485Y167621D02*
G03Y165842I1299J-889D01*
G01X557556D02*
G03Y167621I-1299J890D01*
G01X557008Y164174D02*
G03I-708J0D01*
G01Y159843D02*
G03I-708J0D01*
G01X554446Y160650D02*
G03X556000Y159075I1575J0D01*
G01X549922Y173229D02*
G03I-709J0D01*
G01Y168898D02*
G03I-709J0D01*
G01Y164567D02*
G03I-709J0D01*
G01Y159056D02*
G03I-709J0D01*
G01X547359Y160650D02*
G03X550509I1575J0D01*
G01X537955Y196457D02*
G03X538349Y196063I394J0D01*
G01X533584D02*
G03X533191Y195670I0J-393D01*
G01X535750D02*
G03X535356Y196063I-393J0D01*
G01X526498D02*
G03X526104Y195670I0J-394D01*
G01X528663D02*
G03X528269Y196063I-393J0D01*
G01X540671D02*
G03X540277Y195670I0J-394D01*
G01X542836D02*
G03X542442Y196063I-393J0D01*
G01X537601Y196457D02*
G03X538349Y195709I748J0D01*
G01X535748Y183071D02*
G03I-708J0D01*
G01Y178741D02*
G03I-708J0D01*
G01Y173229D02*
G03I-708J0D01*
G01X542835Y174016D02*
G03I-709J0D01*
G01Y168504D02*
G03I-709J0D01*
G01X535748Y168898D02*
G03I-708J0D01*
G01X542835Y164174D02*
G03I-709J0D01*
G01X535748Y164567D02*
G03I-708J0D01*
G01Y159056D02*
G03I-708J0D01*
G01X542835Y159843D02*
G03I-709J0D01*
G01X540272Y160650D02*
G03X543422I1575J0D01*
G01X528662Y174016D02*
G03I-709J0D01*
G01Y168504D02*
G03I-709J0D01*
G01Y164174D02*
G03I-709J0D01*
G01Y159843D02*
G03I-709J0D01*
G01X533186Y160650D02*
G03X536335I1574J0D01*
G01X526099D02*
G03X529249I1575J0D01*
G01X523782Y196457D02*
G03X524175Y196063I394J0D01*
G01X519411D02*
G03X519017Y195670I0J-394D01*
G01X521576D02*
G03X521183Y196063I-393J0D01*
G01X512324D02*
G03X511931Y195670I0J-393D01*
G01X514490D02*
G03X514096Y196063I-393J0D01*
G01X523427Y196457D02*
G03X524175Y195709I748J0D01*
G01X509608Y196457D02*
G03X510002Y196063I394J0D01*
G01X507403Y195670D02*
G03X507009Y196063I-393J0D01*
G01X505238D02*
G03X504844Y195670I0J-394D01*
G01X509254Y196457D02*
G03X510002Y195709I748J0D01*
G01X514489Y174016D02*
G03I-709J0D01*
G01X521575Y183071D02*
G03I-708J0D01*
G01Y178741D02*
G03I-708J0D01*
G01X514489Y168504D02*
G03I-709J0D01*
G01Y164174D02*
G03I-709J0D01*
G01Y159843D02*
G03I-709J0D01*
G01X521575Y173229D02*
G03I-708J0D01*
G01Y168898D02*
G03I-708J0D01*
G01Y164567D02*
G03I-708J0D01*
G01Y159056D02*
G03I-708J0D01*
G01X519013Y160650D02*
G03X522162I1574J0D01*
G01X511926D02*
G03X515076I1575J0D01*
G01X507402Y178741D02*
G03I-709J0D01*
G01Y183071D02*
G03I-709J0D01*
G01X507950Y172744D02*
G03Y174523I-1300J889D01*
G01X504879D02*
G03Y172744I1299J-890D01*
G01X507402Y173229D02*
G03I-709J0D01*
G01Y168898D02*
G03I-709J0D01*
G01Y164567D02*
G03I-709J0D01*
G01Y159056D02*
G03I-709J0D01*
G01X504839Y160650D02*
G03X507989I1575J0D01*
G01X507950Y165421D02*
G03Y167201I-1300J890D01*
G01X504879D02*
G03Y165421I1299J-890D01*
G01X542835Y154331D02*
G03I-709J0D01*
G01Y150000D02*
G03I-709J0D01*
G01X557008Y154331D02*
G03I-708J0D01*
G01X549922Y154725D02*
G03I-709J0D01*
G01X557008Y150000D02*
G03I-708J0D01*
G01X549922Y150394D02*
G03I-709J0D01*
G01X557398Y156142D02*
G03X558383Y157126I0J985D01*
G01X553658D02*
G03X554642Y156142I984J0D01*
G01X559017Y157501D02*
G03X557442Y159075I-1574J0D01*
G01X542835Y145670D02*
G03I-709J0D01*
G01Y140158D02*
G03I-709J0D01*
G01X557008Y145670D02*
G03I-708J0D01*
G01X549922Y144882D02*
G03I-709J0D01*
G01Y140552D02*
G03I-709J0D01*
G01X557008Y140158D02*
G03I-708J0D01*
G01X557989Y140965D02*
G03I-1969J0D01*
G01X550902D02*
G03I-1968J0D01*
G01X543816D02*
G03I-1969J0D01*
G01X514489Y154331D02*
G03I-709J0D01*
G01Y150000D02*
G03I-709J0D01*
G01X528662Y154331D02*
G03I-709J0D01*
G01X521575Y154725D02*
G03I-708J0D01*
G01X528662Y150000D02*
G03I-709J0D01*
G01X521575Y150394D02*
G03I-708J0D01*
G01X535748Y154725D02*
G03I-708J0D01*
G01Y150394D02*
G03I-708J0D01*
G01X528662Y145670D02*
G03I-709J0D01*
G01X535748Y144882D02*
G03I-708J0D01*
G01X528662Y140158D02*
G03I-709J0D01*
G01X535748Y140552D02*
G03I-708J0D01*
G01X536729Y140965D02*
G03I-1968J0D01*
G01X529642D02*
G03I-1968J0D01*
G01X514489Y145670D02*
G03I-709J0D01*
G01X521575Y144882D02*
G03I-708J0D01*
G01X514489Y140158D02*
G03I-709J0D01*
G01X521575Y140552D02*
G03I-708J0D01*
G01X522556Y140965D02*
G03I-1969J0D01*
G01X515469D02*
G03I-1968J0D01*
G01X542835Y135827D02*
G03I-709J0D01*
G01X535748Y136221D02*
G03I-708J0D01*
G01X557008Y135827D02*
G03I-708J0D01*
G01X549922Y136221D02*
G03I-709J0D01*
G01X514489Y135827D02*
G03I-709J0D01*
G01X528662D02*
G03I-709J0D01*
G01X521575Y136221D02*
G03I-708J0D01*
G01X500532Y156674D02*
G03X501123Y157264I0J591D01*
G01X507402Y154725D02*
G03I-709J0D01*
G01Y150394D02*
G03I-709J0D01*
G01X500532Y156280D02*
G03X501517Y157264I0J985D01*
G01X507792Y156142D02*
G03X508776Y157126I0J984D01*
G01X504052D02*
G03X505036Y156142I984J0D01*
G01X507402Y144882D02*
G03I-709J0D01*
G01Y140552D02*
G03I-709J0D01*
G01X508383Y140965D02*
G03I-1969J0D01*
G01X507402Y136221D02*
G03I-709J0D01*
G01X500961Y162719D02*
X500174Y162264D01*
G01X557556Y163607D02*
X556768Y162243D01*
G01X550509Y177161D02*
X551887Y179548D01*
G01X543422Y177161D02*
X544800Y179548D01*
G01X536335Y177161D02*
X537713Y179548D01*
G01X529249Y177161D02*
X530627Y179548D01*
G01X522162Y177161D02*
X523540Y179548D01*
G01X507950Y163186D02*
X507162Y161822D01*
G01X515076Y177161D02*
X516454Y179548D01*
G01X507989Y177161D02*
X509367Y179548D01*
G01X500961Y177263D02*
X502280Y179548D01*
G01X552744Y202247D02*
X552563Y201218D01*
G01X552175Y201496D02*
X552356Y202526D01*
G01X538571Y202247D02*
X538389Y201218D01*
G01X538002Y201496D02*
X538183Y202526D01*
G01X524398Y202247D02*
X524216Y201218D01*
G01X523828Y201496D02*
X524010Y202526D01*
G01X553213Y196260D02*
X553288Y196995D01*
G01X552900Y197192D02*
X552826Y196457D01*
G01X539040Y196260D02*
X539115Y196995D01*
G01X538727Y197192D02*
X538652Y196457D01*
G01X557371Y190755D02*
X557364Y190158D01*
G01X557140Y200940D02*
X557142Y201241D01*
G01X557015Y195644D02*
X557016Y196063D01*
G01X557376Y199961D02*
X557372Y190755D01*
G01X568111Y589622D02*
Y188977D01*
G01X558996Y201805D02*
Y189370D01*
G01X558668Y190158D02*
Y228741D01*
G01X558383Y180552D02*
Y157126D01*
G01X557556Y165842D02*
Y163607D01*
G01Y173164D02*
Y167621D01*
G01Y180552D02*
Y174944D01*
G01X557521Y190834D02*
Y190158D01*
G01Y201043D02*
Y200151D01*
G01X557324Y190748D02*
Y200624D01*
G01X557142Y201241D02*
Y224608D01*
G01X557140Y196063D02*
Y200940D01*
G01X557009Y195670D02*
Y191733D01*
G01X556911Y195906D02*
Y191969D01*
G01X556758Y196037D02*
Y201040D01*
G01X556754Y224608D02*
Y201241D01*
G01X556568Y226338D02*
Y196063D01*
G01X556543Y224608D02*
Y202526D01*
G01X556377Y196063D02*
Y200940D01*
G01X556180Y226338D02*
Y196063D01*
G01X556155Y202247D02*
Y224608D01*
G01X556038Y226338D02*
Y196063D01*
G01X555650D02*
Y226338D01*
G01X554549Y195906D02*
Y191969D01*
G01X554485Y165842D02*
Y163607D01*
G01Y173164D02*
Y167621D01*
G01Y180552D02*
Y174944D01*
G01X554450Y197192D02*
Y191733D01*
G01X554446Y165902D02*
Y160650D01*
G01Y173225D02*
Y167561D01*
G01Y177161D02*
Y174884D01*
G01X554135Y200624D02*
Y190748D01*
G01X553939Y190834D02*
Y190158D01*
G01Y201043D02*
Y200151D01*
G01X553658Y180552D02*
Y157126D01*
G01X553288Y196995D02*
Y226338D01*
G01X553213Y196260D02*
Y196063D01*
G01X553170D02*
Y195670D01*
G01X552900Y226338D02*
Y197192D01*
G01X552758Y196457D02*
Y226338D01*
G01X552744Y202247D02*
Y224608D01*
G01X552522Y195695D02*
Y200940D01*
G01X552371Y196457D02*
Y226338D01*
G01X552356Y202526D02*
Y224608D01*
G01X552145D02*
Y201241D01*
G01X551759Y200940D02*
Y196457D01*
G01X551757Y224608D02*
Y201241D01*
G01X550509Y160650D02*
Y177161D01*
G01X550435Y190158D02*
Y201805D01*
G01X550423D02*
X550425Y190882D01*
G01X550238Y201805D02*
Y190748D01*
G01X549923Y195670D02*
Y191733D01*
G01X549613Y225788D02*
Y201805D01*
G01X554084Y199961D02*
X554088Y190755D01*
G01X554096Y190158D02*
X554088Y190755D01*
G01X556543Y202526D02*
X556724Y201496D01*
G01X556337Y201218D02*
X556155Y202247D01*
G01X542370Y202526D02*
X542551Y201496D01*
G01X542163Y201218D02*
X541982Y202247D01*
G01X510224D02*
X510043Y201218D01*
G01X509655Y201496D02*
X509837Y202526D01*
G01X524867Y196260D02*
X524942Y196995D01*
G01X524554Y197192D02*
X524479Y196457D01*
G01X510694Y196260D02*
X510769Y196995D01*
G01X510381Y197192D02*
X510306Y196457D01*
G01X507765Y190755D02*
X507758Y190158D01*
G01X542967Y200940D02*
X542969Y201241D01*
G01X528793Y200940D02*
X528795Y201241D01*
G01X514620Y200940D02*
X514622Y201241D01*
G01X542842Y195644D02*
X542843Y196063D01*
G01X528669Y195644D02*
X528670Y196063D01*
G01X514496Y195644D02*
Y196063D01*
G01X547364Y195670D02*
Y191733D01*
G01X547359Y177161D02*
Y160650D01*
G01X547049Y201805D02*
Y190748D01*
G01X546852Y201805D02*
Y190158D01*
G01X545873Y190748D02*
Y225788D01*
G01X545686D02*
Y190882D01*
G01X545676D02*
Y190158D01*
G01X543422Y160650D02*
Y177161D01*
G01X543348Y190158D02*
Y201043D01*
G01X543151Y190748D02*
Y200624D01*
G01X542969Y201241D02*
Y224608D01*
G01X542966Y196063D02*
Y200940D01*
G01X542836Y195670D02*
Y191733D01*
G01X542585Y201040D02*
Y196037D01*
G01X542581Y201241D02*
Y224608D01*
G01X542395Y226338D02*
Y196063D01*
G01X542370Y224608D02*
Y202526D01*
G01X542204Y196063D02*
Y200940D01*
G01X542007Y226338D02*
Y196063D01*
G01X541982Y202247D02*
Y224608D01*
G01X541865Y226338D02*
Y196063D01*
G01X541477D02*
Y226338D01*
G01X540277Y197192D02*
Y191733D01*
G01X540272Y177161D02*
Y160650D01*
G01X539962Y200624D02*
Y190748D01*
G01X539765Y201043D02*
Y190158D01*
G01X539115Y196995D02*
Y226338D01*
G01X539040Y196260D02*
Y196063D01*
G01X538997D02*
Y195670D01*
G01X538727Y226338D02*
Y197192D01*
G01X538585Y196457D02*
Y226338D01*
G01X538571Y202247D02*
Y224608D01*
G01X538349Y195695D02*
Y200940D01*
G01X538197Y196457D02*
Y226338D01*
G01X538183Y202526D02*
Y224608D01*
G01X537972D02*
Y201241D01*
G01X537586Y200940D02*
Y196457D01*
G01X537584Y224608D02*
Y201241D01*
G01X536335Y160650D02*
Y177161D01*
G01X536261Y190158D02*
Y201805D01*
G01X536250D02*
X536252Y190882D01*
G01X536065Y201805D02*
Y190748D01*
G01X535750Y195670D02*
Y191733D01*
G01X535440Y225788D02*
Y201805D01*
G01X533191Y195670D02*
Y191733D01*
G01X533186Y177161D02*
Y160650D01*
G01X532876Y201805D02*
Y190748D01*
G01X532679Y201805D02*
Y190158D01*
G01X531700Y190748D02*
Y225788D01*
G01X531513D02*
Y190882D01*
G01X531503D02*
Y190158D01*
G01X529249Y160650D02*
Y177161D01*
G01X529175Y190158D02*
Y201043D01*
G01X528978Y190748D02*
Y200624D01*
G01X528796Y201241D02*
Y224608D01*
G01X528793Y196063D02*
Y200940D01*
G01X528663Y195670D02*
Y191733D01*
G01X528412Y201040D02*
Y196037D01*
G01X528408Y201241D02*
Y224608D01*
G01X528221Y226338D02*
Y196063D01*
G01X528196Y224608D02*
Y202526D01*
G01X528031Y196063D02*
Y200940D01*
G01X527834Y226338D02*
Y196063D01*
G01X527809Y202247D02*
Y224608D01*
G01X527692Y226338D02*
Y196063D01*
G01X527304D02*
Y226338D01*
G01X526104Y197192D02*
Y191733D01*
G01X526099Y177161D02*
Y160650D01*
G01X525789Y200624D02*
Y190748D01*
G01X525592Y201043D02*
Y190158D01*
G01X524942Y196995D02*
Y226338D01*
G01X524867Y196260D02*
Y196063D01*
G01X524824D02*
Y195670D01*
G01X524554Y226338D02*
Y197192D01*
G01X524412Y196457D02*
Y226338D01*
G01X524398Y202247D02*
Y224608D01*
G01X524175Y195695D02*
Y200940D01*
G01X524024Y196457D02*
Y226338D01*
G01X524010Y202526D02*
Y224608D01*
G01X523798D02*
Y201241D01*
G01X523413Y200940D02*
Y196457D01*
G01X523411Y224608D02*
Y201241D01*
G01X522162Y160650D02*
Y177161D01*
G01X522088Y190158D02*
Y201805D01*
G01X522077D02*
X522078Y190882D01*
G01X521891Y201805D02*
Y190748D01*
G01X521576Y195670D02*
Y191733D01*
G01X521267Y225788D02*
Y201805D01*
G01X519017Y195670D02*
Y191733D01*
G01X519013Y177161D02*
Y160650D01*
G01X518702Y201805D02*
Y190748D01*
G01X518505Y201805D02*
Y190158D01*
G01X517526Y190748D02*
Y225788D01*
G01X517340D02*
Y190882D01*
G01X517329D02*
Y190158D01*
G01X515076Y160650D02*
Y177161D01*
G01X515002Y190158D02*
Y201043D01*
G01X514805Y190748D02*
Y200624D01*
G01X514622Y201241D02*
Y224608D01*
G01X514620Y196063D02*
Y200940D01*
G01X514490Y195670D02*
Y191733D01*
G01X514238Y201040D02*
X514239Y196037D01*
G01X514235Y201241D02*
Y224608D01*
G01X514048Y226338D02*
Y196063D01*
G01X514023Y202526D02*
Y224608D01*
G01X513858Y196063D02*
Y200940D01*
G01X513660Y226338D02*
Y196063D01*
G01X513635Y202247D02*
Y224608D01*
G01X513518Y226338D02*
Y196063D01*
G01X513131D02*
Y226338D01*
G01X511931Y197192D02*
Y191733D01*
G01X511926Y177161D02*
Y160650D01*
G01X511616Y200624D02*
Y190748D01*
G01X511419Y201043D02*
Y190158D01*
G01X510769Y196995D02*
Y226338D01*
G01X510694Y196260D02*
Y196063D01*
G01X510650D02*
Y195670D01*
G01X510381Y226338D02*
Y197192D01*
G01X510239Y196457D02*
Y226338D01*
G01X510224Y202247D02*
Y224608D01*
G01X510002Y195695D02*
Y200940D01*
G01X509851Y196457D02*
Y226338D01*
G01X509837Y202526D02*
Y224608D01*
G01X509625D02*
Y201241D01*
G01X509240Y200940D02*
Y196457D01*
G01X509237Y224608D02*
Y201241D01*
G01X508776Y180552D02*
Y157126D01*
G01X528196Y202526D02*
X528378Y201496D01*
G01X527990Y201218D02*
X527809Y202247D01*
G01X514023Y202526D02*
X514205Y201496D01*
G01X513817Y201218D02*
X513635Y202247D01*
G01X507769Y201805D02*
X507766Y190755D01*
G01X507989Y174463D02*
Y177161D01*
G01Y167140D02*
Y172804D01*
G01Y160650D02*
Y165481D01*
G01X507950Y165421D02*
Y163186D01*
G01Y172744D02*
Y167201D01*
G01Y180552D02*
Y174523D01*
G01X507915Y190834D02*
Y190158D01*
G01X507718Y190748D02*
Y201805D01*
G01X507403Y195670D02*
Y191733D01*
G01X507305Y195906D02*
Y191969D01*
G01X504942Y195906D02*
Y191969D01*
G01X504879Y174523D02*
Y180552D01*
G01Y167201D02*
Y172744D01*
G01Y163186D02*
Y165421D01*
G01X504844Y195670D02*
Y191733D01*
G01X504839Y165481D02*
Y160650D01*
G01Y172804D02*
Y167140D01*
G01Y177161D02*
Y174463D01*
G01X504529Y201805D02*
Y190748D01*
G01X504332Y190834D02*
Y190158D01*
G01X504052Y180552D02*
Y157126D01*
G01X502369Y228741D02*
Y190158D01*
G01X501123Y209646D02*
Y157264D01*
G01X500961Y162719D02*
Y180729D01*
G01X500902Y160650D02*
Y162685D01*
G01X500729Y189863D02*
Y210433D01*
G01X500532Y156674D02*
Y156280D01*
G01X504478Y201805D02*
X504482Y190755D01*
G01X504489Y190158D02*
X504482Y190755D01*
G01X553068Y179548D02*
X554446Y177161D01*
G01X545981Y179548D02*
X547359Y177161D01*
G01X554485Y163607D02*
X555272Y162243D01*
G01X538894Y179548D02*
X540272Y177161D01*
G01X531808Y179548D02*
X533186Y177161D01*
G01X524721Y179548D02*
X526099Y177161D01*
G01X517635Y179548D02*
X519013Y177161D01*
G01X510548Y179548D02*
X511926Y177161D01*
G01X503461Y179548D02*
X504839Y177161D01*
G01X504879Y163186D02*
X505666Y161822D01*
G01X552356Y202526D02*
X556543D01*
G01X538183D02*
X542370D01*
G01X524010D02*
X528196D01*
G01X509837D02*
X514023D01*
G01X513635Y202247D02*
X510224D01*
G01X527809D02*
X524398D01*
G01X541982D02*
X538571D01*
G01X556155D02*
X552744D01*
G01X504478Y201805D02*
X507769D01*
G01X502858D02*
X502369D01*
G01X522088D02*
X518505D01*
G01X536261D02*
X532679D01*
G01X550435D02*
X546852D01*
G01X558996D02*
X558668D01*
G01X542581Y201241D02*
X542969D01*
G01X528408D02*
X528796D01*
G01X514235D02*
X514622D01*
G01X509625D02*
X509237D01*
G01X523798D02*
X523411D01*
G01X537972D02*
X537584D01*
G01X552145D02*
X551757D01*
G01X557142D02*
X556754D01*
G01X552563Y201218D02*
X556337D01*
G01X538389D02*
X542163D01*
G01X524216D02*
X527990D01*
G01X510043D02*
X513817D01*
G01X515002Y201043D02*
X511419D01*
G01X529175D02*
X525592D01*
G01X543348D02*
X539765D01*
G01X557521D02*
X553939D01*
G01X537586Y200940D02*
X542966D01*
G01X523413D02*
X528793D01*
G01X509240D02*
X514620D01*
G01X557140D02*
X551759D01*
G01X514805Y200624D02*
X511616D01*
G01X528978D02*
X525789D01*
G01X543151D02*
X539962D01*
G01X557324D02*
X554135D01*
G01X553939Y200374D02*
X557521D01*
G01X554084Y199961D02*
X557376D01*
G01X552900Y197192D02*
X554450D01*
G01X538727D02*
X540277D01*
G01X524554D02*
X526104D01*
G01X510381D02*
X511931D01*
G01X553288Y196995D02*
X554450D01*
G01X539115D02*
X540277D01*
G01X524942D02*
X526104D01*
G01X510769D02*
X511931D01*
G01X509240Y196457D02*
X511931D01*
G01X526104D02*
X523413D01*
G01X540277D02*
X537586D01*
G01X554450D02*
X551759D01*
G01X553213Y196260D02*
X554450D01*
G01X539040D02*
X540277D01*
G01X524867D02*
X526104D01*
G01X510694D02*
X511931D01*
G01X552522Y196076D02*
X554450D01*
G01X538349D02*
X540277D01*
G01X524175D02*
X526104D01*
G01X510002D02*
X511931D01*
G01X554844Y196063D02*
X556616D01*
G01X507009D02*
X505238D01*
G01X514096D02*
X512324D01*
G01X511931D02*
X510650D01*
G01X514620D02*
X514490D01*
G01X521183D02*
X519411D01*
G01X526104D02*
X524824D01*
G01X528269D02*
X526498D01*
G01X528793D02*
X528663D01*
G01X535356D02*
X533584D01*
G01X542442D02*
X540671D01*
G01X540277D02*
X538997D01*
G01X542967D02*
X542836D01*
G01X549529D02*
X547757D01*
G01X554450D02*
X553170D01*
G01X557140D02*
X557009D01*
G01X507305Y195906D02*
X504942D01*
G01X556911D02*
X554549D01*
G01X552522Y195695D02*
X554450D01*
G01X538349D02*
X540277D01*
G01X524175D02*
X526104D01*
G01X510002D02*
X511931D01*
G01Y195670D02*
X510650D01*
G01X526104D02*
X524824D01*
G01X540277D02*
X538997D01*
G01X554450D02*
X553170D01*
G01X554549Y195048D02*
X556911D01*
G01X557009Y193567D02*
X558668D01*
G01X504844D02*
X502369D01*
G01X511931D02*
X507403D01*
G01X519017D02*
X514490D01*
G01X526104D02*
X521576D01*
G01X533191D02*
X528663D01*
G01X540277D02*
X535750D01*
G01X547364D02*
X542836D01*
G01X554450D02*
X549923D01*
G01X507305Y193544D02*
X504942D01*
G01X556911D02*
X554549D01*
G01X557009Y193370D02*
X558668D01*
G01X549923D02*
X554450D01*
G01X542836D02*
X547364D01*
G01X535750D02*
X540277D01*
G01X528663D02*
X533191D01*
G01X521576D02*
X526104D01*
G01X507403D02*
X511931D01*
G01X502369D02*
X504844D01*
G01X519017D02*
X514490D01*
G01X507305Y191969D02*
X504942D01*
G01X556911D02*
X554549D01*
G01X507403Y191733D02*
X504844D01*
G01X514490D02*
X511931D01*
G01X521576D02*
X519017D01*
G01X528663D02*
X526104D01*
G01X535750D02*
X533191D01*
G01X542836D02*
X540277D01*
G01X549923D02*
X547364D01*
G01X557009D02*
X554450D01*
G01X558668Y190748D02*
X502369D01*
G01X553939Y190237D02*
X557521D01*
G01X525592D02*
X529175D01*
G01X515002D02*
X511419D01*
G01X543348D02*
X539765D01*
G01X558996Y190158D02*
X502369D01*
G01X558996Y189370D02*
X502858D01*
G01X501517Y180729D02*
X500961D01*
G01X507950Y180552D02*
X554485D01*
G01X504879D02*
X502858D01*
G01X558996D02*
X557556D01*
G01X502280Y179548D02*
X503461D01*
G01X510548D02*
X509367D01*
G01X517635D02*
X516454D01*
G01X524721D02*
X523540D01*
G01X531808D02*
X530627D01*
G01X538894D02*
X537713D01*
G01X545981D02*
X544800D01*
G01X553068D02*
X551887D01*
G01X556768Y162243D02*
X555272D01*
G01X507162Y161822D02*
X505666D01*
G01X556000Y159075D02*
X557442D01*
G01X508776Y158665D02*
X504052D01*
G01X558383D02*
X553658D01*
G01X501123Y157264D02*
X501517D01*
G01X507792Y156142D02*
X505036D01*
G01X557398D02*
X554642D01*
G01X568111Y261975D02*
G03X560237I-3937J0D01*
G01X558104Y228592D02*
X558076Y228533D01*
G01X558142Y228642D02*
X558104Y228592D01*
G01X558191Y228684D02*
X558142Y228642D01*
G01X558246Y228715D02*
X558191Y228684D01*
G01X558305Y228734D02*
X558246Y228715D01*
G01X558368Y228741D02*
X558305Y228734D01*
G01X556534Y228592D02*
X556506Y228533D01*
G01X556572Y228642D02*
X556534Y228592D01*
G01X556621Y228684D02*
X556572Y228642D01*
G01X556676Y228715D02*
X556621Y228684D01*
G01X556735Y228734D02*
X556676Y228715D01*
G01X556798Y228741D02*
X556735Y228734D01*
G01X543931Y228592D02*
X543903Y228533D01*
G01X543969Y228642D02*
X543931Y228592D01*
G01X544018Y228684D02*
X543969Y228642D01*
G01X544072Y228715D02*
X544018Y228684D01*
G01X544132Y228734D02*
X544072Y228715D01*
G01X544195Y228741D02*
X544132Y228734D01*
G01X542361Y228592D02*
X542333Y228533D01*
G01X542399Y228642D02*
X542361Y228592D01*
G01X542447Y228684D02*
X542399Y228642D01*
G01X542502Y228715D02*
X542447Y228684D01*
G01X542562Y228734D02*
X542502Y228715D01*
G01X542625Y228741D02*
X542562Y228734D01*
G01X529758Y228592D02*
X529730Y228533D01*
G01X529796Y228642D02*
X529758Y228592D01*
G01X529844Y228684D02*
X529796Y228642D01*
G01X529899Y228715D02*
X529844Y228684D01*
G01X529959Y228734D02*
X529899Y228715D01*
G01X530021Y228741D02*
X529959Y228734D01*
G01X528188Y228592D02*
X528160Y228533D01*
G01X528226Y228642D02*
X528188Y228592D01*
G01X528274Y228684D02*
X528226Y228642D01*
G01X528329Y228715D02*
X528274Y228684D01*
G01X528389Y228734D02*
X528329Y228715D01*
G01X528451Y228741D02*
X528389Y228734D01*
G01X499925Y210433D02*
X499624Y210480D01*
G01X515584Y228592D02*
X515557Y228533D01*
G01X515623Y228642D02*
X515584Y228592D01*
G01X515671Y228684D02*
X515623Y228642D01*
G01X515726Y228715D02*
X515671Y228684D01*
G01X515786Y228734D02*
X515726Y228715D01*
G01X515848Y228741D02*
X515786Y228734D01*
G01X514014Y228592D02*
X513987Y228533D01*
G01X514053Y228642D02*
X514014Y228592D01*
G01X514101Y228684D02*
X514053Y228642D01*
G01X514156Y228715D02*
X514101Y228684D01*
G01X514216Y228734D02*
X514156Y228715D01*
G01X514278Y228741D02*
X514216Y228734D01*
G01X513590Y226997D02*
X513620Y227012D01*
G01X513542Y226991D02*
X513590Y226997D01*
G01X513480Y226992D02*
X513542Y226991D01*
G01X527763Y226997D02*
X527794Y227012D01*
G01X527715Y226991D02*
X527763Y226997D01*
G01X527654Y226992D02*
X527715Y226991D01*
G01X541936Y226997D02*
X541967Y227012D01*
G01X541888Y226991D02*
X541936Y226997D01*
G01X541827Y226992D02*
X541888Y226991D01*
G01X556109Y226997D02*
X556140Y227012D01*
G01X556061Y226991D02*
X556109Y226997D01*
G01X556000Y226992D02*
X556061Y226991D01*
G01X508590Y228514D02*
X508967Y228426D01*
G01X508513Y228533D02*
X508590Y228514D01*
G01X522763D02*
X523140Y228426D01*
G01X522686Y228533D02*
X522763Y228514D01*
G01X536936D02*
X537314Y228426D01*
G01X536860Y228533D02*
X536936Y228514D01*
G01X551110D02*
X551487Y228426D01*
G01X551033Y228533D02*
X551110Y228514D01*
G01X510357Y226991D02*
X510419Y226992D01*
G01X510309Y226997D02*
X510357Y226991D01*
G01X510279Y227012D02*
X510309Y226997D01*
G01X524531Y226991D02*
X524592Y226992D01*
G01X524483Y226997D02*
X524531Y226991D01*
G01X524452Y227012D02*
X524483Y226997D01*
G01X538704Y226991D02*
X538765Y226992D01*
G01X538656Y226997D02*
X538704Y226991D01*
G01X538625Y227012D02*
X538656Y226997D01*
G01X552877Y226991D02*
X552938Y226992D01*
G01X552829Y226997D02*
X552877Y226991D01*
G01X552798Y227012D02*
X552829Y226997D01*
G01X513546Y227953D02*
X513383Y227395D01*
G01X513626Y228378D02*
X513546Y227953D01*
G01X513618Y228647D02*
X513626Y228378D01*
G01X513524Y228741D02*
X513618Y228647D01*
G01X527720Y227953D02*
X527556Y227395D01*
G01X527800Y228378D02*
X527720Y227953D01*
G01X527792Y228647D02*
X527800Y228378D01*
G01X527697Y228741D02*
X527792Y228647D01*
G01X541893Y227953D02*
X541729Y227395D01*
G01X541973Y228378D02*
X541893Y227953D01*
G01X541965Y228647D02*
X541973Y228378D01*
G01X541871Y228741D02*
X541965Y228647D01*
G01X556066Y227953D02*
X555902Y227395D01*
G01X556146Y228378D02*
X556066Y227953D01*
G01X556138Y228647D02*
X556146Y228378D01*
G01X556044Y228741D02*
X556138Y228647D01*
G01X513751Y228709D02*
X513524Y228741D01*
G01X513898Y228639D02*
X513751Y228709D01*
G01X513987Y228533D02*
X513898Y228639D01*
G01X527924Y228709D02*
X527697Y228741D01*
G01X528071Y228639D02*
X527924Y228709D01*
G01X528160Y228533D02*
X528071Y228639D01*
G01X542097Y228709D02*
X541871Y228741D01*
G01X542244Y228639D02*
X542097Y228709D01*
G01X542333Y228533D02*
X542244Y228639D01*
G01X510671Y226582D02*
X510768Y226378D01*
G01X510554Y226786D02*
X510671Y226582D01*
G01X510331Y227127D02*
X510554Y226786D01*
G01X556271Y228709D02*
X556044Y228741D01*
G01X556418Y228639D02*
X556271Y228709D01*
G01X556506Y228533D02*
X556418Y228639D01*
G01X524844Y226582D02*
X524941Y226378D01*
G01X524727Y226786D02*
X524844Y226582D01*
G01X524504Y227127D02*
X524727Y226786D01*
G01X539017Y226582D02*
X539115Y226378D01*
G01X538900Y226786D02*
X539017Y226582D01*
G01X538677Y227127D02*
X538900Y226786D01*
G01X553191Y226582D02*
X553288Y226378D01*
G01X553073Y226786D02*
X553191Y226582D01*
G01X552850Y227127D02*
X553073Y226786D01*
G01X510252Y227262D02*
X510331Y227127D01*
G01X510184Y227395D02*
X510252Y227262D01*
G01X524425D02*
X524504Y227127D01*
G01X524357Y227395D02*
X524425Y227262D01*
G01X538598D02*
X538677Y227127D01*
G01X538530Y227395D02*
X538598Y227262D01*
G01X508075Y228734D02*
X508012Y228741D01*
G01X508135Y228715D02*
X508075Y228734D01*
G01X508190Y228683D02*
X508135Y228715D01*
G01X508238Y228641D02*
X508190Y228683D01*
G01X508276Y228591D02*
X508238Y228641D01*
G01X508303Y228533D02*
X508276Y228591D01*
G01X508285Y228734D02*
X508222Y228741D01*
G01X508345Y228715D02*
X508285Y228734D01*
G01X508401Y228683D02*
X508345Y228715D01*
G01X508448Y228641D02*
X508401Y228683D01*
G01X508486Y228591D02*
X508448Y228641D01*
G01X508513Y228533D02*
X508486Y228591D01*
G01X509328Y228734D02*
X509265Y228741D01*
G01X509388Y228715D02*
X509328Y228734D01*
G01X509443Y228684D02*
X509388Y228715D01*
G01X509491Y228641D02*
X509443Y228684D01*
G01X509529Y228591D02*
X509491Y228641D01*
G01X509556Y228533D02*
X509529Y228591D01*
G01X509685Y228734D02*
X509621Y228741D01*
G01X509744Y228715D02*
X509685Y228734D01*
G01X509799Y228684D02*
X509744Y228715D01*
G01X509847Y228641D02*
X509799Y228684D01*
G01X509885Y228591D02*
X509847Y228641D01*
G01X509913Y228533D02*
X509885Y228591D01*
G01X522248Y228734D02*
X522185Y228741D01*
G01X522308Y228715D02*
X522248Y228734D01*
G01X522364Y228683D02*
X522308Y228715D01*
G01X522411Y228641D02*
X522364Y228683D01*
G01X522449Y228591D02*
X522411Y228641D01*
G01X522476Y228533D02*
X522449Y228591D01*
G01X522458Y228734D02*
X522395Y228741D01*
G01X522518Y228715D02*
X522458Y228734D01*
G01X522574Y228683D02*
X522518Y228715D01*
G01X522621Y228641D02*
X522574Y228683D01*
G01X522659Y228591D02*
X522621Y228641D01*
G01X522686Y228533D02*
X522659Y228591D01*
G01X523502Y228734D02*
X523438Y228741D01*
G01X523561Y228715D02*
X523502Y228734D01*
G01X523616Y228684D02*
X523561Y228715D01*
G01X523664Y228641D02*
X523616Y228684D01*
G01X523702Y228591D02*
X523664Y228641D01*
G01X523730Y228533D02*
X523702Y228591D01*
G01X523858Y228734D02*
X523794Y228741D01*
G01X523918Y228715D02*
X523858Y228734D01*
G01X523972Y228684D02*
X523918Y228715D01*
G01X524020Y228641D02*
X523972Y228684D01*
G01X524059Y228591D02*
X524020Y228641D01*
G01X524086Y228533D02*
X524059Y228591D01*
G01X536422Y228734D02*
X536358Y228741D01*
G01X536481Y228715D02*
X536422Y228734D01*
G01X536537Y228683D02*
X536481Y228715D01*
G01X536584Y228641D02*
X536537Y228683D01*
G01X536622Y228591D02*
X536584Y228641D01*
G01X536650Y228533D02*
X536622Y228591D01*
G01X536632Y228734D02*
X536568Y228741D01*
G01X536691Y228715D02*
X536632Y228734D01*
G01X536747Y228683D02*
X536691Y228715D01*
G01X536794Y228641D02*
X536747Y228683D01*
G01X536832Y228591D02*
X536794Y228641D01*
G01X536860Y228533D02*
X536832Y228591D01*
G01X537675Y228734D02*
X537611Y228741D01*
G01X537735Y228715D02*
X537675Y228734D01*
G01X537789Y228684D02*
X537735Y228715D01*
G01X537838Y228641D02*
X537789Y228684D01*
G01X537876Y228591D02*
X537838Y228641D01*
G01X537903Y228533D02*
X537876Y228591D01*
G01X538031Y228734D02*
X537968Y228741D01*
G01X538091Y228715D02*
X538031Y228734D01*
G01X538145Y228684D02*
X538091Y228715D01*
G01X538194Y228641D02*
X538145Y228684D01*
G01X538232Y228591D02*
X538194Y228641D01*
G01X538259Y228533D02*
X538232Y228591D01*
G01X510281Y228650D02*
X510375Y228741D01*
G01X510272Y228383D02*
X510281Y228650D01*
G01X510352Y227957D02*
X510272Y228383D01*
G01X510516Y227395D02*
X510352Y227957D01*
G01X500888Y210365D02*
X500729Y210433D01*
G01X501014Y210183D02*
X500888Y210365D01*
G01X501095Y209930D02*
X501014Y210183D01*
G01X501123Y209646D02*
X501095Y209930D01*
G01X509782Y225061D02*
X509715Y225281D01*
G01X509823Y224836D02*
X509782Y225061D01*
G01X509837Y224608D02*
X509823Y224836D01*
G01X510160Y225152D02*
X510080Y225415D01*
G01X510208Y224882D02*
X510160Y225152D01*
G01X510224Y224608D02*
X510208Y224882D01*
G01X509571Y225062D02*
X509505Y225281D01*
G01X509612Y224836D02*
X509571Y225062D01*
G01X509625Y224608D02*
X509612Y224836D01*
G01X510185Y226792D02*
X510119Y227012D01*
G01X510225Y226567D02*
X510185Y226792D01*
G01X510239Y226338D02*
X510225Y226567D01*
G01X552771Y227262D02*
X552850Y227127D01*
G01X552703Y227395D02*
X552771Y227262D01*
G01X550595Y228734D02*
X550531Y228741D01*
G01X550655Y228715D02*
X550595Y228734D01*
G01X550710Y228683D02*
X550655Y228715D01*
G01X550757Y228641D02*
X550710Y228683D01*
G01X550796Y228591D02*
X550757Y228641D01*
G01X550823Y228533D02*
X550796Y228591D01*
G01X550805Y228734D02*
X550741Y228741D01*
G01X550865Y228715D02*
X550805Y228734D01*
G01X550920Y228683D02*
X550865Y228715D01*
G01X550968Y228641D02*
X550920Y228683D01*
G01X551006Y228591D02*
X550968Y228641D01*
G01X551033Y228533D02*
X551006Y228591D01*
G01X551848Y228734D02*
X551785Y228741D01*
G01X551908Y228715D02*
X551848Y228734D01*
G01X551963Y228684D02*
X551908Y228715D01*
G01X552011Y228641D02*
X551963Y228684D01*
G01X552049Y228591D02*
X552011Y228641D01*
G01X552076Y228533D02*
X552049Y228591D01*
G01X552204Y228734D02*
X552141Y228741D01*
G01X552264Y228715D02*
X552204Y228734D01*
G01X552319Y228684D02*
X552264Y228715D01*
G01X552367Y228641D02*
X552319Y228684D01*
G01X552405Y228591D02*
X552367Y228641D01*
G01X552432Y228533D02*
X552405Y228591D01*
G01X524455Y228650D02*
X524548Y228741D01*
G01X524445Y228383D02*
X524455Y228650D01*
G01X524525Y227957D02*
X524445Y228383D01*
G01X524690Y227395D02*
X524525Y227957D01*
G01X538628Y228650D02*
X538721Y228741D01*
G01X538619Y228383D02*
X538628Y228650D01*
G01X538698Y227957D02*
X538619Y228383D01*
G01X538863Y227395D02*
X538698Y227957D01*
G01X552801Y228650D02*
X552895Y228741D01*
G01X552792Y228383D02*
X552801Y228650D01*
G01X552871Y227957D02*
X552792Y228383D01*
G01X553036Y227395D02*
X552871Y227957D01*
G01X510367Y226585D02*
X510381Y226372D01*
G01X510333Y226800D02*
X510367Y226585D01*
G01X510279Y227012D02*
X510333Y226800D01*
G01X524540Y226585D02*
X524554Y226372D01*
G01X524506Y226800D02*
X524540Y226585D01*
G01X524452Y227012D02*
X524506Y226800D01*
G01X538713Y226585D02*
X538727Y226372D01*
G01X538680Y226800D02*
X538713Y226585D01*
G01X538625Y227012D02*
X538680Y226800D01*
G01X510097Y227630D02*
X510279Y227012D01*
G01X509981Y228113D02*
X510097Y227630D01*
G01X509913Y228533D02*
X509981Y228113D01*
G01X524270Y227630D02*
X524452Y227012D01*
G01X524155Y228113D02*
X524270Y227630D01*
G01X524086Y228533D02*
X524155Y228113D01*
G01X501018Y210378D02*
X500729Y210433D01*
G01X501240Y210245D02*
X501018Y210378D01*
G01X501396Y210065D02*
X501240Y210245D01*
G01X501487Y209861D02*
X501396Y210065D01*
G01X501516Y209646D02*
X501487Y209861D01*
G01X523956Y225061D02*
X523889Y225281D01*
G01X523996Y224836D02*
X523956Y225061D01*
G01X524010Y224608D02*
X523996Y224836D01*
G01X538129Y225061D02*
X538062Y225281D01*
G01X538169Y224836D02*
X538129Y225061D01*
G01X538183Y224608D02*
X538169Y224836D01*
G01X552302Y225061D02*
X552235Y225281D01*
G01X552343Y224836D02*
X552302Y225061D01*
G01X552356Y224608D02*
X552343Y224836D01*
G01X524333Y225152D02*
X524253Y225415D01*
G01X524381Y224882D02*
X524333Y225152D01*
G01X524398Y224608D02*
X524381Y224882D01*
G01X538506Y225152D02*
X538426Y225415D01*
G01X538555Y224882D02*
X538506Y225152D01*
G01X538571Y224608D02*
X538555Y224882D01*
G01X552679Y225152D02*
X552599Y225415D01*
G01X552728Y224882D02*
X552679Y225152D01*
G01X552744Y224608D02*
X552728Y224882D01*
G01X523745Y225062D02*
X523678Y225281D01*
G01X523785Y224836D02*
X523745Y225062D01*
G01X523798Y224608D02*
X523785Y224836D01*
G01X537918Y225062D02*
X537852Y225281D01*
G01X537958Y224836D02*
X537918Y225062D01*
G01X537972Y224608D02*
X537958Y224836D01*
G01X552091Y225062D02*
X552025Y225281D01*
G01X552131Y224836D02*
X552091Y225062D01*
G01X552145Y224608D02*
X552131Y224836D01*
G01X524358Y226792D02*
X524292Y227012D01*
G01X524398Y226567D02*
X524358Y226792D01*
G01X524412Y226338D02*
X524398Y226567D01*
G01X538532Y226792D02*
X538465Y227012D01*
G01X538572Y226567D02*
X538532Y226792D01*
G01X538585Y226338D02*
X538572Y226567D01*
G01X552705Y226792D02*
X552639Y227012D01*
G01X552745Y226567D02*
X552705Y226792D01*
G01X552758Y226338D02*
X552745Y226567D01*
G01X514288Y225061D02*
X514355Y225281D01*
G01X514248Y224836D02*
X514288Y225061D01*
G01X514235Y224608D02*
X514248Y224836D01*
G01X528461Y225061D02*
X528528Y225281D01*
G01X528421Y224836D02*
X528461Y225061D01*
G01X528408Y224608D02*
X528421Y224836D01*
G01X513566Y226800D02*
X513620Y227012D01*
G01X513532Y226585D02*
X513566Y226800D01*
G01X513519Y226372D02*
X513532Y226585D01*
G01X527739Y226800D02*
X527794Y227012D01*
G01X527705Y226585D02*
X527739Y226800D01*
G01X527692Y226372D02*
X527705Y226585D01*
G01X513801Y227627D02*
X513620Y227012D01*
G01X513917Y228109D02*
X513801Y227627D01*
G01X513987Y228533D02*
X513917Y228109D01*
G01X552887Y226585D02*
X552900Y226372D01*
G01X552853Y226800D02*
X552887Y226585D01*
G01X552798Y227012D02*
X552853Y226800D01*
G01X538443Y227630D02*
X538625Y227012D01*
G01X538328Y228113D02*
X538443Y227630D01*
G01X538259Y228533D02*
X538328Y228113D01*
G01X552616Y227630D02*
X552798Y227012D01*
G01X552501Y228113D02*
X552616Y227630D01*
G01X552432Y228533D02*
X552501Y228113D01*
G01X542635Y225061D02*
X542701Y225281D01*
G01X542595Y224836D02*
X542635Y225061D01*
G01X542581Y224608D02*
X542595Y224836D01*
G01X556808Y225061D02*
X556874Y225281D01*
G01X556768Y224836D02*
X556808Y225061D01*
G01X556754Y224608D02*
X556768Y224836D01*
G01X541912Y226800D02*
X541967Y227012D01*
G01X541879Y226585D02*
X541912Y226800D01*
G01X541865Y226372D02*
X541879Y226585D01*
G01X556086Y226800D02*
X556140Y227012D01*
G01X556052Y226585D02*
X556086Y226800D01*
G01X556038Y226372D02*
X556052Y226585D01*
G01X527975Y227627D02*
X527794Y227012D01*
G01X528090Y228109D02*
X527975Y227627D01*
G01X528160Y228533D02*
X528090Y228109D01*
G01X542148Y227627D02*
X541967Y227012D01*
G01X542264Y228109D02*
X542148Y227627D01*
G01X542333Y228533D02*
X542264Y228109D01*
G01X556321Y227627D02*
X556140Y227012D01*
G01X556437Y228109D02*
X556321Y227627D01*
G01X556506Y228533D02*
X556437Y228109D01*
G01X513674Y226567D02*
X513660Y226338D01*
G01X513714Y226792D02*
X513674Y226567D01*
G01X513780Y227012D02*
X513714Y226792D01*
G01X527847Y226567D02*
X527834Y226338D01*
G01X527887Y226792D02*
X527847Y226567D01*
G01X527954Y227012D02*
X527887Y226792D01*
G01X542020Y226567D02*
X542007Y226338D01*
G01X542060Y226792D02*
X542020Y226567D01*
G01X542127Y227012D02*
X542060Y226792D01*
G01X513652Y224882D02*
X513635Y224608D01*
G01X513700Y225152D02*
X513652Y224882D01*
G01X513780Y225415D02*
X513700Y225152D01*
G01X527825Y224882D02*
X527809Y224608D01*
G01X527873Y225152D02*
X527825Y224882D01*
G01X527953Y225415D02*
X527873Y225152D01*
G01X541998Y224882D02*
X541982Y224608D01*
G01X542047Y225152D02*
X541998Y224882D01*
G01X542127Y225415D02*
X542047Y225152D01*
G01X514037Y224836D02*
X514023Y224608D01*
G01X514077Y225061D02*
X514037Y224836D01*
G01X514144Y225281D02*
X514077Y225061D01*
G01X528210Y224836D02*
X528196Y224608D01*
G01X528251Y225061D02*
X528210Y224836D01*
G01X528318Y225281D02*
X528251Y225061D01*
G01X542383Y224836D02*
X542370Y224608D01*
G01X542424Y225061D02*
X542383Y224836D01*
G01X542491Y225281D02*
X542424Y225061D01*
G01X514571Y228734D02*
X514634Y228741D01*
G01X514511Y228715D02*
X514571Y228734D01*
G01X514455Y228683D02*
X514511Y228715D01*
G01X514408Y228641D02*
X514455Y228683D01*
G01X514370Y228591D02*
X514408Y228641D01*
G01X514343Y228533D02*
X514370Y228591D01*
G01X515575Y228734D02*
X515638Y228741D01*
G01X515515Y228715D02*
X515575Y228734D01*
G01X515459Y228683D02*
X515515Y228715D01*
G01X515412Y228641D02*
X515459Y228683D01*
G01X515374Y228591D02*
X515412Y228641D01*
G01X515347Y228533D02*
X515374Y228591D01*
G01X528744Y228734D02*
X528807Y228741D01*
G01X528684Y228715D02*
X528744Y228734D01*
G01X528629Y228683D02*
X528684Y228715D01*
G01X528581Y228641D02*
X528629Y228683D01*
G01X528543Y228591D02*
X528581Y228641D01*
G01X528516Y228533D02*
X528543Y228591D01*
G01X529748Y228734D02*
X529811Y228741D01*
G01X529688Y228715D02*
X529748Y228734D01*
G01X529632Y228683D02*
X529688Y228715D01*
G01X529585Y228641D02*
X529632Y228683D01*
G01X529547Y228591D02*
X529585Y228641D01*
G01X529520Y228533D02*
X529547Y228591D01*
G01X513228Y226582D02*
X513345Y226786D01*
G01X513131Y226378D02*
X513228Y226582D01*
G01X527401D02*
X527519Y226786D01*
G01X527304Y226378D02*
X527401Y226582D01*
G01X513647Y227262D02*
X513716Y227395D01*
G01X513569Y227127D02*
X513647Y227262D01*
G01X513345Y226786D02*
X513569Y227127D01*
G01X556194Y226567D02*
X556180Y226338D01*
G01X556234Y226792D02*
X556194Y226567D01*
G01X556300Y227012D02*
X556234Y226792D01*
G01X556171Y224882D02*
X556155Y224608D01*
G01X556220Y225152D02*
X556171Y224882D01*
G01X556300Y225415D02*
X556220Y225152D01*
G01X556556Y224836D02*
X556543Y224608D01*
G01X556597Y225061D02*
X556556Y224836D01*
G01X556664Y225281D02*
X556597Y225061D01*
G01X542917Y228734D02*
X542981Y228741D01*
G01X542857Y228715D02*
X542917Y228734D01*
G01X542802Y228683D02*
X542857Y228715D01*
G01X542755Y228641D02*
X542802Y228683D01*
G01X542716Y228591D02*
X542755Y228641D01*
G01X542689Y228533D02*
X542716Y228591D01*
G01X543921Y228734D02*
X543984Y228741D01*
G01X543861Y228715D02*
X543921Y228734D01*
G01X543806Y228683D02*
X543861Y228715D01*
G01X543758Y228641D02*
X543806Y228683D01*
G01X543720Y228591D02*
X543758Y228641D01*
G01X543693Y228533D02*
X543720Y228591D01*
G01X557090Y228734D02*
X557154Y228741D01*
G01X557031Y228715D02*
X557090Y228734D01*
G01X556975Y228683D02*
X557031Y228715D01*
G01X556928Y228641D02*
X556975Y228683D01*
G01X556890Y228591D02*
X556928Y228641D01*
G01X556862Y228533D02*
X556890Y228591D01*
G01X558094Y228734D02*
X558158Y228741D01*
G01X558035Y228715D02*
X558094Y228734D01*
G01X557979Y228683D02*
X558035Y228715D01*
G01X557932Y228641D02*
X557979Y228683D01*
G01X557894Y228591D02*
X557932Y228641D01*
G01X557866Y228533D02*
X557894Y228591D01*
G01X541575Y226582D02*
X541692Y226786D01*
G01X541477Y226378D02*
X541575Y226582D01*
G01X555748D02*
X555865Y226786D01*
G01X555651Y226378D02*
X555748Y226582D01*
G01X527821Y227262D02*
X527889Y227395D01*
G01X527742Y227127D02*
X527821Y227262D01*
G01X527519Y226786D02*
X527742Y227127D01*
G01X541994Y227262D02*
X542062Y227395D01*
G01X541915Y227127D02*
X541994Y227262D01*
G01X541692Y226786D02*
X541915Y227127D01*
G01X556167Y227262D02*
X556235Y227395D01*
G01X556088Y227127D02*
X556167Y227262D01*
G01X555865Y226786D02*
X556088Y227127D01*
G01X510152Y228710D02*
X510375Y228741D01*
G01X509994Y228633D02*
X510152Y228710D01*
G01X509913Y228533D02*
X509994Y228633D01*
G01X524325Y228710D02*
X524548Y228741D01*
G01X524167Y228633D02*
X524325Y228710D01*
G01X524086Y228533D02*
X524167Y228633D01*
G01X538498Y228710D02*
X538721Y228741D01*
G01X538340Y228633D02*
X538498Y228710D01*
G01X538259Y228533D02*
X538340Y228633D01*
G01X552672Y228710D02*
X552895Y228741D01*
G01X552514Y228633D02*
X552672Y228710D01*
G01X552432Y228533D02*
X552514Y228633D01*
G01X556681Y226871D02*
G03X556586Y226338I1440J-532D01*
G01X551739Y224608D02*
G03X551644Y225140I-1535J0D01*
G01X552352Y226338D02*
G03X552257Y226871I-1535J1D01*
G01X557256Y225140D02*
G03X557160Y224608I1440J-534D01*
G01X542508Y226871D02*
G03X542412Y226338I1440J-534D01*
G01X528335Y226871D02*
G03X528239Y226338I1440J-534D01*
G01X537566Y224608D02*
G03X537471Y225140I-1536J0D01*
G01X538179Y226338D02*
G03X538084Y226871I-1535J1D01*
G01X528909Y225140D02*
G03X528814Y224608I1440J-532D01*
G01X543082Y225140D02*
G03X542987Y224608I1441J-532D01*
G01X514161Y226871D02*
G03X514066Y226338I1440J-532D01*
G01X523393Y224608D02*
G03X523297Y225140I-1536J-2D01*
G01X524006Y226338D02*
G03X523911Y226871I-1535J1D01*
G01X514736Y225140D02*
G03X514641Y224608I1440J-532D01*
G01X509219D02*
G03X509124Y225140I-1535J0D01*
G01X509833Y226338D02*
G03X509737Y226871I-1536J-1D01*
G01X501517Y209646D02*
G03X500729Y210433I-787J0D01*
G01X552076Y228533D02*
X551702Y228426D01*
G01X550449D02*
X550823Y228533D01*
G01X552599Y225416D02*
X552235Y225281D01*
G01X552025D02*
X551661Y225146D01*
G01X552639Y227012D02*
X552274Y226877D01*
G01X538426Y225416D02*
X538062Y225281D01*
G01X537852D02*
X537487Y225146D01*
G01X538465Y227012D02*
X538101Y226877D01*
G01X558274Y228741D02*
X556929Y227395D01*
G01X551778Y228741D02*
X550433Y227395D01*
G01X537903Y228533D02*
X537529Y228426D01*
G01X536275D02*
X536650Y228533D01*
G01X523730D02*
X523355Y228426D01*
G01X522102D02*
X522476Y228533D01*
G01X509556D02*
X509182Y228426D01*
G01X507929D02*
X508303Y228533D01*
G01X524253Y225416D02*
X523889Y225281D01*
G01X523678D02*
X523314Y225146D01*
G01X524292Y227012D02*
X523928Y226877D01*
G01X510080Y225416D02*
X509715Y225281D01*
G01X509505D02*
X509141Y225146D01*
G01X510119Y227012D02*
X509755Y226877D01*
G01X544692Y228741D02*
X543347Y227395D01*
G01X537605Y228741D02*
X536260Y227395D01*
G01X530518Y228741D02*
X529173Y227395D01*
G01X523432Y228741D02*
X522087Y227395D01*
G01X516345Y228741D02*
X515000Y227395D01*
G01X509259Y228741D02*
X507914Y227395D01*
G01X558451Y228426D02*
X557239Y225146D01*
G01X556874Y225281D02*
X558076Y228533D01*
G01X557866D02*
X556664Y225281D01*
G01X556300Y225416D02*
X557412Y228426D01*
G01X556664Y226877D02*
X557225Y228394D01*
G01X556862Y228533D02*
X556300Y227012D01*
G01X544277Y228426D02*
X543065Y225146D01*
G01X542701Y225281D02*
X543903Y228533D01*
G01X543693D02*
X542491Y225281D01*
G01X542127Y225416D02*
X543239Y228426D01*
G01X542491Y226877D02*
X543052Y228394D01*
G01X542689Y228533D02*
X542127Y227012D01*
G01X530104Y228426D02*
X528892Y225146D01*
G01X528528Y225281D02*
X529730Y228533D01*
G01X529520D02*
X528318Y225281D01*
G01X527953Y225416D02*
X529066Y228426D01*
G01X528318Y226877D02*
X528879Y228394D01*
G01X528516Y228533D02*
X527954Y227012D01*
G01X515931Y228426D02*
X514719Y225146D01*
G01X514355Y225281D02*
X515557Y228533D01*
G01X515347D02*
X514144Y225281D01*
G01X513780Y225416D02*
X514893Y228426D01*
G01X514145Y226877D02*
X514705Y228394D01*
G01X514343Y228533D02*
X513780Y227012D01*
G01X556038Y226372D02*
Y226338D01*
G01X555650D02*
X555651Y226378D01*
G01X558451Y228426D02*
Y228741D01*
G01X557412Y228426D02*
Y228741D01*
G01X557225D02*
Y220867D01*
G01X551702Y228741D02*
Y228426D01*
G01X551487D02*
Y228741D01*
G01X550449D02*
Y228426D01*
G01X550302Y228741D02*
Y220867D01*
G01X552900Y226372D02*
Y226338D01*
G01X553288Y226378D02*
Y226338D01*
G01X541865Y226372D02*
Y226338D01*
G01X541477D02*
Y226378D01*
G01X527692Y226372D02*
Y226338D01*
G01X527304D02*
Y226378D01*
G01X513519Y226372D02*
X513518Y226338D01*
G01X513131D02*
Y226378D01*
G01X545774Y220867D02*
Y228741D01*
G01X545414D02*
Y220867D01*
G01X544277Y228426D02*
Y228741D01*
G01X543239Y228426D02*
Y228741D01*
G01X543052D02*
Y220867D01*
G01X537529Y228741D02*
Y228426D01*
G01X537314D02*
Y228741D01*
G01X536275D02*
Y228426D01*
G01X536129Y228741D02*
Y220867D01*
G01X531601D02*
Y228741D01*
G01X531241D02*
Y220867D01*
G01X530104Y228426D02*
Y228741D01*
G01X529066Y228426D02*
Y228741D01*
G01X528879D02*
Y220867D01*
G01X523355Y228741D02*
Y228426D01*
G01X523140D02*
Y228741D01*
G01X522102D02*
Y228426D01*
G01X521955Y228741D02*
Y220867D01*
G01X517428D02*
Y228741D01*
G01X517068D02*
Y220867D01*
G01X515931Y228426D02*
Y228741D01*
G01X514893Y228426D02*
Y228741D01*
G01X514705D02*
Y220867D01*
G01X509182Y228426D02*
Y228741D01*
G01X508967Y228426D02*
Y228741D01*
G01X538727Y226372D02*
Y226338D01*
G01X524554Y226372D02*
Y226338D01*
G01X510381Y226372D02*
Y226338D01*
G01X539115Y226378D02*
Y226338D01*
G01X524941Y226378D02*
X524942Y226338D01*
G01X510768Y226378D02*
X510769Y226338D01*
G01X552639Y227012D02*
X552076Y228533D01*
G01X551702Y228426D02*
X552274Y226877D01*
G01X551487Y228426D02*
X552599Y225416D01*
G01X552235Y225281D02*
X551033Y228533D01*
G01X550823D02*
X552025Y225281D01*
G01X551661Y225146D02*
X550449Y228426D01*
G01X538465Y227012D02*
X537903Y228533D01*
G01X537529Y228426D02*
X538101Y226877D01*
G01X537314Y228426D02*
X538426Y225416D01*
G01X538062Y225281D02*
X536860Y228533D01*
G01X536650D02*
X537852Y225281D01*
G01X537487Y225146D02*
X536275Y228426D01*
G01X507929Y228741D02*
Y228426D01*
G01X507782Y228741D02*
Y220867D01*
G01X524292Y227012D02*
X523730Y228533D01*
G01X523355Y228426D02*
X523928Y226877D01*
G01X523140Y228426D02*
X524253Y225416D01*
G01X523889Y225281D02*
X522686Y228533D01*
G01X522476D02*
X523678Y225281D01*
G01X523314Y225146D02*
X522102Y228426D01*
G01X510119Y227012D02*
X509556Y228533D01*
G01X509182Y228426D02*
X509755Y226877D01*
G01X508967Y228426D02*
X510080Y225416D01*
G01X509715Y225281D02*
X508513Y228533D01*
G01X508303D02*
X509505Y225281D01*
G01X509141Y225146D02*
X507929Y228426D01*
G01X552959Y228741D02*
X554305Y227395D01*
G01X545873Y228741D02*
X547218Y227395D01*
G01X540131D02*
X538786Y228741D01*
G01X533045Y227395D02*
X531700Y228741D01*
G01X525958Y227395D02*
X524613Y228741D01*
G01X518871Y227395D02*
X517526Y228741D01*
G01X511785Y227395D02*
X510440Y228741D01*
G01X504698Y227395D02*
X503353Y228741D01*
G01X556300Y227012D02*
X556664Y226877D01*
G01X557239Y225146D02*
X556874Y225281D01*
G01X556664D02*
X556300Y225415D01*
G01X542127Y227012D02*
X542491Y226877D01*
G01X543065Y225146D02*
X542701Y225281D01*
G01X542491D02*
X542127Y225415D01*
G01X527954Y227012D02*
X528318Y226877D01*
G01X528892Y225146D02*
X528528Y225281D01*
G01X528318D02*
X527953Y225415D01*
G01X513780Y227012D02*
X514145Y226877D01*
G01X514355Y225281D02*
X514719Y225146D01*
G01X514144Y225281D02*
X513780Y225415D01*
G01X558451Y228426D02*
X558076Y228533D01*
G01X556862D02*
X557225Y228429D01*
G01X543903Y228533D02*
X544277Y228426D01*
G01X542689Y228533D02*
X543052Y228429D01*
G01X529730Y228533D02*
X530104Y228426D01*
G01X528516Y228533D02*
X528879Y228429D01*
G01X515557Y228533D02*
X515931Y228426D01*
G01X514343Y228533D02*
X514705Y228429D01*
G01X555651Y226378D02*
X556038Y226372D01*
G01X541477Y226378D02*
X541865Y226372D01*
G01X527304Y226378D02*
X527692Y226372D01*
G01X513131Y226378D02*
X513519Y226372D01*
G01X502369Y228741D02*
X558668D01*
G01X556506Y228533D02*
X556862D01*
G01X542333D02*
X542689D01*
G01X528160D02*
X528516D01*
G01X513987D02*
X514343D01*
G01X509556D02*
X509913D01*
G01X508513D02*
X508303D01*
G01X515557D02*
X515347D01*
G01X522686D02*
X522476D01*
G01X529730D02*
X529520D01*
G01X536860D02*
X536650D01*
G01X543903D02*
X543693D01*
G01X551033D02*
X550823D01*
G01X558076D02*
X557866D01*
G01X552076D02*
X552432D01*
G01X537903D02*
X538259D01*
G01X523730D02*
X524086D01*
G01X502369Y228426D02*
X514893D01*
G01X529066D02*
X515931D01*
G01X543239D02*
X530104D01*
G01X557412D02*
X544277D01*
G01X558668D02*
X558451D01*
G01X507782Y228253D02*
X502369D01*
G01X517068D02*
X514705D01*
G01X521955D02*
X517428D01*
G01X531241D02*
X528879D01*
G01X536129D02*
X531601D01*
G01X545414D02*
X543052D01*
G01X550302D02*
X545774D01*
G01X558668D02*
X557225D01*
G01X507914Y227395D02*
X504698D01*
G01X515000D02*
X510184D01*
G01X522087D02*
X518871D01*
G01X529173D02*
X524357D01*
G01X536260D02*
X533045D01*
G01X543347D02*
X538530D01*
G01X550433D02*
X547218D01*
G01X556929D02*
X552703D01*
G01X556140Y227012D02*
X556300D01*
G01X541967D02*
X542127D01*
G01X527794D02*
X527954D01*
G01X513620D02*
X513780D01*
G01X510279D02*
X510119D01*
G01X524452D02*
X524292D01*
G01X538625D02*
X538465D01*
G01X552798D02*
X552639D01*
G01X552371Y226338D02*
X553288D01*
G01X538197D02*
X539115D01*
G01X524024D02*
X524942D01*
G01X509851D02*
X510769D01*
G01X555650D02*
X556568D01*
G01X541477D02*
X542395D01*
G01X527304D02*
X528221D01*
G01X513131D02*
X514048D01*
G01X521267Y225788D02*
X517341D01*
G01X535440D02*
X531514D01*
G01X549613D02*
X545687D01*
G01X542701Y225281D02*
X542491D01*
G01X556874D02*
X556664D01*
G01X514355D02*
X514144D01*
G01X528528D02*
X528318D01*
G01X509715D02*
X509505D01*
G01X523889D02*
X523678D01*
G01X538062D02*
X537852D01*
G01X552235D02*
X552025D01*
G01X551757Y224608D02*
X552744D01*
G01X541982D02*
X542969D01*
G01X537584D02*
X538571D01*
G01X527809D02*
X528796D01*
G01X523411D02*
X524398D01*
G01X513635D02*
X514622D01*
G01X509237D02*
X510224D01*
G01X557142D02*
X556155D01*
G01X510768Y226378D02*
X510380Y226372D01*
G01X524941Y226378D02*
X524554Y226372D01*
G01X539115Y226378D02*
X538727Y226372D01*
G01X553288Y226378D02*
X552900Y226372D01*
G01X558668Y220866D02*
X557225D01*
G01X507782Y220867D02*
X502369D01*
G01X517068D02*
X514705D01*
G01X521955D02*
X517428D01*
G01X531241D02*
X528879D01*
G01X536129D02*
X531601D01*
G01X545414D02*
X543052D01*
G01X550302D02*
X545774D01*
G01X514893Y228426D02*
X515270Y228514D01*
G01X529066Y228426D02*
X529443Y228514D01*
G01X543239Y228426D02*
X543616Y228514D01*
G01X557412Y228426D02*
X557790Y228514D01*
G01X515270D02*
X515347Y228533D01*
G01X529443Y228514D02*
X529520Y228533D01*
G01X543616Y228514D02*
X543693Y228533D01*
G01X557790Y228514D02*
X557866Y228533D01*
G01X560237Y551040D02*
Y292684D01*
G01D02*
G03X568111I3937J0D01*
G01Y551040D02*
G03X560237I-3937J0D01*
G01Y581748D02*
G03X568111I3937J0D01*
G01X561484Y594905D02*
G03X560237Y589622I10564J-5282D01*
G01X579665Y631267D02*
X561484Y594904D01*
G01X560237Y589622D02*
Y581748D01*
G01X568526Y591383D02*
G03X568111Y589622I3522J-1759D01*
G01X586707Y627745D02*
X568526Y591383D01*
G01X528179Y763780D02*
Y763386D01*
G01Y763780D02*
Y764174D01*
G01X527687Y763780D02*
X528671D01*
G01X559674Y762380D02*
Y765180D01*
G01X524242Y763780D02*
G03X532116I3937J0D01*
G01X834646D02*
X532116D01*
G01X519032Y1463291D02*
Y1444354D01*
G01X594685Y307087D02*
G03I-6889J0D01*
G01X597441Y472441D02*
G03I-6889J0D01*
G01X590229Y637796D02*
G03X579665Y631268I0J-11812D01*
G01X590229Y629922D02*
G03X586708Y627746I0J-3937D01*
G01X619095Y606300D02*
G03I-6890J0D01*
G01X590229Y629922D02*
X842520D01*
G01X590229Y637796D02*
X838583D01*
G01X622665Y762380D02*
Y765180D01*
G01X591170Y762380D02*
Y765180D01*
G01X712599Y86811D02*
G03X700000I-6299J0D01*
G01Y80512D02*
G03X712599I6299J0D01*
G01Y86811D02*
Y80512D01*
G01X700000Y86811D02*
Y80512D01*
G01X712599Y204922D02*
G03X700000I-6299J0D01*
G01Y198622D02*
G03X712599I6299J0D01*
G01Y204922D02*
Y198622D01*
G01X700000Y204922D02*
Y198622D01*
G01X671217Y513302D02*
X671221Y513274D01*
G01X671206Y513328D02*
X671217Y513302D01*
G01X671188Y513352D02*
X671206Y513328D01*
G01X671163Y513373D02*
X671188Y513352D01*
G01X671133Y513391D02*
X671163Y513373D01*
G01X671099Y513404D02*
X671133Y513391D01*
G01X671062Y513412D02*
X671099Y513404D01*
G01X671024Y513414D02*
X671062Y513412D01*
G01X673185Y513302D02*
X673189Y513274D01*
G01X673174Y513328D02*
X673185Y513302D01*
G01X673156Y513352D02*
X673174Y513328D01*
G01X673132Y513373D02*
X673156Y513352D01*
G01X673101Y513391D02*
X673132Y513373D01*
G01X673068Y513404D02*
X673101Y513391D01*
G01X673031Y513412D02*
X673068Y513404D01*
G01X672992Y513414D02*
X673031Y513412D01*
G01X675154Y513302D02*
X675158Y513274D01*
G01X675143Y513328D02*
X675154Y513302D01*
G01X675125Y513352D02*
X675143Y513328D01*
G01X675100Y513373D02*
X675125Y513352D01*
G01X675070Y513391D02*
X675100Y513373D01*
G01X675036Y513404D02*
X675070Y513391D01*
G01X674999Y513412D02*
X675036Y513404D01*
G01X674961Y513414D02*
X674999Y513412D01*
G01X677122Y513302D02*
X677126Y513274D01*
G01X677111Y513328D02*
X677122Y513302D01*
G01X677093Y513352D02*
X677111Y513328D01*
G01X677069Y513373D02*
X677093Y513352D01*
G01X677038Y513391D02*
X677069Y513373D01*
G01X677005Y513404D02*
X677038Y513391D01*
G01X676968Y513412D02*
X677005Y513404D01*
G01X676929Y513414D02*
X676968Y513412D01*
G01X679091Y513302D02*
X679095Y513274D01*
G01X679080Y513328D02*
X679091Y513302D01*
G01X679062Y513352D02*
X679080Y513328D01*
G01X679037Y513373D02*
X679062Y513352D01*
G01X679007Y513391D02*
X679037Y513373D01*
G01X678973Y513404D02*
X679007Y513391D01*
G01X678936Y513412D02*
X678973Y513404D01*
G01X678898Y513414D02*
X678936Y513412D01*
G01X681059Y513302D02*
X681063Y513274D01*
G01X681048Y513328D02*
X681059Y513302D01*
G01X681030Y513352D02*
X681048Y513328D01*
G01X681006Y513373D02*
X681030Y513352D01*
G01X680975Y513391D02*
X681006Y513373D01*
G01X680942Y513404D02*
X680975Y513391D01*
G01X680905Y513412D02*
X680942Y513404D01*
G01X680867Y513414D02*
X680905Y513412D01*
G01X683028Y513302D02*
X683032Y513274D01*
G01X683017Y513328D02*
X683028Y513302D01*
G01X682999Y513352D02*
X683017Y513328D01*
G01X682974Y513373D02*
X682999Y513352D01*
G01X682944Y513391D02*
X682974Y513373D01*
G01X682910Y513404D02*
X682944Y513391D01*
G01X682873Y513412D02*
X682910Y513404D01*
G01X682835Y513414D02*
X682873Y513412D01*
G01X684996Y513302D02*
X685000Y513274D01*
G01X684985Y513328D02*
X684996Y513302D01*
G01X684967Y513352D02*
X684985Y513328D01*
G01X684943Y513373D02*
X684967Y513352D01*
G01X684912Y513391D02*
X684943Y513373D01*
G01X684879Y513404D02*
X684912Y513391D01*
G01X684842Y513412D02*
X684879Y513404D01*
G01X684804Y513414D02*
X684842Y513412D01*
G01X686965Y513302D02*
X686969Y513274D01*
G01X686954Y513328D02*
X686965Y513302D01*
G01X686936Y513352D02*
X686954Y513328D01*
G01X686911Y513373D02*
X686936Y513352D01*
G01X686881Y513391D02*
X686911Y513373D01*
G01X686847Y513404D02*
X686881Y513391D01*
G01X686810Y513412D02*
X686847Y513404D01*
G01X686772Y513414D02*
X686810Y513412D01*
G01X688933Y513302D02*
X688937Y513274D01*
G01X688922Y513328D02*
X688933Y513302D01*
G01X688904Y513352D02*
X688922Y513328D01*
G01X688880Y513373D02*
X688904Y513352D01*
G01X688849Y513391D02*
X688880Y513373D01*
G01X688816Y513404D02*
X688849Y513391D01*
G01X688779Y513412D02*
X688816Y513404D01*
G01X688741Y513414D02*
X688779Y513412D01*
G01X690902Y513302D02*
X690906Y513274D01*
G01X690891Y513328D02*
X690902Y513302D01*
G01X690873Y513352D02*
X690891Y513328D01*
G01X690848Y513373D02*
X690873Y513352D01*
G01X690818Y513391D02*
X690848Y513373D01*
G01X690784Y513404D02*
X690818Y513391D01*
G01X690747Y513412D02*
X690784Y513404D01*
G01X690709Y513414D02*
X690747Y513412D01*
G01X692870Y513302D02*
X692874Y513274D01*
G01X692859Y513328D02*
X692870Y513302D01*
G01X692841Y513352D02*
X692859Y513328D01*
G01X692817Y513373D02*
X692841Y513352D01*
G01X692786Y513391D02*
X692817Y513373D01*
G01X692753Y513404D02*
X692786Y513391D01*
G01X692716Y513412D02*
X692753Y513404D01*
G01X692678Y513414D02*
X692716Y513412D01*
G01X694839Y513302D02*
X694843Y513274D01*
G01X694828Y513328D02*
X694839Y513302D01*
G01X694810Y513352D02*
X694828Y513328D01*
G01X694785Y513373D02*
X694810Y513352D01*
G01X694755Y513391D02*
X694785Y513373D01*
G01X694721Y513404D02*
X694755Y513391D01*
G01X694684Y513412D02*
X694721Y513404D01*
G01X694646Y513414D02*
X694684Y513412D01*
G01X696808Y513302D02*
X696811Y513274D01*
G01X696796Y513328D02*
X696808Y513302D01*
G01X696778Y513352D02*
X696796Y513328D01*
G01X696754Y513373D02*
X696778Y513352D01*
G01X696723Y513391D02*
X696754Y513373D01*
G01X696690Y513404D02*
X696723Y513391D01*
G01X696653Y513412D02*
X696690Y513404D01*
G01X696615Y513414D02*
X696653Y513412D01*
G01X698776Y513302D02*
X698780Y513274D01*
G01X698765Y513328D02*
X698776Y513302D01*
G01X698747Y513352D02*
X698765Y513328D01*
G01X698722Y513373D02*
X698747Y513352D01*
G01X698692Y513391D02*
X698722Y513373D01*
G01X698658Y513404D02*
X698692Y513391D01*
G01X698621Y513412D02*
X698658Y513404D01*
G01X698583Y513414D02*
X698621Y513412D01*
G01X700745Y513302D02*
X700748Y513274D01*
G01X700733Y513328D02*
X700745Y513302D01*
G01X700715Y513352D02*
X700733Y513328D01*
G01X700691Y513373D02*
X700715Y513352D01*
G01X700660Y513391D02*
X700691Y513373D01*
G01X700627Y513404D02*
X700660Y513391D01*
G01X700590Y513412D02*
X700627Y513404D01*
G01X700552Y513414D02*
X700590Y513412D01*
G01X702713Y513302D02*
X702717Y513274D01*
G01X702702Y513328D02*
X702713Y513302D01*
G01X702684Y513352D02*
X702702Y513328D01*
G01X702659Y513373D02*
X702684Y513352D01*
G01X702629Y513391D02*
X702659Y513373D01*
G01X702595Y513404D02*
X702629Y513391D01*
G01X702558Y513412D02*
X702595Y513404D01*
G01X702520Y513414D02*
X702558Y513412D01*
G01X704682Y513302D02*
X704685Y513274D01*
G01X704670Y513328D02*
X704682Y513302D01*
G01X704652Y513352D02*
X704670Y513328D01*
G01X704628Y513373D02*
X704652Y513352D01*
G01X704597Y513391D02*
X704628Y513373D01*
G01X704564Y513404D02*
X704597Y513391D01*
G01X704527Y513412D02*
X704564Y513404D01*
G01X704489Y513414D02*
X704527Y513412D01*
G01X706650Y513302D02*
X706654Y513274D01*
G01X706639Y513328D02*
X706650Y513302D01*
G01X706621Y513352D02*
X706639Y513328D01*
G01X706596Y513373D02*
X706621Y513352D01*
G01X706566Y513391D02*
X706596Y513373D01*
G01X706532Y513404D02*
X706566Y513391D01*
G01X706495Y513412D02*
X706532Y513404D01*
G01X706457Y513414D02*
X706495Y513412D01*
G01X708619Y513302D02*
X708622Y513274D01*
G01X708607Y513328D02*
X708619Y513302D01*
G01X708589Y513352D02*
X708607Y513328D01*
G01X708565Y513373D02*
X708589Y513352D01*
G01X708534Y513391D02*
X708565Y513373D01*
G01X708501Y513404D02*
X708534Y513391D01*
G01X708464Y513412D02*
X708501Y513404D01*
G01X708426Y513414D02*
X708464Y513412D01*
G01X710587Y513302D02*
X710591Y513274D01*
G01X710576Y513328D02*
X710587Y513302D01*
G01X710558Y513352D02*
X710576Y513328D01*
G01X710533Y513373D02*
X710558Y513352D01*
G01X710503Y513391D02*
X710533Y513373D01*
G01X710469Y513404D02*
X710503Y513391D01*
G01X710432Y513412D02*
X710469Y513404D01*
G01X710394Y513414D02*
X710432Y513412D01*
G01X712556Y513302D02*
X712559Y513274D01*
G01X712544Y513328D02*
X712556Y513302D01*
G01X712526Y513352D02*
X712544Y513328D01*
G01X712502Y513373D02*
X712526Y513352D01*
G01X712472Y513391D02*
X712502Y513373D01*
G01X712438Y513404D02*
X712472Y513391D01*
G01X712401Y513412D02*
X712438Y513404D01*
G01X712363Y513414D02*
X712401Y513412D01*
G01X714524Y513302D02*
X714528Y513274D01*
G01X714513Y513328D02*
X714524Y513302D01*
G01X714495Y513352D02*
X714513Y513328D01*
G01X714470Y513373D02*
X714495Y513352D01*
G01X714440Y513391D02*
X714470Y513373D01*
G01X714406Y513404D02*
X714440Y513391D01*
G01X714369Y513412D02*
X714406Y513404D01*
G01X714331Y513414D02*
X714369Y513412D01*
G01X671213Y513069D02*
X671221Y512993D01*
G01X671194Y513132D02*
X671213Y513069D01*
G01X671167Y513183D02*
X671194Y513132D01*
G01X671135Y513222D02*
X671167Y513183D01*
G01X671099Y513249D02*
X671135Y513222D01*
G01X671062Y513265D02*
X671099Y513249D01*
G01X671024Y513270D02*
X671062Y513265D01*
G01X673182Y513069D02*
X673189Y512993D01*
G01X673163Y513132D02*
X673182Y513069D01*
G01X673136Y513183D02*
X673163Y513132D01*
G01X673103Y513222D02*
X673136Y513183D01*
G01X673068Y513249D02*
X673103Y513222D01*
G01X673031Y513265D02*
X673068Y513249D01*
G01X672992Y513270D02*
X673031Y513265D01*
G01X675150Y513069D02*
X675158Y512993D01*
G01X675131Y513132D02*
X675150Y513069D01*
G01X675104Y513183D02*
X675131Y513132D01*
G01X675072Y513222D02*
X675104Y513183D01*
G01X675036Y513249D02*
X675072Y513222D01*
G01X674999Y513265D02*
X675036Y513249D01*
G01X674961Y513270D02*
X674999Y513265D01*
G01X677119Y513069D02*
X677126Y512993D01*
G01X677100Y513132D02*
X677119Y513069D01*
G01X677073Y513183D02*
X677100Y513132D01*
G01X677040Y513222D02*
X677073Y513183D01*
G01X677005Y513249D02*
X677040Y513222D01*
G01X676968Y513265D02*
X677005Y513249D01*
G01X676929Y513270D02*
X676968Y513265D01*
G01X679087Y513069D02*
X679095Y512993D01*
G01X679068Y513132D02*
X679087Y513069D01*
G01X679041Y513183D02*
X679068Y513132D01*
G01X679009Y513222D02*
X679041Y513183D01*
G01X678973Y513249D02*
X679009Y513222D01*
G01X678936Y513265D02*
X678973Y513249D01*
G01X678898Y513270D02*
X678936Y513265D01*
G01X681056Y513069D02*
X681063Y512993D01*
G01X681037Y513132D02*
X681056Y513069D01*
G01X681010Y513183D02*
X681037Y513132D01*
G01X680977Y513222D02*
X681010Y513183D01*
G01X680942Y513249D02*
X680977Y513222D01*
G01X680905Y513265D02*
X680942Y513249D01*
G01X680867Y513270D02*
X680905Y513265D01*
G01X683024Y513069D02*
X683032Y512993D01*
G01X683005Y513132D02*
X683024Y513069D01*
G01X682978Y513183D02*
X683005Y513132D01*
G01X682946Y513222D02*
X682978Y513183D01*
G01X682910Y513249D02*
X682946Y513222D01*
G01X682873Y513265D02*
X682910Y513249D01*
G01X682835Y513270D02*
X682873Y513265D01*
G01X684993Y513069D02*
X685000Y512993D01*
G01X684974Y513132D02*
X684993Y513069D01*
G01X684947Y513183D02*
X684974Y513132D01*
G01X684914Y513222D02*
X684947Y513183D01*
G01X684879Y513249D02*
X684914Y513222D01*
G01X684842Y513265D02*
X684879Y513249D01*
G01X684804Y513270D02*
X684842Y513265D01*
G01X686961Y513069D02*
X686969Y512993D01*
G01X686942Y513132D02*
X686961Y513069D01*
G01X686915Y513183D02*
X686942Y513132D01*
G01X686883Y513222D02*
X686915Y513183D01*
G01X686847Y513249D02*
X686883Y513222D01*
G01X686810Y513265D02*
X686847Y513249D01*
G01X686772Y513270D02*
X686810Y513265D01*
G01X688930Y513069D02*
X688937Y512993D01*
G01X688911Y513132D02*
X688930Y513069D01*
G01X688884Y513183D02*
X688911Y513132D01*
G01X688851Y513222D02*
X688884Y513183D01*
G01X688816Y513249D02*
X688851Y513222D01*
G01X688779Y513265D02*
X688816Y513249D01*
G01X688741Y513270D02*
X688779Y513265D01*
G01X690898Y513069D02*
X690906Y512993D01*
G01X690879Y513132D02*
X690898Y513069D01*
G01X690852Y513183D02*
X690879Y513132D01*
G01X690820Y513222D02*
X690852Y513183D01*
G01X690784Y513249D02*
X690820Y513222D01*
G01X690747Y513265D02*
X690784Y513249D01*
G01X690709Y513270D02*
X690747Y513265D01*
G01X692867Y513069D02*
X692874Y512993D01*
G01X692848Y513132D02*
X692867Y513069D01*
G01X692821Y513183D02*
X692848Y513132D01*
G01X692788Y513222D02*
X692821Y513183D01*
G01X692753Y513249D02*
X692788Y513222D01*
G01X692716Y513265D02*
X692753Y513249D01*
G01X692678Y513270D02*
X692716Y513265D01*
G01X694835Y513069D02*
X694843Y512993D01*
G01X694816Y513132D02*
X694835Y513069D01*
G01X694789Y513183D02*
X694816Y513132D01*
G01X694757Y513222D02*
X694789Y513183D01*
G01X694721Y513249D02*
X694757Y513222D01*
G01X694684Y513265D02*
X694721Y513249D01*
G01X694646Y513270D02*
X694684Y513265D01*
G01X696804Y513069D02*
X696811Y512993D01*
G01X696785Y513132D02*
X696804Y513069D01*
G01X696758Y513183D02*
X696785Y513132D01*
G01X696725Y513222D02*
X696758Y513183D01*
G01X696690Y513249D02*
X696725Y513222D01*
G01X696653Y513265D02*
X696690Y513249D01*
G01X696615Y513270D02*
X696653Y513265D01*
G01X698772Y513069D02*
X698780Y512993D01*
G01X698753Y513132D02*
X698772Y513069D01*
G01X698726Y513183D02*
X698753Y513132D01*
G01X698694Y513222D02*
X698726Y513183D01*
G01X698658Y513249D02*
X698694Y513222D01*
G01X698621Y513265D02*
X698658Y513249D01*
G01X698583Y513270D02*
X698621Y513265D01*
G01X700741Y513069D02*
X700748Y512993D01*
G01X700722Y513132D02*
X700741Y513069D01*
G01X700695Y513183D02*
X700722Y513132D01*
G01X700662Y513222D02*
X700695Y513183D01*
G01X700627Y513249D02*
X700662Y513222D01*
G01X700590Y513265D02*
X700627Y513249D01*
G01X700552Y513270D02*
X700590Y513265D01*
G01X670671D02*
X670709Y513270D01*
G01X670634Y513249D02*
X670671Y513265D01*
G01X670598Y513222D02*
X670634Y513249D01*
G01X670566Y513183D02*
X670598Y513222D01*
G01X670539Y513132D02*
X670566Y513183D01*
G01X670520Y513069D02*
X670539Y513132D01*
G01X670512Y512993D02*
X670520Y513069D01*
G01X672639Y513265D02*
X672678Y513270D01*
G01X672602Y513249D02*
X672639Y513265D01*
G01X672567Y513222D02*
X672602Y513249D01*
G01X672534Y513183D02*
X672567Y513222D01*
G01X672507Y513132D02*
X672534Y513183D01*
G01X672488Y513069D02*
X672507Y513132D01*
G01X672481Y512993D02*
X672488Y513069D01*
G01X674608Y513265D02*
X674646Y513270D01*
G01X674571Y513249D02*
X674608Y513265D01*
G01X674535Y513222D02*
X674571Y513249D01*
G01X674503Y513183D02*
X674535Y513222D01*
G01X674476Y513132D02*
X674503Y513183D01*
G01X674457Y513069D02*
X674476Y513132D01*
G01X674449Y512993D02*
X674457Y513069D01*
G01X676576Y513265D02*
X676615Y513270D01*
G01X676539Y513249D02*
X676576Y513265D01*
G01X676504Y513222D02*
X676539Y513249D01*
G01X676471Y513183D02*
X676504Y513222D01*
G01X676444Y513132D02*
X676471Y513183D01*
G01X676425Y513069D02*
X676444Y513132D01*
G01X676418Y512993D02*
X676425Y513069D01*
G01X678545Y513265D02*
X678583Y513270D01*
G01X678508Y513249D02*
X678545Y513265D01*
G01X678472Y513222D02*
X678508Y513249D01*
G01X678440Y513183D02*
X678472Y513222D01*
G01X678413Y513132D02*
X678440Y513183D01*
G01X678394Y513069D02*
X678413Y513132D01*
G01X678386Y512993D02*
X678394Y513069D01*
G01X680513Y513265D02*
X680552Y513270D01*
G01X680476Y513249D02*
X680513Y513265D01*
G01X680441Y513222D02*
X680476Y513249D01*
G01X680408Y513183D02*
X680441Y513222D01*
G01X680381Y513132D02*
X680408Y513183D01*
G01X680362Y513069D02*
X680381Y513132D01*
G01X680355Y512993D02*
X680362Y513069D01*
G01X682482Y513265D02*
X682520Y513270D01*
G01X682445Y513249D02*
X682482Y513265D01*
G01X682409Y513222D02*
X682445Y513249D01*
G01X682377Y513183D02*
X682409Y513222D01*
G01X682350Y513132D02*
X682377Y513183D01*
G01X682331Y513069D02*
X682350Y513132D01*
G01X682323Y512993D02*
X682331Y513069D01*
G01X670670Y513412D02*
X670709Y513414D01*
G01X670633Y513404D02*
X670670Y513412D01*
G01X670600Y513391D02*
X670633Y513404D01*
G01X670570Y513373D02*
X670600Y513391D01*
G01X670545Y513352D02*
X670570Y513373D01*
G01X670527Y513328D02*
X670545Y513352D01*
G01X670516Y513302D02*
X670527Y513328D01*
G01X670512Y513274D02*
X670516Y513302D01*
G01X672639Y513412D02*
X672678Y513414D01*
G01X672602Y513404D02*
X672639Y513412D01*
G01X672568Y513391D02*
X672602Y513404D01*
G01X672538Y513373D02*
X672568Y513391D01*
G01X672514Y513352D02*
X672538Y513373D01*
G01X672496Y513328D02*
X672514Y513352D01*
G01X672484Y513302D02*
X672496Y513328D01*
G01X672481Y513274D02*
X672484Y513302D01*
G01X674607Y513412D02*
X674646Y513414D01*
G01X674570Y513404D02*
X674607Y513412D01*
G01X674537Y513391D02*
X674570Y513404D01*
G01X674507Y513373D02*
X674537Y513391D01*
G01X674482Y513352D02*
X674507Y513373D01*
G01X674464Y513328D02*
X674482Y513352D01*
G01X674453Y513302D02*
X674464Y513328D01*
G01X674449Y513274D02*
X674453Y513302D01*
G01X676576Y513412D02*
X676615Y513414D01*
G01X676539Y513404D02*
X676576Y513412D01*
G01X676505Y513391D02*
X676539Y513404D01*
G01X676475Y513373D02*
X676505Y513391D01*
G01X676451Y513352D02*
X676475Y513373D01*
G01X676433Y513328D02*
X676451Y513352D01*
G01X676421Y513302D02*
X676433Y513328D01*
G01X676418Y513274D02*
X676421Y513302D01*
G01X678544Y513412D02*
X678583Y513414D01*
G01X678507Y513404D02*
X678544Y513412D01*
G01X678474Y513391D02*
X678507Y513404D01*
G01X678444Y513373D02*
X678474Y513391D01*
G01X678419Y513352D02*
X678444Y513373D01*
G01X678401Y513328D02*
X678419Y513352D01*
G01X678390Y513302D02*
X678401Y513328D01*
G01X678386Y513274D02*
X678390Y513302D01*
G01X680513Y513412D02*
X680552Y513414D01*
G01X680476Y513404D02*
X680513Y513412D01*
G01X680442Y513391D02*
X680476Y513404D01*
G01X680412Y513373D02*
X680442Y513391D01*
G01X680388Y513352D02*
X680412Y513373D01*
G01X680370Y513328D02*
X680388Y513352D01*
G01X680358Y513302D02*
X680370Y513328D01*
G01X680355Y513274D02*
X680358Y513302D01*
G01X682481Y513412D02*
X682520Y513414D01*
G01X682444Y513404D02*
X682481Y513412D01*
G01X682411Y513391D02*
X682444Y513404D01*
G01X682381Y513373D02*
X682411Y513391D01*
G01X682356Y513352D02*
X682381Y513373D01*
G01X682338Y513328D02*
X682356Y513352D01*
G01X682327Y513302D02*
X682338Y513328D01*
G01X682323Y513274D02*
X682327Y513302D01*
G01X684450Y513412D02*
X684489Y513414D01*
G01X684413Y513404D02*
X684450Y513412D01*
G01X684379Y513391D02*
X684413Y513404D01*
G01X684349Y513373D02*
X684379Y513391D01*
G01X684325Y513352D02*
X684349Y513373D01*
G01X684307Y513328D02*
X684325Y513352D01*
G01X684295Y513302D02*
X684307Y513328D01*
G01X684292Y513274D02*
X684295Y513302D01*
G01X686418Y513412D02*
X686457Y513414D01*
G01X686381Y513404D02*
X686418Y513412D01*
G01X686348Y513391D02*
X686381Y513404D01*
G01X686318Y513373D02*
X686348Y513391D01*
G01X686293Y513352D02*
X686318Y513373D01*
G01X686275Y513328D02*
X686293Y513352D01*
G01X686264Y513302D02*
X686275Y513328D01*
G01X686260Y513274D02*
X686264Y513302D01*
G01X688387Y513412D02*
X688426Y513414D01*
G01X688350Y513404D02*
X688387Y513412D01*
G01X688316Y513391D02*
X688350Y513404D01*
G01X688286Y513373D02*
X688316Y513391D01*
G01X688262Y513352D02*
X688286Y513373D01*
G01X688244Y513328D02*
X688262Y513352D01*
G01X688232Y513302D02*
X688244Y513328D01*
G01X688229Y513274D02*
X688232Y513302D01*
G01X702709Y513069D02*
X702717Y512993D01*
G01X702690Y513132D02*
X702709Y513069D01*
G01X702663Y513183D02*
X702690Y513132D01*
G01X702631Y513222D02*
X702663Y513183D01*
G01X702595Y513249D02*
X702631Y513222D01*
G01X702558Y513265D02*
X702595Y513249D01*
G01X702520Y513270D02*
X702558Y513265D01*
G01X704678Y513069D02*
X704685Y512993D01*
G01X704659Y513132D02*
X704678Y513069D01*
G01X704632Y513183D02*
X704659Y513132D01*
G01X704599Y513222D02*
X704632Y513183D01*
G01X704564Y513249D02*
X704599Y513222D01*
G01X704527Y513265D02*
X704564Y513249D01*
G01X704489Y513270D02*
X704527Y513265D01*
G01X706646Y513069D02*
X706654Y512993D01*
G01X706627Y513132D02*
X706646Y513069D01*
G01X706600Y513183D02*
X706627Y513132D01*
G01X706568Y513222D02*
X706600Y513183D01*
G01X706532Y513249D02*
X706568Y513222D01*
G01X706495Y513265D02*
X706532Y513249D01*
G01X706457Y513270D02*
X706495Y513265D01*
G01X708615Y513069D02*
X708622Y512993D01*
G01X708596Y513132D02*
X708615Y513069D01*
G01X708569Y513183D02*
X708596Y513132D01*
G01X708536Y513222D02*
X708569Y513183D01*
G01X708501Y513249D02*
X708536Y513222D01*
G01X708464Y513265D02*
X708501Y513249D01*
G01X708426Y513270D02*
X708464Y513265D01*
G01X710583Y513069D02*
X710591Y512993D01*
G01X710564Y513132D02*
X710583Y513069D01*
G01X710537Y513183D02*
X710564Y513132D01*
G01X710505Y513222D02*
X710537Y513183D01*
G01X710469Y513249D02*
X710505Y513222D01*
G01X710432Y513265D02*
X710469Y513249D01*
G01X710394Y513270D02*
X710432Y513265D01*
G01X712552Y513069D02*
X712559Y512993D01*
G01X712533Y513132D02*
X712552Y513069D01*
G01X712506Y513183D02*
X712533Y513132D01*
G01X712473Y513222D02*
X712506Y513183D01*
G01X712438Y513249D02*
X712473Y513222D01*
G01X712401Y513265D02*
X712438Y513249D01*
G01X712363Y513270D02*
X712401Y513265D01*
G01X714520Y513069D02*
X714528Y512993D01*
G01X714501Y513132D02*
X714520Y513069D01*
G01X714474Y513183D02*
X714501Y513132D01*
G01X714442Y513222D02*
X714474Y513183D01*
G01X714406Y513249D02*
X714442Y513222D01*
G01X714369Y513265D02*
X714406Y513249D01*
G01X714331Y513270D02*
X714369Y513265D01*
G01X684450D02*
X684489Y513270D01*
G01X684413Y513249D02*
X684450Y513265D01*
G01X684378Y513222D02*
X684413Y513249D01*
G01X684345Y513183D02*
X684378Y513222D01*
G01X684318Y513132D02*
X684345Y513183D01*
G01X684299Y513069D02*
X684318Y513132D01*
G01X684292Y512993D02*
X684299Y513069D01*
G01X686419Y513265D02*
X686457Y513270D01*
G01X686382Y513249D02*
X686419Y513265D01*
G01X686346Y513222D02*
X686382Y513249D01*
G01X686314Y513183D02*
X686346Y513222D01*
G01X686287Y513132D02*
X686314Y513183D01*
G01X686268Y513069D02*
X686287Y513132D01*
G01X686260Y512993D02*
X686268Y513069D01*
G01X688387Y513265D02*
X688426Y513270D01*
G01X688350Y513249D02*
X688387Y513265D01*
G01X688315Y513222D02*
X688350Y513249D01*
G01X688282Y513183D02*
X688315Y513222D01*
G01X688255Y513132D02*
X688282Y513183D01*
G01X688236Y513069D02*
X688255Y513132D01*
G01X688229Y512993D02*
X688236Y513069D01*
G01X690356Y513265D02*
X690394Y513270D01*
G01X690319Y513249D02*
X690356Y513265D01*
G01X690283Y513222D02*
X690319Y513249D01*
G01X690251Y513183D02*
X690283Y513222D01*
G01X690224Y513132D02*
X690251Y513183D01*
G01X690205Y513069D02*
X690224Y513132D01*
G01X690197Y512993D02*
X690205Y513069D01*
G01X692324Y513265D02*
X692363Y513270D01*
G01X692287Y513249D02*
X692324Y513265D01*
G01X692252Y513222D02*
X692287Y513249D01*
G01X692219Y513183D02*
X692252Y513222D01*
G01X692192Y513132D02*
X692219Y513183D01*
G01X692173Y513069D02*
X692192Y513132D01*
G01X692166Y512993D02*
X692173Y513069D01*
G01X694293Y513265D02*
X694331Y513270D01*
G01X694256Y513249D02*
X694293Y513265D01*
G01X694220Y513222D02*
X694256Y513249D01*
G01X694188Y513183D02*
X694220Y513222D01*
G01X694161Y513132D02*
X694188Y513183D01*
G01X694142Y513069D02*
X694161Y513132D01*
G01X694134Y512993D02*
X694142Y513069D01*
G01X696261Y513265D02*
X696300Y513270D01*
G01X696224Y513249D02*
X696261Y513265D01*
G01X696189Y513222D02*
X696224Y513249D01*
G01X696156Y513183D02*
X696189Y513222D01*
G01X696129Y513132D02*
X696156Y513183D01*
G01X696110Y513069D02*
X696129Y513132D01*
G01X696103Y512993D02*
X696110Y513069D01*
G01X698230Y513265D02*
X698268Y513270D01*
G01X698193Y513249D02*
X698230Y513265D01*
G01X698158Y513222D02*
X698193Y513249D01*
G01X698125Y513183D02*
X698158Y513222D01*
G01X698098Y513132D02*
X698125Y513183D01*
G01X698079Y513069D02*
X698098Y513132D01*
G01X698071Y512993D02*
X698079Y513069D01*
G01X700198Y513265D02*
X700237Y513270D01*
G01X700161Y513249D02*
X700198Y513265D01*
G01X700126Y513222D02*
X700161Y513249D01*
G01X700093Y513183D02*
X700126Y513222D01*
G01X700066Y513132D02*
X700093Y513183D01*
G01X700047Y513069D02*
X700066Y513132D01*
G01X700040Y512993D02*
X700047Y513069D01*
G01X702167Y513265D02*
X702205Y513270D01*
G01X702130Y513249D02*
X702167Y513265D01*
G01X702095Y513222D02*
X702130Y513249D01*
G01X702062Y513183D02*
X702095Y513222D01*
G01X702035Y513132D02*
X702062Y513183D01*
G01X702016Y513069D02*
X702035Y513132D01*
G01X702008Y512993D02*
X702016Y513069D01*
G01X704135Y513265D02*
X704174Y513270D01*
G01X704098Y513249D02*
X704135Y513265D01*
G01X704063Y513222D02*
X704098Y513249D01*
G01X704030Y513183D02*
X704063Y513222D01*
G01X704003Y513132D02*
X704030Y513183D01*
G01X703984Y513069D02*
X704003Y513132D01*
G01X703977Y512993D02*
X703984Y513069D01*
G01X706104Y513265D02*
X706142Y513270D01*
G01X706067Y513249D02*
X706104Y513265D01*
G01X706032Y513222D02*
X706067Y513249D01*
G01X705999Y513183D02*
X706032Y513222D01*
G01X705972Y513132D02*
X705999Y513183D01*
G01X705953Y513069D02*
X705972Y513132D01*
G01X705945Y512993D02*
X705953Y513069D01*
G01X708072Y513265D02*
X708111Y513270D01*
G01X708035Y513249D02*
X708072Y513265D01*
G01X708000Y513222D02*
X708035Y513249D01*
G01X707967Y513183D02*
X708000Y513222D01*
G01X707940Y513132D02*
X707967Y513183D01*
G01X707921Y513069D02*
X707940Y513132D01*
G01X707914Y512993D02*
X707921Y513069D01*
G01X710041Y513265D02*
X710079Y513270D01*
G01X710004Y513249D02*
X710041Y513265D01*
G01X709969Y513222D02*
X710004Y513249D01*
G01X709936Y513183D02*
X709969Y513222D01*
G01X709909Y513132D02*
X709936Y513183D01*
G01X709890Y513069D02*
X709909Y513132D01*
G01X709882Y512993D02*
X709890Y513069D01*
G01X712009Y513265D02*
X712048Y513270D01*
G01X711972Y513249D02*
X712009Y513265D01*
G01X711937Y513222D02*
X711972Y513249D01*
G01X711904Y513183D02*
X711937Y513222D01*
G01X711877Y513132D02*
X711904Y513183D01*
G01X711858Y513069D02*
X711877Y513132D01*
G01X711851Y512993D02*
X711858Y513069D01*
G01X713978Y513265D02*
X714016Y513270D01*
G01X713941Y513249D02*
X713978Y513265D01*
G01X713906Y513222D02*
X713941Y513249D01*
G01X713873Y513183D02*
X713906Y513222D01*
G01X713846Y513132D02*
X713873Y513183D01*
G01X713827Y513069D02*
X713846Y513132D01*
G01X713819Y512993D02*
X713827Y513069D01*
G01X690355Y513412D02*
X690394Y513414D01*
G01X690318Y513404D02*
X690355Y513412D01*
G01X690285Y513391D02*
X690318Y513404D01*
G01X690255Y513373D02*
X690285Y513391D01*
G01X690230Y513352D02*
X690255Y513373D01*
G01X690212Y513328D02*
X690230Y513352D01*
G01X690201Y513302D02*
X690212Y513328D01*
G01X690197Y513274D02*
X690201Y513302D01*
G01X692324Y513412D02*
X692363Y513414D01*
G01X692287Y513404D02*
X692324Y513412D01*
G01X692253Y513391D02*
X692287Y513404D01*
G01X692223Y513373D02*
X692253Y513391D01*
G01X692199Y513352D02*
X692223Y513373D01*
G01X692181Y513328D02*
X692199Y513352D01*
G01X692169Y513302D02*
X692181Y513328D01*
G01X692166Y513274D02*
X692169Y513302D01*
G01X694292Y513412D02*
X694331Y513414D01*
G01X694255Y513404D02*
X694292Y513412D01*
G01X694222Y513391D02*
X694255Y513404D01*
G01X694192Y513373D02*
X694222Y513391D01*
G01X694167Y513352D02*
X694192Y513373D01*
G01X694149Y513328D02*
X694167Y513352D01*
G01X694138Y513302D02*
X694149Y513328D01*
G01X694134Y513274D02*
X694138Y513302D01*
G01X696261Y513412D02*
X696300Y513414D01*
G01X696224Y513404D02*
X696261Y513412D01*
G01X696190Y513391D02*
X696224Y513404D01*
G01X696160Y513373D02*
X696190Y513391D01*
G01X696136Y513352D02*
X696160Y513373D01*
G01X696118Y513328D02*
X696136Y513352D01*
G01X696106Y513302D02*
X696118Y513328D01*
G01X696103Y513274D02*
X696106Y513302D01*
G01X698229Y513412D02*
X698268Y513414D01*
G01X698192Y513404D02*
X698229Y513412D01*
G01X698159Y513391D02*
X698192Y513404D01*
G01X698129Y513373D02*
X698159Y513391D01*
G01X698104Y513352D02*
X698129Y513373D01*
G01X698086Y513328D02*
X698104Y513352D01*
G01X698075Y513302D02*
X698086Y513328D01*
G01X698071Y513274D02*
X698075Y513302D01*
G01X700198Y513412D02*
X700237Y513414D01*
G01X700161Y513404D02*
X700198Y513412D01*
G01X700127Y513391D02*
X700161Y513404D01*
G01X700097Y513373D02*
X700127Y513391D01*
G01X700073Y513352D02*
X700097Y513373D01*
G01X700055Y513328D02*
X700073Y513352D01*
G01X700043Y513302D02*
X700055Y513328D01*
G01X700040Y513274D02*
X700043Y513302D01*
G01X702166Y513412D02*
X702205Y513414D01*
G01X702129Y513404D02*
X702166Y513412D01*
G01X702096Y513391D02*
X702129Y513404D01*
G01X702066Y513373D02*
X702096Y513391D01*
G01X702041Y513352D02*
X702066Y513373D01*
G01X702023Y513328D02*
X702041Y513352D01*
G01X702012Y513302D02*
X702023Y513328D01*
G01X702008Y513274D02*
X702012Y513302D01*
G01X704135Y513412D02*
X704174Y513414D01*
G01X704098Y513404D02*
X704135Y513412D01*
G01X704064Y513391D02*
X704098Y513404D01*
G01X704034Y513373D02*
X704064Y513391D01*
G01X704010Y513352D02*
X704034Y513373D01*
G01X703992Y513328D02*
X704010Y513352D01*
G01X703980Y513302D02*
X703992Y513328D01*
G01X703977Y513274D02*
X703980Y513302D01*
G01X706103Y513412D02*
X706142Y513414D01*
G01X706066Y513404D02*
X706103Y513412D01*
G01X706033Y513391D02*
X706066Y513404D01*
G01X706003Y513373D02*
X706033Y513391D01*
G01X705978Y513352D02*
X706003Y513373D01*
G01X705960Y513328D02*
X705978Y513352D01*
G01X705949Y513302D02*
X705960Y513328D01*
G01X705945Y513274D02*
X705949Y513302D01*
G01X708072Y513412D02*
X708111Y513414D01*
G01X708035Y513404D02*
X708072Y513412D01*
G01X708001Y513391D02*
X708035Y513404D01*
G01X707971Y513373D02*
X708001Y513391D01*
G01X707947Y513352D02*
X707971Y513373D01*
G01X707929Y513328D02*
X707947Y513352D01*
G01X707917Y513302D02*
X707929Y513328D01*
G01X707914Y513274D02*
X707917Y513302D01*
G01X710040Y513412D02*
X710079Y513414D01*
G01X710003Y513404D02*
X710040Y513412D01*
G01X709970Y513391D02*
X710003Y513404D01*
G01X709940Y513373D02*
X709970Y513391D01*
G01X709915Y513352D02*
X709940Y513373D01*
G01X709897Y513328D02*
X709915Y513352D01*
G01X709886Y513302D02*
X709897Y513328D01*
G01X709882Y513274D02*
X709886Y513302D01*
G01X712009Y513412D02*
X712048Y513414D01*
G01X711972Y513404D02*
X712009Y513412D01*
G01X711938Y513391D02*
X711972Y513404D01*
G01X711908Y513373D02*
X711938Y513391D01*
G01X711884Y513352D02*
X711908Y513373D01*
G01X711866Y513328D02*
X711884Y513352D01*
G01X711855Y513302D02*
X711866Y513328D01*
G01X711851Y513274D02*
X711855Y513302D01*
G01X713977Y513412D02*
X714016Y513414D01*
G01X713940Y513404D02*
X713977Y513412D01*
G01X713907Y513391D02*
X713940Y513404D01*
G01X713877Y513373D02*
X713907Y513391D01*
G01X713852Y513352D02*
X713877Y513373D01*
G01X713834Y513328D02*
X713852Y513352D01*
G01X713823Y513302D02*
X713834Y513328D01*
G01X713819Y513274D02*
X713823Y513302D01*
G01X714961Y531183D02*
G03X714764Y530986I0J-197D01*
G01X712992Y531183D02*
G03X712796Y530986I0J-196D01*
G01X713583D02*
G03X713386Y531183I-197J0D01*
G01X711024D02*
G03X710827Y530986I0J-197D01*
G01X711615D02*
G03X711418Y531183I-197J0D01*
G01X709055D02*
G03X708859Y530986I0J-196D01*
G01X709646D02*
G03X709449Y531183I-197J0D01*
G01X707087D02*
G03X706890Y530986I0J-197D01*
G01X707678D02*
G03X707481Y531183I-197J0D01*
G01X705118D02*
G03X704922Y530986I0J-196D01*
G01X705709D02*
G03X705512Y531183I-197J0D01*
G01X714370Y499213D02*
G03X714567Y499410I0J197D01*
G01X713780D02*
G03X713977Y499213I197J0D01*
G01X712402D02*
G03X712599Y499410I0J197D01*
G01X711811D02*
G03X712008Y499213I197J0D01*
G01X710433D02*
G03X710630Y499410I0J197D01*
G01X709843D02*
G03X710040Y499213I197J0D01*
G01X708465D02*
G03X708662Y499410I0J197D01*
G01X707874D02*
G03X708071Y499213I197J0D01*
G01X706496D02*
G03X706693Y499410I0J197D01*
G01X705906D02*
G03X706103Y499213I197J0D01*
G01X703150Y531183D02*
G03X702953Y530986I0J-197D01*
G01X703741D02*
G03X703544Y531183I-197J0D01*
G01X701181D02*
G03X700985Y530986I0J-196D01*
G01X701772D02*
G03X701575Y531183I-197J0D01*
G01X699213D02*
G03X699016Y530986I0J-197D01*
G01X699804D02*
G03X699607Y531183I-197J0D01*
G01X697244D02*
G03X697048Y530986I0J-196D01*
G01X697835D02*
G03X697638Y531183I-197J0D01*
G01X695276D02*
G03X695079Y530986I0J-197D01*
G01X695867D02*
G03X695670Y531183I-197J0D01*
G01X693307D02*
G03X693111Y530986I0J-196D01*
G01X693898D02*
G03X693701Y531183I-197J0D01*
G01X691339D02*
G03X691142Y530986I0J-197D01*
G01X691929D02*
G03X691733Y531183I-197J0D01*
G01X689370D02*
G03X689174Y530986I0J-196D01*
G01X689961D02*
G03X689764Y531183I-197J0D01*
G01X687402D02*
G03X687205Y530986I0J-197D01*
G01X687992D02*
G03X687796Y531183I-197J0D01*
G01X685433D02*
G03X685237Y530986I0J-196D01*
G01X686024D02*
G03X685827Y531183I-197J0D01*
G01X684055Y530986D02*
G03X683859Y531183I-197J0D01*
G01X688662Y523898D02*
G03X687874Y524685I-787J0D01*
G01X683465Y531183D02*
G03X683268Y530986I0J-197D01*
G01X681496Y531183D02*
G03X681300Y530986I0J-196D01*
G01X682087D02*
G03X681890Y531183I-197J0D01*
G01X679528D02*
G03X679331Y530986I0J-197D01*
G01X680118D02*
G03X679922Y531183I-197J0D01*
G01X677559D02*
G03X677363Y530986I0J-196D01*
G01X678150D02*
G03X677953Y531183I-197J0D01*
G01X675591D02*
G03X675394Y530986I0J-197D01*
G01X676181D02*
G03X675985Y531183I-197J0D01*
G01X673622D02*
G03X673426Y530986I0J-196D01*
G01X674213D02*
G03X674016Y531183I-197J0D01*
G01X671654D02*
G03X671457Y530986I0J-197D01*
G01X672244D02*
G03X672048Y531183I-197J0D01*
G01X669685D02*
G03X669489Y530986I0J-196D01*
G01X670276D02*
G03X670079Y531183I-197J0D01*
G01X666339Y530709D02*
G03X665552I-394J0D01*
G01X663780Y532678D02*
G03X662992Y531890I0J-788D01*
G01X665158Y532678D02*
G03X664370Y531890I0J-788D01*
G01X665552Y525197D02*
G03X666339I393J0D01*
G01X668229Y524685D02*
G03X667441Y523898I0J-788D01*
G01X664370Y524016D02*
G03X665158Y523229I787J0D01*
G01X687874Y514252D02*
G03X688662Y515040I0J788D01*
G01X704528Y499213D02*
G03X704725Y499410I0J197D01*
G01X703937D02*
G03X704134Y499213I197J0D01*
G01X702559D02*
G03X702756Y499410I0J197D01*
G01X701969D02*
G03X702166Y499213I197J0D01*
G01X700591D02*
G03X700788Y499410I0J197D01*
G01X700000D02*
G03X700197Y499213I197J0D01*
G01X698622D02*
G03X698819Y499410I0J197D01*
G01X698032D02*
G03X698229Y499213I197J0D01*
G01X696654D02*
G03X696851Y499410I0J197D01*
G01X696063D02*
G03X696260Y499213I197J0D01*
G01X694685D02*
G03X694882Y499410I0J197D01*
G01X694095D02*
G03X694292Y499213I197J0D01*
G01X692717D02*
G03X692914Y499410I0J197D01*
G01X692126D02*
G03X692323Y499213I197J0D01*
G01X690748D02*
G03X690945Y499410I0J197D01*
G01X690158D02*
G03X690355Y499213I197J0D01*
G01X688780D02*
G03X688977Y499410I0J197D01*
G01X688189D02*
G03X688386Y499213I197J0D01*
G01X686811D02*
G03X687008Y499410I0J197D01*
G01X686221D02*
G03X686418Y499213I197J0D01*
G01X684843D02*
G03X685040Y499410I0J197D01*
G01X684252D02*
G03X684449Y499213I197J0D01*
G01X667441Y515040D02*
G03X668229Y514252I788J0D01*
G01X667914Y510237D02*
G03I-985J0D01*
G01X665453Y506103D02*
G03X666634Y507284I0J1181D01*
G01X668701Y510237D02*
G03I-1772J0D01*
G01X682874Y499213D02*
G03X683071Y499410I0J197D01*
G01X682284D02*
G03X682481Y499213I197J0D01*
G01X680906D02*
G03X681103Y499410I0J197D01*
G01X680315D02*
G03X680512Y499213I197J0D01*
G01X678937D02*
G03X679134Y499410I0J197D01*
G01X678347D02*
G03X678544Y499213I197J0D01*
G01X676969D02*
G03X677166Y499410I0J197D01*
G01X676378D02*
G03X676575Y499213I197J0D01*
G01X675000D02*
G03X675197Y499410I0J197D01*
G01X674410D02*
G03X674607Y499213I197J0D01*
G01X673032D02*
G03X673229Y499410I0J197D01*
G01X672441D02*
G03X672638Y499213I197J0D01*
G01X671063D02*
G03X671260Y499410I0J197D01*
G01X670473D02*
G03X670670Y499213I197J0D01*
G01X662992Y501378D02*
G03X663780Y500591I787J0D01*
G01X686615Y521947D02*
X686680Y521679D01*
G01X686286Y521947D02*
X686352Y521679D01*
G01X684909Y521411D02*
X684974Y521143D01*
G01X681628Y522081D02*
X681693Y521813D01*
G01X684580Y521411D02*
X684712Y520942D01*
G01X686549Y522148D02*
X686615Y521947D01*
G01X683924Y522282D02*
X683990Y522081D01*
G01X679922Y521411D02*
X679987Y521210D01*
G01X676313Y521947D02*
X676378Y521746D01*
G01X676969Y518386D02*
X677953Y515572D01*
G01X676772Y517716D02*
X677691Y515237D01*
G01X673950Y522416D02*
X674082Y522081D01*
G01X679987Y521210D02*
X680053Y521076D01*
G01X679659Y521143D02*
X679790Y520875D01*
G01X678937Y522282D02*
X679003Y522148D01*
G01X676575Y522215D02*
X676641Y522081D01*
G01X674935Y520875D02*
X675000Y520741D01*
G01X673688Y522215D02*
X673754Y522081D01*
G01X672638Y522215D02*
X672704Y522081D01*
G01X686418Y522349D02*
X686549Y522148D01*
G01X686155D02*
X686286Y521947D01*
G01X684974Y521143D02*
X685105Y520942D01*
G01X684712D02*
X684843Y520741D01*
G01X681234Y522148D02*
X681365Y521947D01*
G01X676181Y522148D02*
X676313Y521947D01*
G01X674935Y521210D02*
X675066Y521009D01*
G01X681431Y522349D02*
X681628Y522081D01*
G01X686286Y522483D02*
X686418Y522349D01*
G01X686024Y522282D02*
X686155Y522148D01*
G01X683793Y522416D02*
X683924Y522282D01*
G01X685105Y520942D02*
X685237Y520808D01*
G01X683531Y522215D02*
X683662Y522081D01*
G01X684843Y520741D02*
X684974Y520607D01*
G01X678806Y522416D02*
X678937Y522282D01*
G01X680053Y521076D02*
X680250Y520875D01*
G01X678544Y522215D02*
X678675Y522081D01*
G01X679790Y520875D02*
X679922Y520741D01*
G01X676378Y522416D02*
X676575Y522215D01*
G01X673819Y522550D02*
X673950Y522416D01*
G01X673622Y522282D02*
X673688Y522215D01*
G01X675000Y520741D02*
X675132Y520607D01*
G01X672769Y522550D02*
X672966Y522349D01*
G01X672573Y522282D02*
X672638Y522215D01*
G01X714764Y512214D02*
Y514571D01*
G01Y530986D02*
Y528665D01*
G01X714567Y501731D02*
Y499410D01*
G01X714528Y513274D02*
Y509095D01*
G01X714331Y513414D02*
Y513270D01*
G01X714016D02*
Y513414D01*
G01X713819Y513274D02*
Y509095D01*
G01X713780Y499410D02*
Y501731D01*
G01X713583Y514571D02*
Y512214D01*
G01Y530986D02*
Y528665D01*
G01X712796Y512214D02*
Y514571D01*
G01Y530986D02*
Y528665D01*
G01X712599Y501731D02*
Y499410D01*
G01X712559Y513274D02*
Y509095D01*
G01X712363Y513414D02*
Y513270D01*
G01X712048D02*
Y513414D01*
G01X711851Y513274D02*
Y509095D01*
G01X711811Y499410D02*
Y501731D01*
G01X711615Y514571D02*
Y512214D01*
G01Y530986D02*
Y528665D01*
G01X710827Y512214D02*
Y514571D01*
G01Y530986D02*
Y528665D01*
G01X710630Y501731D02*
Y499410D01*
G01X710591Y513274D02*
Y509095D01*
G01X710394Y513414D02*
Y513270D01*
G01X710079D02*
Y513414D01*
G01X709882Y513274D02*
Y509095D01*
G01X709843Y499410D02*
Y501731D01*
G01X709646Y514571D02*
Y512214D01*
G01Y530986D02*
Y528665D01*
G01X708859Y512214D02*
Y514571D01*
G01Y530986D02*
Y528665D01*
G01X712889Y510554D02*
X712848Y511604D01*
G01X710920Y510554D02*
X710880Y511604D01*
G01X708952Y510554D02*
X708911Y511604D01*
G01X706983Y510554D02*
X706943Y511604D01*
G01X705015Y510554D02*
X704974Y511604D01*
G01X714764Y512555D02*
X714772Y512398D01*
G01X712796Y512555D02*
X712804Y512398D01*
G01X710827Y512555D02*
X710835Y512398D01*
G01X708859Y512555D02*
X708867Y512398D01*
G01X706890Y512555D02*
X706898Y512398D01*
G01X704922Y512555D02*
X704929Y512398D01*
G01X702953Y512555D02*
X702961Y512398D01*
G01X714857Y510554D02*
X714764Y512214D01*
G01X712889Y510554D02*
X712796Y512214D01*
G01X710920Y510554D02*
X710827Y512214D01*
G01X708952Y510554D02*
X708859Y512214D01*
G01X706983Y510554D02*
X706890Y512214D01*
G01X705015Y510554D02*
X704922Y512214D01*
G01X703046Y510554D02*
X702953Y512214D01*
G01X714817Y511604D02*
X714772Y512398D01*
G01X712848Y511604D02*
X712804Y512398D01*
G01X710880Y511604D02*
X710835Y512398D01*
G01X708911Y511604D02*
X708867Y512398D01*
G01X706943Y511604D02*
X706898Y512398D01*
G01X704974Y511604D02*
X704929Y512398D01*
G01X703006Y511604D02*
X702961Y512398D01*
G01X679594Y521545D02*
X679659Y521143D01*
G01X683990Y522081D02*
X684055Y521746D01*
G01X683662Y522081D02*
X683727Y521746D01*
G01X679003Y522148D02*
X679069Y521813D01*
G01X678675Y522081D02*
X678741Y521813D01*
G01X676641Y522081D02*
X676706Y521813D01*
G01X669817Y523354D02*
X670407Y521545D01*
G01X670473Y521277D02*
X670735Y520473D01*
G01X670079Y523622D02*
X671129Y520473D01*
G01X683596Y522550D02*
X683793Y522416D01*
G01X681037Y522282D02*
X681234Y522148D01*
G01X678609Y522550D02*
X678806Y522416D01*
G01X679922Y520741D02*
X680118Y520607D01*
G01X676181Y522550D02*
X676378Y522416D01*
G01X675066Y521009D02*
X675263Y520875D01*
G01X681431Y522349D02*
X681103Y522550D01*
G01X686286Y522483D02*
X686155Y522550D01*
G01X683531Y522215D02*
X683399Y522282D01*
G01X685105Y520540D02*
X684974Y520607D01*
G01X678544Y522215D02*
X678412Y522282D01*
G01X680381Y520808D02*
X680250Y520875D01*
G01X676181Y522148D02*
X675919Y522282D01*
G01X673622D02*
X673491Y522349D01*
G01X672573Y522282D02*
X672441Y522349D01*
G01X675263Y520540D02*
X675132Y520607D01*
G01X683596Y522550D02*
X683399Y522617D01*
G01X713490Y510554D02*
X713583Y512214D01*
G01X713575Y512398D02*
X713530Y511604D01*
G01X711521Y510554D02*
X711615Y512214D01*
G01X711607Y512398D02*
X711562Y511604D01*
G01X709553Y510554D02*
X709646Y512214D01*
G01X709638Y512398D02*
X709593Y511604D01*
G01X707584Y510554D02*
X707678Y512214D01*
G01X707670Y512398D02*
X707625Y511604D01*
G01X705616Y510554D02*
X705709Y512214D01*
G01X705701Y512398D02*
X705656Y511604D01*
G01X703647Y510554D02*
X703741Y512214D01*
G01X703733Y512398D02*
X703688Y511604D01*
G01X701679Y510554D02*
X701772Y512214D01*
G01X701764Y512398D02*
X701719Y511604D01*
G01X699710Y510554D02*
X699804Y512214D01*
G01X699796Y512398D02*
X699751Y511604D01*
G01X697742Y510554D02*
X697835Y512214D01*
G01X697827Y512398D02*
X697782Y511604D01*
G01X695773Y510554D02*
X695867Y512214D01*
G01X695859Y512398D02*
X695814Y511604D01*
G01X693805Y510554D02*
X693898Y512214D01*
G01X693890Y512398D02*
X693845Y511604D01*
G01X691836Y510554D02*
X691929Y512214D01*
G01X691922Y512398D02*
X691877Y511604D01*
G01X689868Y510554D02*
X689961Y512214D01*
G01X689953Y512398D02*
X689908Y511604D01*
G01X687899Y510554D02*
X687992Y512214D01*
G01X687985Y512398D02*
X687940Y511604D01*
G01X685931Y510554D02*
X686024Y512214D01*
G01X686016Y512398D02*
X685971Y511604D01*
G01X683962Y510554D02*
X684055Y512214D01*
G01X684048Y512398D02*
X684003Y511604D01*
G01X681994Y510554D02*
X682087Y512214D01*
G01X682079Y512398D02*
X682034Y511604D01*
G01X680025Y510554D02*
X680118Y512214D01*
G01X680111Y512398D02*
X680066Y511604D01*
G01X678057Y510554D02*
X678150Y512214D01*
G01X678142Y512398D02*
X678097Y511604D01*
G01X676181Y512214D02*
X676174Y512064D01*
G01X713575Y512398D02*
X713583Y512555D01*
G01X711607Y512398D02*
X711615Y512555D01*
G01X709638Y512398D02*
X709646Y512555D01*
G01X707670Y512398D02*
X707678Y512555D01*
G01X705701Y512398D02*
X705709Y512555D01*
G01X703733Y512398D02*
X703741Y512555D01*
G01X701764Y512398D02*
X701772Y512555D01*
G01X699796Y512398D02*
X699804Y512555D01*
G01X697827Y512398D02*
X697835Y512555D01*
G01X695859Y512398D02*
X695867Y512555D01*
G01X693890Y512398D02*
X693898Y512555D01*
G01X691922Y512398D02*
X691929Y512555D01*
G01X689953Y512398D02*
X689961Y512555D01*
G01X687985Y512398D02*
X687992Y512555D01*
G01X686016Y512398D02*
X686024Y512555D01*
G01X684048Y512398D02*
X684055Y512555D01*
G01X682079Y512398D02*
X682087Y512555D01*
G01X680111Y512398D02*
X680118Y512555D01*
G01X678142Y512398D02*
X678150Y512555D01*
G01X676174Y512398D02*
X676181Y512555D01*
G01X713490Y510554D02*
X713530Y511604D01*
G01X711521Y510554D02*
X711562Y511604D01*
G01X709553Y510554D02*
X709593Y511604D01*
G01X707584Y510554D02*
X707625Y511604D01*
G01X705616Y510554D02*
X705656Y511604D01*
G01X703647Y510554D02*
X703688Y511604D01*
G01X701679Y510554D02*
X701719Y511604D01*
G01X699710Y510554D02*
X699751Y511604D01*
G01X697742Y510554D02*
X697782Y511604D01*
G01X695773Y510554D02*
X695814Y511604D01*
G01X693805Y510554D02*
X693845Y511604D01*
G01X691836Y510554D02*
X691877Y511604D01*
G01X689868Y510554D02*
X689908Y511604D01*
G01X687899Y510554D02*
X687940Y511604D01*
G01X685931Y510554D02*
X685971Y511604D01*
G01X683962Y510554D02*
X684003Y511604D01*
G01X681994Y510554D02*
X682034Y511604D01*
G01X680025Y510554D02*
X680066Y511604D01*
G01X678057Y510554D02*
X678097Y511604D01*
G01X676088Y510554D02*
X676129Y511604D01*
G01X674120Y510554D02*
X674160Y511604D01*
G01X708662Y501731D02*
Y499410D01*
G01X708622Y513274D02*
Y509095D01*
G01X708426Y513414D02*
Y513270D01*
G01X708111D02*
Y513414D01*
G01X707914Y513274D02*
Y509095D01*
G01X707874Y499410D02*
Y501731D01*
G01X707678Y514571D02*
Y512214D01*
G01Y530986D02*
Y528665D01*
G01X706890Y512214D02*
Y514571D01*
G01Y530986D02*
Y528665D01*
G01X706693Y501731D02*
Y499410D01*
G01X706654Y513274D02*
Y509095D01*
G01X706457Y513414D02*
Y513270D01*
G01X706142D02*
Y513414D01*
G01X705945Y513274D02*
Y509095D01*
G01X705906Y499410D02*
Y501731D01*
G01X705709Y514571D02*
Y512214D01*
G01Y530986D02*
Y528665D01*
G01X704922Y512214D02*
Y514571D01*
G01Y530986D02*
Y528665D01*
G01X704725Y501731D02*
Y499410D01*
G01X704685Y513274D02*
Y509095D01*
G01X704489Y513414D02*
Y513270D01*
G01X704174D02*
Y513414D01*
G01X703977Y513274D02*
Y509095D01*
G01X703937Y499410D02*
Y501731D01*
G01X703741Y514571D02*
Y512214D01*
G01Y530986D02*
Y528665D01*
G01X702953Y512214D02*
Y514571D01*
G01Y530986D02*
Y528665D01*
G01X702756Y501731D02*
Y499410D01*
G01X702717Y513274D02*
Y509095D01*
G01X702520Y513414D02*
Y513270D01*
G01X702205D02*
Y513414D01*
G01X702008Y513274D02*
Y509095D01*
G01X701969Y499410D02*
Y501731D01*
G01X701772Y514571D02*
Y512214D01*
G01Y530986D02*
Y528665D01*
G01X700985Y512214D02*
Y514571D01*
G01Y530986D02*
Y528665D01*
G01X700788Y501731D02*
Y499410D01*
G01X700748Y513274D02*
Y509095D01*
G01X700552Y513414D02*
Y513270D01*
G01X700237D02*
Y513414D01*
G01X700040Y513274D02*
Y509095D01*
G01X700000Y499410D02*
Y501731D01*
G01X699804Y514571D02*
Y512214D01*
G01Y530986D02*
Y528665D01*
G01X699016Y512214D02*
Y514571D01*
G01Y530986D02*
Y528665D01*
G01X698819Y501731D02*
Y499410D01*
G01X698780Y513274D02*
Y509095D01*
G01X698583Y513414D02*
Y513270D01*
G01X698268D02*
Y513414D01*
G01X698071Y513274D02*
Y509095D01*
G01X698032Y499410D02*
Y501731D01*
G01X697835Y514571D02*
Y512214D01*
G01Y530986D02*
Y528665D01*
G01X697048Y512214D02*
Y514571D01*
G01Y530986D02*
Y528665D01*
G01X696851Y501731D02*
Y499410D01*
G01X696811Y513274D02*
Y509095D01*
G01X696615Y513414D02*
Y513270D01*
G01X696300D02*
Y513414D01*
G01X696103Y513274D02*
Y509095D01*
G01X696063Y499410D02*
Y501731D01*
G01X695867Y514571D02*
Y512214D01*
G01Y530986D02*
Y528665D01*
G01X695079Y512214D02*
Y514571D01*
G01Y530986D02*
Y528665D01*
G01X694882Y501731D02*
Y499410D01*
G01X694843Y513274D02*
Y509095D01*
G01X694646Y513414D02*
Y513270D01*
G01X694331D02*
Y513414D01*
G01X694134Y513274D02*
Y509095D01*
G01X694095Y499410D02*
Y501731D01*
G01X693898Y514571D02*
Y512214D01*
G01Y530986D02*
Y528665D01*
G01X693111Y512214D02*
Y514571D01*
G01Y530986D02*
Y528665D01*
G01X692914Y501731D02*
Y499410D01*
G01X692874Y513274D02*
Y509095D01*
G01X692678Y513414D02*
Y513270D01*
G01X692363D02*
Y513414D01*
G01X692166Y513274D02*
Y509095D01*
G01X692126Y499410D02*
Y501731D01*
G01X691929Y514571D02*
Y512214D01*
G01Y530986D02*
Y528665D01*
G01X691142Y512214D02*
Y514571D01*
G01Y530986D02*
Y528665D01*
G01X690945Y501731D02*
Y499410D01*
G01X690906Y513274D02*
Y509095D01*
G01X690709Y513414D02*
Y513270D01*
G01X690394D02*
Y513414D01*
G01X690197Y513274D02*
Y509095D01*
G01X690158Y499410D02*
Y501731D01*
G01X689961Y514571D02*
Y512214D01*
G01Y530986D02*
Y528665D01*
G01X689174Y512214D02*
Y514571D01*
G01Y530986D02*
Y528665D01*
G01X688977Y501731D02*
Y499410D01*
G01X688937Y513274D02*
Y509095D01*
G01X688741Y513414D02*
Y513270D01*
G01X688662Y523898D02*
Y515040D01*
G01X688426Y513270D02*
Y513414D01*
G01X688229Y513274D02*
Y509095D01*
G01X688189Y499410D02*
Y501731D01*
G01X687992Y514571D02*
Y512214D01*
G01Y530986D02*
Y528665D01*
G01X687533Y523622D02*
Y520473D01*
G01X687205Y512214D02*
Y514571D01*
G01Y523622D02*
Y520473D01*
G01Y530986D02*
Y528665D01*
G01X687008Y501731D02*
Y499410D01*
G01X686969Y513274D02*
Y509095D01*
G01X686772Y513414D02*
Y513270D01*
G01X686680Y521679D02*
Y521411D01*
G01X686457Y513270D02*
Y513414D01*
G01X686352Y521679D02*
Y521411D01*
G01X686260Y513274D02*
Y509095D01*
G01X686221Y499410D02*
Y501731D01*
G01X686024Y514571D02*
Y512214D01*
G01Y530986D02*
Y528665D01*
G01X685237Y512214D02*
Y514571D01*
G01Y530986D02*
Y528665D01*
G01X685040Y501731D02*
Y499410D01*
G01X685000Y513274D02*
Y509095D01*
G01X684909Y521679D02*
Y521411D01*
G01X684804Y513414D02*
Y513270D01*
G01X684580Y521679D02*
Y521411D01*
G01X684489Y513270D02*
Y513414D01*
G01X684292Y513274D02*
Y509095D01*
G01X684252Y499410D02*
Y501731D01*
G01X684055Y514571D02*
Y512214D01*
G01Y521746D02*
Y520473D01*
G01Y530986D02*
Y528665D01*
G01X683727Y521746D02*
Y520473D01*
G01X683268Y512214D02*
Y514571D01*
G01Y530986D02*
Y528665D01*
G01X683071Y501731D02*
Y499410D01*
G01X683032Y513274D02*
Y509095D01*
G01X682835Y513414D02*
Y513270D01*
G01X682546Y522014D02*
Y520473D01*
G01Y522617D02*
Y522282D01*
G01X682520Y513270D02*
Y513414D01*
G01X682323Y513274D02*
Y509095D01*
G01X682284Y499410D02*
Y501731D01*
G01X682218Y522617D02*
Y520473D01*
G01X682087Y514571D02*
Y512214D01*
G01Y530986D02*
Y528665D01*
G01X681693Y521813D02*
Y521545D01*
G01X681365Y521947D02*
Y521813D01*
G01X681300Y512214D02*
Y514571D01*
G01Y530986D02*
Y528665D01*
G01X681103Y501731D02*
Y499410D01*
G01X681063Y513274D02*
Y509095D01*
G01X680867Y513414D02*
Y513270D01*
G01X680552D02*
Y513414D01*
G01X680355Y513274D02*
Y509095D01*
G01X680315Y499410D02*
Y501731D01*
G01X680118Y514571D02*
Y512214D01*
G01Y530986D02*
Y528665D01*
G01X679987Y521880D02*
Y521813D01*
G01X679922Y521545D02*
Y521411D01*
G01X679528Y518386D02*
Y515237D01*
G01X679331Y512214D02*
Y514571D01*
G01Y530986D02*
Y528665D01*
G01X679134Y501731D02*
Y499410D01*
G01Y517716D02*
Y515237D01*
G01X679095Y513274D02*
Y509095D01*
G01X679069Y521813D02*
Y520473D01*
G01X678898Y513414D02*
Y513270D01*
G01X678741Y521813D02*
Y520473D01*
G01X678583Y513270D02*
Y513414D01*
G01X678386Y513274D02*
Y509095D01*
G01X678347Y499410D02*
Y501731D01*
G01X678150Y514571D02*
Y512214D01*
G01Y530986D02*
Y528665D01*
G01X677559Y522014D02*
Y520473D01*
G01Y523622D02*
Y522282D01*
G01X677363Y512214D02*
Y514571D01*
G01Y530986D02*
Y528665D01*
G01X677231Y523622D02*
Y520473D01*
G01X677166Y501731D02*
Y499410D01*
G01X677126Y513274D02*
Y509095D01*
G01X676929Y513414D02*
Y513270D01*
G01X676772Y517716D02*
Y515237D01*
G01X676706Y521813D02*
Y521277D01*
G01X676615Y513270D02*
Y513414D01*
G01X676418Y513274D02*
Y509095D01*
G01X676378Y499410D02*
Y501731D01*
G01Y518386D02*
Y515237D01*
G01Y521746D02*
Y521344D01*
G01X676181Y514571D02*
Y512214D01*
G01Y530986D02*
Y528665D01*
G01X675394Y512214D02*
Y514571D01*
G01Y530986D02*
Y528665D01*
G01X675197Y501731D02*
Y499410D01*
G01X675158Y513274D02*
Y509095D01*
G01X674961Y513414D02*
Y513270D01*
G01X674935Y521880D02*
Y521210D01*
G01Y520875D02*
Y519401D01*
G01Y522617D02*
Y522215D01*
G01X674646Y513270D02*
Y513414D01*
G01X674607Y522617D02*
Y519401D01*
G01X674449Y513274D02*
Y509095D01*
G01X674410Y499410D02*
Y501731D01*
G01X674213Y514571D02*
Y512214D01*
G01Y530986D02*
Y528665D01*
G01X674082Y522081D02*
Y520473D01*
G01X673754Y522081D02*
Y520473D01*
G01X673426Y512214D02*
Y514571D01*
G01Y530986D02*
Y528665D01*
G01X673229Y501731D02*
Y499410D01*
G01X673189Y513274D02*
Y509095D01*
G01X673032Y522081D02*
Y520473D01*
G01X672992Y513414D02*
Y513270D01*
G01X672835Y522638D02*
Y526575D01*
G01X672704Y522081D02*
Y520473D01*
G01X672678Y513270D02*
Y513414D01*
G01X672481Y513274D02*
Y509095D01*
G01X672441Y499410D02*
Y501731D01*
G01X672244Y514571D02*
Y512214D01*
G01Y530986D02*
Y528665D01*
G01X671982Y522148D02*
Y520473D01*
G01Y522617D02*
Y522416D01*
G01X671654Y522617D02*
Y520473D01*
G01X671457Y512214D02*
Y514571D01*
G01Y530986D02*
Y528665D01*
G01X671260Y501731D02*
Y499410D01*
G01X671221Y513274D02*
Y509095D01*
G01X671024Y513414D02*
Y513270D01*
G01X670867Y526575D02*
Y522638D01*
G01X670709Y513270D02*
Y513414D01*
G01X670512Y513274D02*
Y509095D01*
G01X670473Y499410D02*
Y501731D01*
G01X670276Y514571D02*
Y512214D01*
G01Y530986D02*
Y528665D01*
G01X669489Y512214D02*
Y514571D01*
G01Y530986D02*
Y528665D01*
G01X703046Y510554D02*
X703006Y511604D01*
G01X701078Y510554D02*
X701037Y511604D01*
G01X699109Y510554D02*
X699069Y511604D01*
G01X697141Y510554D02*
X697100Y511604D01*
G01X695172Y510554D02*
X695132Y511604D01*
G01X693204Y510554D02*
X693163Y511604D01*
G01X691235Y510554D02*
X691195Y511604D01*
G01X689267Y510554D02*
X689226Y511604D01*
G01X687298Y510554D02*
X687258Y511604D01*
G01X685330Y510554D02*
X685289Y511604D01*
G01X683361Y510554D02*
X683321Y511604D01*
G01X681393Y510554D02*
X681352Y511604D01*
G01X679424Y510554D02*
X679384Y511604D01*
G01X677456Y510554D02*
X677415Y511604D01*
G01X675487Y510554D02*
X675447Y511604D01*
G01X673519Y510554D02*
X673478Y511604D01*
G01X671550Y510554D02*
X671510Y511604D01*
G01X669582Y510554D02*
X669541Y511604D01*
G01X700985Y512555D02*
X700992Y512398D01*
G01X699016Y512555D02*
X699024Y512398D01*
G01X697048Y512555D02*
X697055Y512398D01*
G01X695079Y512555D02*
X695087Y512398D01*
G01X693111Y512555D02*
X693118Y512398D01*
G01X691142Y512555D02*
X691150Y512398D01*
G01X689174Y512555D02*
X689181Y512398D01*
G01X687205Y512555D02*
X687213Y512398D01*
G01X685237Y512555D02*
X685244Y512398D01*
G01X683268Y512555D02*
X683276Y512398D01*
G01X681300Y512555D02*
X681307Y512398D01*
G01X679331Y512555D02*
X679339Y512398D01*
G01X677363Y512555D02*
X677370Y512398D01*
G01X675394Y512555D02*
X675402Y512398D01*
G01X673426Y512555D02*
X673433Y512398D01*
G01X671457Y512555D02*
X671465Y512398D01*
G01X669489Y512555D02*
X669496Y512398D01*
G01X701078Y510554D02*
X700985Y512214D01*
G01X699109Y510554D02*
X699016Y512214D01*
G01X697141Y510554D02*
X697048Y512214D01*
G01X695172Y510554D02*
X695079Y512214D01*
G01X693204Y510554D02*
X693111Y512214D01*
G01X691235Y510554D02*
X691142Y512214D01*
G01X689267Y510554D02*
X689174Y512214D01*
G01X687298Y510554D02*
X687205Y512214D01*
G01X685330Y510554D02*
X685237Y512214D01*
G01X683361Y510554D02*
X683268Y512214D01*
G01X681393Y510554D02*
X681300Y512214D01*
G01X679424Y510554D02*
X679331Y512214D01*
G01X677456Y510554D02*
X677363Y512214D01*
G01X675487Y510554D02*
X675394Y512214D01*
G01X673519Y510554D02*
X673426Y512214D01*
G01X671550Y510554D02*
X671457Y512214D01*
G01X669582Y510554D02*
X669489Y512214D01*
G01X701037Y511604D02*
X700992Y512398D01*
G01X699069Y511604D02*
X699024Y512398D01*
G01X697100Y511604D02*
X697055Y512398D01*
G01X695132Y511604D02*
X695087Y512398D01*
G01X693163Y511604D02*
X693118Y512398D01*
G01X691195Y511604D02*
X691150Y512398D01*
G01X689226Y511604D02*
X689181Y512398D01*
G01X687258Y511604D02*
X687213Y512398D01*
G01X685289Y511604D02*
X685244Y512398D01*
G01X683321Y511604D02*
X683276Y512398D01*
G01X681352Y511604D02*
X681307Y512398D01*
G01X679384Y511604D02*
X679339Y512398D01*
G01X677415Y511604D02*
X677370Y512398D01*
G01X675447Y511604D02*
X675402Y512398D01*
G01X673478Y511604D02*
X673433Y512398D01*
G01X671510Y511604D02*
X671465Y512398D01*
G01X669541Y511604D02*
X669496Y512398D01*
G01X678609Y522550D02*
X678412Y522617D01*
G01X680315Y520540D02*
X680118Y520607D01*
G01X673819Y522550D02*
X673622Y522617D01*
G01X672769Y522550D02*
X672573Y522617D01*
G01X686155Y522550D02*
X685893Y522617D01*
G01X686024Y522282D02*
X685762Y522349D01*
G01X683399Y522282D02*
X683137Y522349D01*
G01X685499Y520741D02*
X685237Y520808D01*
G01X678412Y522282D02*
X678150Y522349D01*
G01X685368Y520473D02*
X685105Y520540D01*
G01X676181Y522550D02*
X675919Y522617D01*
G01X680643Y520741D02*
X680381Y520808D01*
G01X675525D02*
X675263Y520875D01*
G01X675525Y520473D02*
X675263Y520540D01*
G01X681103Y522550D02*
X680709Y522617D01*
G01X681037Y522282D02*
X680643Y522349D01*
G01X680709Y520473D02*
X680315Y520540D01*
G01X684712Y522148D02*
X684646Y521947D01*
G01X686680Y521411D02*
X686549Y520942D01*
G01X686352Y521411D02*
X686286Y521143D01*
G01X684974Y521947D02*
X684909Y521679D01*
G01X684646Y521947D02*
X684580Y521679D01*
G01X681693Y521143D02*
X681628Y520875D01*
G01X676706Y521277D02*
X676641Y521009D01*
G01X679659Y521947D02*
X679594Y521545D01*
G01X676088Y510554D02*
X676174Y512064D01*
G01Y512398D02*
X676129Y511604D01*
G01X674120Y510554D02*
X674213Y512214D01*
G01X674205Y512398D02*
X674160Y511604D01*
G01X672151Y510554D02*
X672244Y512214D01*
G01X672237Y512398D02*
X672192Y511604D01*
G01X670183Y510554D02*
X670276Y512214D01*
G01X670268Y512398D02*
X670223Y511604D01*
G01X674205Y512398D02*
X674213Y512555D01*
G01X672237Y512398D02*
X672244Y512555D01*
G01X670268Y512398D02*
X670276Y512555D01*
G01X672151Y510554D02*
X672192Y511604D01*
G01X670183Y510554D02*
X670223Y511604D01*
G01X667756Y529725D02*
Y532678D01*
G01X667717Y508650D02*
Y500591D01*
G01X667441Y523898D02*
Y515040D01*
G01X667323Y532678D02*
Y529725D01*
G01X667035Y523229D02*
Y529725D01*
G01X666733Y532678D02*
Y523229D01*
G01X666634Y507284D02*
Y517126D01*
G01X666339Y530709D02*
Y525197D01*
G01X666142Y526575D02*
Y532678D01*
G01X665552Y525197D02*
Y530709D01*
G01X665453Y506103D02*
Y510040D01*
G01X664370Y524016D02*
Y531890D01*
G01X663977Y526575D02*
Y532678D01*
G01X662992Y531890D02*
Y500591D01*
G01X663780Y532678D02*
X667914D01*
G01X670079Y531183D02*
X669685D01*
G01X674016D02*
X673622D01*
G01X672048D02*
X671654D01*
G01X677953D02*
X677559D01*
G01X675985D02*
X675591D01*
G01X679922D02*
X679528D01*
G01X683859D02*
X683465D01*
G01X681890D02*
X681496D01*
G01X687796D02*
X687402D01*
G01X685827D02*
X685433D01*
G01X689764D02*
X689370D01*
G01X693701D02*
X693307D01*
G01X691733D02*
X691339D01*
G01X697638D02*
X697244D01*
G01X695670D02*
X695276D01*
G01X699607D02*
X699213D01*
G01X703544D02*
X703150D01*
G01X701575D02*
X701181D01*
G01X707481D02*
X707087D01*
G01X705512D02*
X705118D01*
G01X711418D02*
X711024D01*
G01X709449D02*
X709055D01*
G01X713386D02*
X712992D01*
G01X666142Y529725D02*
X746457D01*
G01X670276Y529214D02*
X669489D01*
G01X674213D02*
X673426D01*
G01X672244D02*
X671457D01*
G01X678150D02*
X677363D01*
G01X676181D02*
X675394D01*
G01X680118D02*
X679331D01*
G01X684055D02*
X683268D01*
G01X682087D02*
X681300D01*
G01X687992D02*
X687205D01*
G01X686024D02*
X685237D01*
G01X691929D02*
X691142D01*
G01X689961D02*
X689174D01*
G01X693898D02*
X693111D01*
G01X697835D02*
X697048D01*
G01X695867D02*
X695079D01*
G01X701772D02*
X700985D01*
G01X699804D02*
X699016D01*
G01X703741D02*
X702953D01*
G01X707678D02*
X706890D01*
G01X705709D02*
X704922D01*
G01X711615D02*
X710827D01*
G01X709646D02*
X708859D01*
G01X713583D02*
X712796D01*
G01X715552D02*
X714764D01*
G01Y528665D02*
X715552D01*
G01X712796D02*
X713583D01*
G01X710827D02*
X711615D01*
G01X708859D02*
X709646D01*
G01X706890D02*
X707678D01*
G01X704922D02*
X705709D01*
G01X702953D02*
X703741D01*
G01X700985D02*
X701772D01*
G01X699016D02*
X699804D01*
G01X697048D02*
X697835D01*
G01X695079D02*
X695867D01*
G01X693111D02*
X693898D01*
G01X691142D02*
X691929D01*
G01X689174D02*
X689961D01*
G01X687205D02*
X687992D01*
G01X685237D02*
X686024D01*
G01X683268D02*
X684055D01*
G01X681300D02*
X682087D01*
G01X679331D02*
X680118D01*
G01X677363D02*
X678150D01*
G01X675394D02*
X676181D01*
G01X673426D02*
X674213D01*
G01X671457D02*
X672244D01*
G01X669489D02*
X670276D01*
G01X746457Y527363D02*
X666142D01*
G01X664370Y526575D02*
X662992D01*
G01X666142D02*
X665552D01*
G01X672835D02*
X670867D01*
G01X687874Y524685D02*
X668229D01*
G01X670079Y523622D02*
X669554D01*
G01X677559D02*
X677231D01*
G01X687533D02*
X687205D01*
G01X665158Y523229D02*
X667035D01*
G01X672835Y522638D02*
X670867D01*
G01X674935Y522617D02*
X674607D01*
G01X671982D02*
X671654D01*
G01X672573D02*
X672310D01*
G01X673622D02*
X673360D01*
G01X675919D02*
X675525D01*
G01X678412D02*
X678150D01*
G01X682546D02*
X682218D01*
G01X683399D02*
X683137D01*
G01X685893D02*
X685368D01*
G01X672441Y522349D02*
X672310D01*
G01X673491D02*
X673294D01*
G01X685762D02*
X685499D01*
G01X675919Y522282D02*
X675525D01*
G01X681365Y521813D02*
X679987D01*
G01X670407Y521545D02*
X669226D01*
G01X681693D02*
X679922D01*
G01X670473Y521277D02*
X669160D01*
G01X681693Y521143D02*
X681365D01*
G01X675788Y520808D02*
X675525D01*
G01X685762Y520741D02*
X685499D01*
G01X668898Y520473D02*
X668504D01*
G01X671129D02*
X670735D01*
G01X673032D02*
X672704D01*
G01X674082D02*
X673754D01*
G01X671982D02*
X671654D01*
G01X677559D02*
X677231D01*
G01X675919D02*
X675525D01*
G01X679069D02*
X678741D01*
G01X684055D02*
X683727D01*
G01X682546D02*
X682218D01*
G01X687533D02*
X687205D01*
G01X685893D02*
X685368D01*
G01X674935Y519401D02*
X674607D01*
G01X676969Y518386D02*
X676378D01*
G01X679528D02*
X678937D01*
G01X728248Y517126D02*
X666634D01*
G01X676772Y515237D02*
X676378D01*
G01X678216D02*
X677691D01*
G01X679528D02*
X679134D01*
G01X670276Y514571D02*
X669489D01*
G01X672244D02*
X671457D01*
G01X674213D02*
X673426D01*
G01X676181D02*
X675394D01*
G01X678150D02*
X677363D01*
G01X680118D02*
X679331D01*
G01X682087D02*
X681300D01*
G01X684055D02*
X683268D01*
G01X686024D02*
X685237D01*
G01X687992D02*
X687205D01*
G01X689961D02*
X689174D01*
G01X691929D02*
X691142D01*
G01X693898D02*
X693111D01*
G01X695867D02*
X695079D01*
G01X697835D02*
X697048D01*
G01X699804D02*
X699016D01*
G01X701772D02*
X700985D01*
G01X703741D02*
X702953D01*
G01X705709D02*
X704922D01*
G01X707678D02*
X706890D01*
G01X709646D02*
X708859D01*
G01X711615D02*
X710827D01*
G01X713583D02*
X712796D01*
G01X715552D02*
X714764D01*
G01X687874Y514252D02*
X668229D01*
G01X670276Y513888D02*
X669489D01*
G01X672244D02*
X671457D01*
G01X674213D02*
X673426D01*
G01X676181D02*
X675394D01*
G01X678150D02*
X677363D01*
G01X680118D02*
X679331D01*
G01X682087D02*
X681300D01*
G01X684055D02*
X683268D01*
G01X686024D02*
X685237D01*
G01X687992D02*
X687205D01*
G01X689961D02*
X689174D01*
G01X691929D02*
X691142D01*
G01X693898D02*
X693111D01*
G01X695867D02*
X695079D01*
G01X697835D02*
X697048D01*
G01X699804D02*
X699016D01*
G01X701772D02*
X700985D01*
G01X703741D02*
X702953D01*
G01X705709D02*
X704922D01*
G01X707678D02*
X706890D01*
G01X709646D02*
X708859D01*
G01X711615D02*
X710827D01*
G01X713583D02*
X712796D01*
G01X715552D02*
X714764D01*
G01X670276Y513826D02*
X669489D01*
G01X672244D02*
X671457D01*
G01X674213D02*
X673426D01*
G01X676181D02*
X675394D01*
G01X678150D02*
X677363D01*
G01X680118D02*
X679331D01*
G01X682087D02*
X681300D01*
G01X684055D02*
X683268D01*
G01X686024D02*
X685237D01*
G01X687992D02*
X687205D01*
G01X689961D02*
X689174D01*
G01X691929D02*
X691142D01*
G01X693898D02*
X693111D01*
G01X695867D02*
X695079D01*
G01X697835D02*
X697048D01*
G01X699804D02*
X699016D01*
G01X701772D02*
X700985D01*
G01X703741D02*
X702953D01*
G01X705709D02*
X704922D01*
G01X707678D02*
X706890D01*
G01X709646D02*
X708859D01*
G01X711615D02*
X710827D01*
G01X713583D02*
X712796D01*
G01X715552D02*
X714764D01*
G01Y513499D02*
X715552D01*
G01X712796D02*
X713583D01*
G01X708859D02*
X709646D01*
G01X710827D02*
X711615D01*
G01X704922D02*
X705709D01*
G01X706890D02*
X707678D01*
G01X702953D02*
X703741D01*
G01X699016D02*
X699804D01*
G01X700985D02*
X701772D01*
G01X695079D02*
X695867D01*
G01X697048D02*
X697835D01*
G01X693111D02*
X693898D01*
G01X689174D02*
X689961D01*
G01X691142D02*
X691929D01*
G01X685237D02*
X686024D01*
G01X687205D02*
X687992D01*
G01X681300D02*
X682087D01*
G01X683268D02*
X684055D01*
G01X679331D02*
X680118D01*
G01X675394D02*
X676181D01*
G01X677363D02*
X678150D01*
G01X671457D02*
X672244D01*
G01X673426D02*
X674213D01*
G01X669489D02*
X670276D01*
G01X712048Y513414D02*
X712363D01*
G01X714016D02*
X714331D01*
G01X708111D02*
X708426D01*
G01X710079D02*
X710394D01*
G01X706142D02*
X706457D01*
G01X702205D02*
X702520D01*
G01X704174D02*
X704489D01*
G01X698268D02*
X698583D01*
G01X700237D02*
X700552D01*
G01X696300D02*
X696615D01*
G01X692363D02*
X692678D01*
G01X694331D02*
X694646D01*
G01X688426D02*
X688741D01*
G01X690394D02*
X690709D01*
G01X686457D02*
X686772D01*
G01X682520D02*
X682835D01*
G01X684489D02*
X684804D01*
G01X678583D02*
X678898D01*
G01X680552D02*
X680867D01*
G01X674646D02*
X674961D01*
G01X676615D02*
X676929D01*
G01X672678D02*
X672992D01*
G01X670709D02*
X671024D01*
G01X712048Y513270D02*
X712363D01*
G01X714016D02*
X714331D01*
G01X708111D02*
X708426D01*
G01X710079D02*
X710394D01*
G01X706142D02*
X706457D01*
G01X702205D02*
X702520D01*
G01X704174D02*
X704489D01*
G01X698268D02*
X698583D01*
G01X700237D02*
X700552D01*
G01X696300D02*
X696615D01*
G01X692363D02*
X692678D01*
G01X694331D02*
X694646D01*
G01X688426D02*
X688741D01*
G01X690394D02*
X690709D01*
G01X686457D02*
X686772D01*
G01X682520D02*
X682835D01*
G01X684489D02*
X684804D01*
G01X678583D02*
X678898D01*
G01X680552D02*
X680867D01*
G01X674646D02*
X674961D01*
G01X676615D02*
X676929D01*
G01X672678D02*
X672992D01*
G01X670709D02*
X671024D01*
G01X671221Y512890D02*
X670512D01*
G01X673189D02*
X672481D01*
G01X675158D02*
X674449D01*
G01X677126D02*
X676418D01*
G01X679095D02*
X678386D01*
G01X681063D02*
X680355D01*
G01X683032D02*
X682323D01*
G01X685000D02*
X684292D01*
G01X686969D02*
X686260D01*
G01X688937D02*
X688229D01*
G01X690906D02*
X690197D01*
G01X692874D02*
X692166D01*
G01X694843D02*
X694134D01*
G01X696811D02*
X696103D01*
G01X698780D02*
X698071D01*
G01X700748D02*
X700040D01*
G01X702717D02*
X702008D01*
G01X704685D02*
X703977D01*
G01X706654D02*
X705945D01*
G01X708622D02*
X707914D01*
G01X710591D02*
X709882D01*
G01X712559D02*
X711851D01*
G01X714528D02*
X713819D01*
G01X711851Y512854D02*
X712559D01*
G01X713819D02*
X714528D01*
G01X707914D02*
X708622D01*
G01X709882D02*
X710591D01*
G01X705945D02*
X706654D01*
G01X702008D02*
X702717D01*
G01X703977D02*
X704685D01*
G01X698071D02*
X698780D01*
G01X700040D02*
X700748D01*
G01X696103D02*
X696811D01*
G01X692166D02*
X692874D01*
G01X694134D02*
X694843D01*
G01X688229D02*
X688937D01*
G01X690197D02*
X690906D01*
G01X686260D02*
X686969D01*
G01X682323D02*
X683032D01*
G01X684292D02*
X685000D01*
G01X678386D02*
X679095D01*
G01X680355D02*
X681063D01*
G01X676418D02*
X677126D01*
G01X672481D02*
X673189D01*
G01X674449D02*
X675158D01*
G01X670512D02*
X671221D01*
G01X666634Y512796D02*
X728248D01*
G01X671221Y512522D02*
X670512D01*
G01X673189D02*
X672481D01*
G01X675158D02*
X674449D01*
G01X677126D02*
X676418D01*
G01X679095D02*
X678386D01*
G01X681063D02*
X680355D01*
G01X683032D02*
X682323D01*
G01X685000D02*
X684292D01*
G01X686969D02*
X686260D01*
G01X688937D02*
X688229D01*
G01X690906D02*
X690197D01*
G01X692874D02*
X692166D01*
G01X694843D02*
X694134D01*
G01X696811D02*
X696103D01*
G01X698780D02*
X698071D01*
G01X700748D02*
X700040D01*
G01X702717D02*
X702008D01*
G01X704685D02*
X703977D01*
G01X706654D02*
X705945D01*
G01X708622D02*
X707914D01*
G01X710591D02*
X709882D01*
G01X712559D02*
X711851D01*
G01X714528D02*
X713819D01*
G01X670268Y512398D02*
X669496D01*
G01X672237D02*
X671465D01*
G01X674205D02*
X673433D01*
G01X676174D02*
X675402D01*
G01X678142D02*
X677370D01*
G01X680111D02*
X679339D01*
G01X682079D02*
X681307D01*
G01X684048D02*
X683276D01*
G01X686016D02*
X685244D01*
G01X687985D02*
X687213D01*
G01X689953D02*
X689181D01*
G01X691922D02*
X691150D01*
G01X693890D02*
X693118D01*
G01X695859D02*
X695087D01*
G01X697827D02*
X697055D01*
G01X699796D02*
X699024D01*
G01X701764D02*
X700992D01*
G01X703733D02*
X702961D01*
G01X705701D02*
X704929D01*
G01X707670D02*
X706898D01*
G01X709638D02*
X708867D01*
G01X711607D02*
X710835D01*
G01X713575D02*
X712804D01*
G01X715544D02*
X714772D01*
G01Y512064D02*
X715544D01*
G01X712804D02*
X713575D01*
G01X708867D02*
X709638D01*
G01X710835D02*
X711607D01*
G01X704929D02*
X705701D01*
G01X706898D02*
X707670D01*
G01X702961D02*
X703733D01*
G01X699024D02*
X699796D01*
G01X700992D02*
X701764D01*
G01X695087D02*
X695859D01*
G01X697055D02*
X697827D01*
G01X693118D02*
X693890D01*
G01X689181D02*
X689953D01*
G01X691150D02*
X691922D01*
G01X685244D02*
X686016D01*
G01X687213D02*
X687985D01*
G01X681307D02*
X682079D01*
G01X683276D02*
X684048D01*
G01X679339D02*
X680111D01*
G01X675402D02*
X676174D01*
G01X677370D02*
X678142D01*
G01X671465D02*
X672237D01*
G01X673433D02*
X674205D01*
G01X669496D02*
X670268D01*
G01X711851Y511674D02*
X712559D01*
G01X713819D02*
X714528D01*
G01X707914D02*
X708622D01*
G01X709882D02*
X710591D01*
G01X705945D02*
X706654D01*
G01X702008D02*
X702717D01*
G01X703977D02*
X704685D01*
G01X698071D02*
X698780D01*
G01X700040D02*
X700748D01*
G01X696103D02*
X696811D01*
G01X692166D02*
X692874D01*
G01X694134D02*
X694843D01*
G01X688229D02*
X688937D01*
G01X690197D02*
X690906D01*
G01X686260D02*
X686969D01*
G01X682323D02*
X683032D01*
G01X684292D02*
X685000D01*
G01X678386D02*
X679095D01*
G01X680355D02*
X681063D01*
G01X676418D02*
X677126D01*
G01X672481D02*
X673189D01*
G01X674449D02*
X675158D01*
G01X670512D02*
X671221D01*
G01X670223Y511604D02*
X669541D01*
G01X672192D02*
X671510D01*
G01X674160D02*
X673478D01*
G01X676129D02*
X675447D01*
G01X678097D02*
X677415D01*
G01X680066D02*
X679384D01*
G01X682034D02*
X681352D01*
G01X684003D02*
X683321D01*
G01X685971D02*
X685289D01*
G01X687940D02*
X687258D01*
G01X689908D02*
X689226D01*
G01X691877D02*
X691195D01*
G01X693845D02*
X693163D01*
G01X695814D02*
X695132D01*
G01X697782D02*
X697100D01*
G01X699751D02*
X699069D01*
G01X701719D02*
X701037D01*
G01X703688D02*
X703006D01*
G01X705656D02*
X704974D01*
G01X707625D02*
X706943D01*
G01X709593D02*
X708911D01*
G01X711562D02*
X710880D01*
G01X713530D02*
X712848D01*
G01X671221Y511497D02*
X670512D01*
G01X673189D02*
X672481D01*
G01X675158D02*
X674449D01*
G01X677126D02*
X676418D01*
G01X679095D02*
X678386D01*
G01X681063D02*
X680355D01*
G01X683032D02*
X682323D01*
G01X685000D02*
X684292D01*
G01X686969D02*
X686260D01*
G01X688937D02*
X688229D01*
G01X690906D02*
X690197D01*
G01X692874D02*
X692166D01*
G01X694843D02*
X694134D01*
G01X696811D02*
X696103D01*
G01X698780D02*
X698071D01*
G01X700748D02*
X700040D01*
G01X702717D02*
X702008D01*
G01X704685D02*
X703977D01*
G01X706654D02*
X705945D01*
G01X708622D02*
X707914D01*
G01X710591D02*
X709882D01*
G01X712559D02*
X711851D01*
G01X714528D02*
X713819D01*
G01X670183Y510554D02*
X669582D01*
G01X672151D02*
X671550D01*
G01X674120D02*
X673519D01*
G01X676088D02*
X675487D01*
G01X678057D02*
X677456D01*
G01X680025D02*
X679424D01*
G01X681994D02*
X681393D01*
G01X683962D02*
X683361D01*
G01X685931D02*
X685330D01*
G01X687899D02*
X687298D01*
G01X689868D02*
X689267D01*
G01X691836D02*
X691235D01*
G01X693805D02*
X693204D01*
G01X695773D02*
X695172D01*
G01X697742D02*
X697141D01*
G01X699710D02*
X699109D01*
G01X701679D02*
X701078D01*
G01X703647D02*
X703046D01*
G01X705616D02*
X705015D01*
G01X707584D02*
X706983D01*
G01X709553D02*
X708952D01*
G01X711521D02*
X710920D01*
G01X713490D02*
X712889D01*
G01X671221Y510355D02*
X670512D01*
G01X673189D02*
X672481D01*
G01X675158D02*
X674449D01*
G01X677126D02*
X676418D01*
G01X679095D02*
X678386D01*
G01X681063D02*
X680355D01*
G01X683032D02*
X682323D01*
G01X685000D02*
X684292D01*
G01X686969D02*
X686260D01*
G01X688937D02*
X688229D01*
G01X690906D02*
X690197D01*
G01X692874D02*
X692166D01*
G01X694843D02*
X694134D01*
G01X696811D02*
X696103D01*
G01X698780D02*
X698071D01*
G01X700748D02*
X700040D01*
G01X702717D02*
X702008D01*
G01X704685D02*
X703977D01*
G01X706654D02*
X705945D01*
G01X708622D02*
X707914D01*
G01X710591D02*
X709882D01*
G01X712559D02*
X711851D01*
G01X714528D02*
X713819D01*
G01X665158Y510237D02*
X662992D01*
G01Y510040D02*
X749607D01*
G01X671221Y509095D02*
X670512D01*
G01X673189D02*
X672481D01*
G01X675158D02*
X674449D01*
G01X677126D02*
X676418D01*
G01X679095D02*
X678386D01*
G01X681063D02*
X680355D01*
G01X683032D02*
X682323D01*
G01X685000D02*
X684292D01*
G01X686969D02*
X686260D01*
G01X688937D02*
X688229D01*
G01X690906D02*
X690197D01*
G01X692874D02*
X692166D01*
G01X694843D02*
X694134D01*
G01X696811D02*
X696103D01*
G01X698780D02*
X698071D01*
G01X700748D02*
X700040D01*
G01X702717D02*
X702008D01*
G01X704685D02*
X703977D01*
G01X706654D02*
X705945D01*
G01X708622D02*
X707914D01*
G01X710591D02*
X709882D01*
G01X712559D02*
X711851D01*
G01X714528D02*
X713819D01*
G01X665453Y506103D02*
X662992D01*
G01X680053Y522014D02*
X679987Y521880D01*
G01X679790Y522215D02*
X679659Y521947D01*
G01X676313Y521143D02*
X676247Y521009D01*
G01X675000Y522349D02*
X674935Y522215D01*
G01X673097D02*
X673032Y522081D01*
G01X679134Y517716D02*
X678216Y515237D01*
G01X678937Y518386D02*
X677953Y515572D01*
G01X669554Y523622D02*
X668504Y520473D01*
G01X681365Y521143D02*
X681300Y520942D01*
G01X676378Y521344D02*
X676313Y521143D01*
G01X669160Y521277D02*
X668898Y520473D01*
G01X669817Y523354D02*
X669226Y521545D01*
G01X671260Y501731D02*
X670473D01*
G01X675197D02*
X674410D01*
G01X673229D02*
X672441D01*
G01X677166D02*
X676378D01*
G01X681103D02*
X680315D01*
G01X679134D02*
X678347D01*
G01X685040D02*
X684252D01*
G01X683071D02*
X682284D01*
G01X687008D02*
X686221D01*
G01X690945D02*
X690158D01*
G01X688977D02*
X688189D01*
G01X694882D02*
X694095D01*
G01X692914D02*
X692126D01*
G01X696851D02*
X696063D01*
G01X700788D02*
X700000D01*
G01X698819D02*
X698032D01*
G01X704725D02*
X703937D01*
G01X702756D02*
X701969D01*
G01X706693D02*
X705906D01*
G01X710630D02*
X709843D01*
G01X708662D02*
X707874D01*
G01X714567D02*
X713780D01*
G01X712599D02*
X711811D01*
G01X713780Y501182D02*
X714567D01*
G01X711811D02*
X712599D01*
G01X709843D02*
X710630D01*
G01X707874D02*
X708662D01*
G01X705906D02*
X706693D01*
G01X703937D02*
X704725D01*
G01X701969D02*
X702756D01*
G01X700000D02*
X700788D01*
G01X698032D02*
X698819D01*
G01X696063D02*
X696851D01*
G01X694095D02*
X694882D01*
G01X692126D02*
X692914D01*
G01X690158D02*
X690945D01*
G01X688189D02*
X688977D01*
G01X686221D02*
X687008D01*
G01X684252D02*
X685040D01*
G01X682284D02*
X683071D01*
G01X680315D02*
X681103D01*
G01X678347D02*
X679134D01*
G01X676378D02*
X677166D01*
G01X674410D02*
X675197D01*
G01X672441D02*
X673229D01*
G01X670473D02*
X671260D01*
G01X749607Y500591D02*
X662992D01*
G01X671063Y499213D02*
X670670D01*
G01X675000D02*
X674607D01*
G01X673032D02*
X672638D01*
G01X676969D02*
X676575D01*
G01X680906D02*
X680512D01*
G01X678937D02*
X678544D01*
G01X684843D02*
X684449D01*
G01X682874D02*
X682481D01*
G01X686811D02*
X686418D01*
G01X690748D02*
X690355D01*
G01X688780D02*
X688386D01*
G01X694685D02*
X694292D01*
G01X692717D02*
X692323D01*
G01X696654D02*
X696260D01*
G01X700591D02*
X700197D01*
G01X698622D02*
X698229D01*
G01X704528D02*
X704134D01*
G01X702559D02*
X702166D01*
G01X706496D02*
X706103D01*
G01X710433D02*
X710040D01*
G01X708465D02*
X708071D01*
G01X714370D02*
X713977D01*
G01X712402D02*
X712008D01*
G01X681103Y520808D02*
X680643Y520741D01*
G01X681168Y520540D02*
X680709Y520473D01*
G01Y522617D02*
X680315Y522550D01*
G01X675525Y522617D02*
X675263Y522550D01*
G01X675525Y522282D02*
X675263Y522215D01*
G01X678150Y522617D02*
X677888Y522550D01*
G01X678150Y522349D02*
X677888Y522282D01*
G01X686549Y520942D02*
X686418Y520741D01*
G01X686286Y521143D02*
X686155Y520942D01*
G01X685105Y522148D02*
X684974Y521947D01*
G01X684843Y522349D02*
X684712Y522148D01*
G01X675066Y522081D02*
X674935Y521880D01*
G01X680643Y522349D02*
X680381Y522282D01*
G01X676050Y520875D02*
X675788Y520808D01*
G01X683137Y522617D02*
X682874Y522550D01*
G01X683137Y522349D02*
X682874Y522282D01*
G01X676181Y520540D02*
X675919Y520473D01*
G01X685368Y522617D02*
X685105Y522550D01*
G01X685499Y522349D02*
X685237Y522282D01*
G01X686024Y520808D02*
X685762Y520741D01*
G01X686155Y520540D02*
X685893Y520473D01*
G01X686418Y520741D02*
X686286Y520607D01*
G01X686155Y520942D02*
X686024Y520808D01*
G01X685237Y522282D02*
X685105Y522148D01*
G01X684974Y522483D02*
X684843Y522349D01*
G01X681628Y520875D02*
X681431Y520674D01*
G01X682678Y522148D02*
X682546Y522014D01*
G01X682678Y522416D02*
X682546Y522282D01*
G01X680250Y522215D02*
X680053Y522014D01*
G01X679922Y522349D02*
X679790Y522215D01*
G01X677691Y522148D02*
X677559Y522014D01*
G01X677691Y522416D02*
X677559Y522282D01*
G01X675132Y522483D02*
X675000Y522349D01*
G01X673163Y522282D02*
X673097Y522215D01*
G01X673163Y522550D02*
X672966Y522349D01*
G01X672113Y522282D02*
X671982Y522148D01*
G01X672113Y522550D02*
X671982Y522416D01*
G01X676641Y521009D02*
X676378Y520674D01*
G01X681300Y520942D02*
X681103Y520808D01*
G01X686286Y520607D02*
X686155Y520540D01*
G01X681431Y520674D02*
X681168Y520540D01*
G01X685105Y522550D02*
X684974Y522483D01*
G01X680381Y522282D02*
X680250Y522215D01*
G01X675263Y522550D02*
X675132Y522483D01*
G01X673294Y522349D02*
X673163Y522282D01*
G01X682874D02*
X682678Y522148D01*
G01X682874Y522550D02*
X682678Y522416D01*
G01X680118Y522483D02*
X679922Y522349D01*
G01X676378Y520674D02*
X676181Y520540D01*
G01X676247Y521009D02*
X676050Y520875D01*
G01X677888Y522282D02*
X677691Y522148D01*
G01X677888Y522550D02*
X677691Y522416D01*
G01X675263Y522215D02*
X675066Y522081D01*
G01X680315Y522550D02*
X680118Y522483D01*
G01X673360Y522617D02*
X673163Y522550D01*
G01X672310Y522349D02*
X672113Y522282D01*
G01X672310Y522617D02*
X672113Y522550D01*
G01X685655Y762380D02*
Y765180D01*
G01X654160Y762380D02*
Y765180D01*
G01X738702Y-714465D02*
Y-733402D01*
G01X727028Y-524387D02*
Y-614517D01*
G01X730696Y-569705D02*
X1144351D01*
G01X716493Y513302D02*
X716496Y513274D01*
G01X716481Y513328D02*
X716493Y513302D01*
G01X716463Y513352D02*
X716481Y513328D01*
G01X716439Y513373D02*
X716463Y513352D01*
G01X716409Y513391D02*
X716439Y513373D01*
G01X716375Y513404D02*
X716409Y513391D01*
G01X716338Y513412D02*
X716375Y513404D01*
G01X716300Y513414D02*
X716338Y513412D01*
G01X718461Y513302D02*
X718465Y513274D01*
G01X718450Y513328D02*
X718461Y513302D01*
G01X718432Y513352D02*
X718450Y513328D01*
G01X718407Y513373D02*
X718432Y513352D01*
G01X718377Y513391D02*
X718407Y513373D01*
G01X718343Y513404D02*
X718377Y513391D01*
G01X718306Y513412D02*
X718343Y513404D01*
G01X718268Y513414D02*
X718306Y513412D01*
G01X720430Y513302D02*
X720433Y513274D01*
G01X720418Y513328D02*
X720430Y513302D01*
G01X720400Y513352D02*
X720418Y513328D01*
G01X720376Y513373D02*
X720400Y513352D01*
G01X720346Y513391D02*
X720376Y513373D01*
G01X720312Y513404D02*
X720346Y513391D01*
G01X720275Y513412D02*
X720312Y513404D01*
G01X720237Y513414D02*
X720275Y513412D01*
G01X722398Y513302D02*
X722402Y513274D01*
G01X722387Y513328D02*
X722398Y513302D01*
G01X722369Y513352D02*
X722387Y513328D01*
G01X722344Y513373D02*
X722369Y513352D01*
G01X722314Y513391D02*
X722344Y513373D01*
G01X722280Y513404D02*
X722314Y513391D01*
G01X722243Y513412D02*
X722280Y513404D01*
G01X722205Y513414D02*
X722243Y513412D01*
G01X724367Y513302D02*
X724370Y513274D01*
G01X724355Y513328D02*
X724367Y513302D01*
G01X724337Y513352D02*
X724355Y513328D01*
G01X724313Y513373D02*
X724337Y513352D01*
G01X724283Y513391D02*
X724313Y513373D01*
G01X724249Y513404D02*
X724283Y513391D01*
G01X724212Y513412D02*
X724249Y513404D01*
G01X724174Y513414D02*
X724212Y513412D01*
G01X726335Y513302D02*
X726339Y513274D01*
G01X726324Y513328D02*
X726335Y513302D01*
G01X726306Y513352D02*
X726324Y513328D01*
G01X726281Y513373D02*
X726306Y513352D01*
G01X726251Y513391D02*
X726281Y513373D01*
G01X726217Y513404D02*
X726251Y513391D01*
G01X726180Y513412D02*
X726217Y513404D01*
G01X726142Y513414D02*
X726180Y513412D01*
G01X736178Y513302D02*
X736181Y513274D01*
G01X736166Y513328D02*
X736178Y513302D01*
G01X736148Y513352D02*
X736166Y513328D01*
G01X736124Y513373D02*
X736148Y513352D01*
G01X736094Y513391D02*
X736124Y513373D01*
G01X736060Y513404D02*
X736094Y513391D01*
G01X736023Y513412D02*
X736060Y513404D01*
G01X735985Y513414D02*
X736023Y513412D01*
G01X738146Y513302D02*
X738150Y513274D01*
G01X738135Y513328D02*
X738146Y513302D01*
G01X738117Y513352D02*
X738135Y513328D01*
G01X738092Y513373D02*
X738117Y513352D01*
G01X738062Y513391D02*
X738092Y513373D01*
G01X738028Y513404D02*
X738062Y513391D01*
G01X737991Y513412D02*
X738028Y513404D01*
G01X737953Y513414D02*
X737991Y513412D01*
G01X740115Y513302D02*
X740118Y513274D01*
G01X740103Y513328D02*
X740115Y513302D01*
G01X740085Y513352D02*
X740103Y513328D01*
G01X740061Y513373D02*
X740085Y513352D01*
G01X740031Y513391D02*
X740061Y513373D01*
G01X739997Y513404D02*
X740031Y513391D01*
G01X739960Y513412D02*
X739997Y513404D01*
G01X739922Y513414D02*
X739960Y513412D01*
G01X742083Y513302D02*
X742087Y513274D01*
G01X742072Y513328D02*
X742083Y513302D01*
G01X742054Y513352D02*
X742072Y513328D01*
G01X742029Y513373D02*
X742054Y513352D01*
G01X741999Y513391D02*
X742029Y513373D01*
G01X741965Y513404D02*
X741999Y513391D01*
G01X741928Y513412D02*
X741965Y513404D01*
G01X741890Y513414D02*
X741928Y513412D01*
G01X769642Y513302D02*
X769646Y513274D01*
G01X769631Y513328D02*
X769642Y513302D01*
G01X769613Y513352D02*
X769631Y513328D01*
G01X769588Y513373D02*
X769613Y513352D01*
G01X769558Y513391D02*
X769588Y513373D01*
G01X769524Y513404D02*
X769558Y513391D01*
G01X769487Y513412D02*
X769524Y513404D01*
G01X769449Y513414D02*
X769487Y513412D01*
G01X771611Y513302D02*
X771615Y513274D01*
G01X771599Y513328D02*
X771611Y513302D01*
G01X771581Y513352D02*
X771599Y513328D01*
G01X771557Y513373D02*
X771581Y513352D01*
G01X771527Y513391D02*
X771557Y513373D01*
G01X771493Y513404D02*
X771527Y513391D01*
G01X771456Y513412D02*
X771493Y513404D01*
G01X771418Y513414D02*
X771456Y513412D01*
G01X773579Y513302D02*
X773583Y513274D01*
G01X773568Y513328D02*
X773579Y513302D01*
G01X773550Y513352D02*
X773568Y513328D01*
G01X773525Y513373D02*
X773550Y513352D01*
G01X773495Y513391D02*
X773525Y513373D01*
G01X773461Y513404D02*
X773495Y513391D01*
G01X773424Y513412D02*
X773461Y513404D01*
G01X773386Y513414D02*
X773424Y513412D01*
G01X775548Y513302D02*
X775552Y513274D01*
G01X775536Y513328D02*
X775548Y513302D01*
G01X775518Y513352D02*
X775536Y513328D01*
G01X775494Y513373D02*
X775518Y513352D01*
G01X775464Y513391D02*
X775494Y513373D01*
G01X775430Y513404D02*
X775464Y513391D01*
G01X775393Y513412D02*
X775430Y513404D01*
G01X775355Y513414D02*
X775393Y513412D01*
G01X777516Y513302D02*
X777520Y513274D01*
G01X777505Y513328D02*
X777516Y513302D01*
G01X777487Y513352D02*
X777505Y513328D01*
G01X777462Y513373D02*
X777487Y513352D01*
G01X777432Y513391D02*
X777462Y513373D01*
G01X777398Y513404D02*
X777432Y513391D01*
G01X777361Y513412D02*
X777398Y513404D01*
G01X777323Y513414D02*
X777361Y513412D01*
G01X779485Y513302D02*
X779489Y513274D01*
G01X779473Y513328D02*
X779485Y513302D01*
G01X779455Y513352D02*
X779473Y513328D01*
G01X779431Y513373D02*
X779455Y513352D01*
G01X779401Y513391D02*
X779431Y513373D01*
G01X779367Y513404D02*
X779401Y513391D01*
G01X779330Y513412D02*
X779367Y513404D01*
G01X779292Y513414D02*
X779330Y513412D01*
G01X781453Y513302D02*
X781457Y513274D01*
G01X781442Y513328D02*
X781453Y513302D01*
G01X781424Y513352D02*
X781442Y513328D01*
G01X781399Y513373D02*
X781424Y513352D01*
G01X781369Y513391D02*
X781399Y513373D01*
G01X781335Y513404D02*
X781369Y513391D01*
G01X781298Y513412D02*
X781335Y513404D01*
G01X781260Y513414D02*
X781298Y513412D01*
G01X783422Y513302D02*
X783426Y513274D01*
G01X783410Y513328D02*
X783422Y513302D01*
G01X783392Y513352D02*
X783410Y513328D01*
G01X783368Y513373D02*
X783392Y513352D01*
G01X783338Y513391D02*
X783368Y513373D01*
G01X783304Y513404D02*
X783338Y513391D01*
G01X783267Y513412D02*
X783304Y513404D01*
G01X783229Y513414D02*
X783267Y513412D01*
G01X785390Y513302D02*
X785394Y513274D01*
G01X785379Y513328D02*
X785390Y513302D01*
G01X785361Y513352D02*
X785379Y513328D01*
G01X785336Y513373D02*
X785361Y513352D01*
G01X785306Y513391D02*
X785336Y513373D01*
G01X785272Y513404D02*
X785306Y513391D01*
G01X785235Y513412D02*
X785272Y513404D01*
G01X785197Y513414D02*
X785235Y513412D01*
G01X716489Y513069D02*
X716496Y512993D01*
G01X716470Y513132D02*
X716489Y513069D01*
G01X716443Y513183D02*
X716470Y513132D01*
G01X716410Y513222D02*
X716443Y513183D01*
G01X716375Y513249D02*
X716410Y513222D01*
G01X716338Y513265D02*
X716375Y513249D01*
G01X716300Y513270D02*
X716338Y513265D01*
G01X718457Y513069D02*
X718465Y512993D01*
G01X718438Y513132D02*
X718457Y513069D01*
G01X718411Y513183D02*
X718438Y513132D01*
G01X718379Y513222D02*
X718411Y513183D01*
G01X718343Y513249D02*
X718379Y513222D01*
G01X718306Y513265D02*
X718343Y513249D01*
G01X718268Y513270D02*
X718306Y513265D01*
G01X720426Y513069D02*
X720433Y512993D01*
G01X720407Y513132D02*
X720426Y513069D01*
G01X720380Y513183D02*
X720407Y513132D01*
G01X720347Y513222D02*
X720380Y513183D01*
G01X720312Y513249D02*
X720347Y513222D01*
G01X720275Y513265D02*
X720312Y513249D01*
G01X720237Y513270D02*
X720275Y513265D01*
G01X722395Y513069D02*
X722402Y512993D01*
G01X722375Y513132D02*
X722395Y513069D01*
G01X722348Y513183D02*
X722375Y513132D01*
G01X722316Y513222D02*
X722348Y513183D01*
G01X722280Y513249D02*
X722316Y513222D01*
G01X722243Y513265D02*
X722280Y513249D01*
G01X722205Y513270D02*
X722243Y513265D01*
G01X724363Y513069D02*
X724370Y512993D01*
G01X724344Y513132D02*
X724363Y513069D01*
G01X724317Y513183D02*
X724344Y513132D01*
G01X724284Y513222D02*
X724317Y513183D01*
G01X724249Y513249D02*
X724284Y513222D01*
G01X724212Y513265D02*
X724249Y513249D01*
G01X724174Y513270D02*
X724212Y513265D01*
G01X726332Y513069D02*
X726339Y512993D01*
G01X726312Y513132D02*
X726332Y513069D01*
G01X726285Y513183D02*
X726312Y513132D01*
G01X726253Y513222D02*
X726285Y513183D01*
G01X726217Y513249D02*
X726253Y513222D01*
G01X726180Y513265D02*
X726217Y513249D01*
G01X726142Y513270D02*
X726180Y513265D01*
G01X736174Y513069D02*
X736181Y512993D01*
G01X736155Y513132D02*
X736174Y513069D01*
G01X736128Y513183D02*
X736155Y513132D01*
G01X736095Y513222D02*
X736128Y513183D01*
G01X736060Y513249D02*
X736095Y513222D01*
G01X736023Y513265D02*
X736060Y513249D01*
G01X735985Y513270D02*
X736023Y513265D01*
G01X738143Y513069D02*
X738150Y512993D01*
G01X738123Y513132D02*
X738143Y513069D01*
G01X738096Y513183D02*
X738123Y513132D01*
G01X738064Y513222D02*
X738096Y513183D01*
G01X738028Y513249D02*
X738064Y513222D01*
G01X737991Y513265D02*
X738028Y513249D01*
G01X737953Y513270D02*
X737991Y513265D01*
G01X740111Y513069D02*
X740118Y512993D01*
G01X740092Y513132D02*
X740111Y513069D01*
G01X740065Y513183D02*
X740092Y513132D01*
G01X740032Y513222D02*
X740065Y513183D01*
G01X739997Y513249D02*
X740032Y513222D01*
G01X739960Y513265D02*
X739997Y513249D01*
G01X739922Y513270D02*
X739960Y513265D01*
G01X742080Y513069D02*
X742087Y512993D01*
G01X742060Y513132D02*
X742080Y513069D01*
G01X742033Y513183D02*
X742060Y513132D01*
G01X742001Y513222D02*
X742033Y513183D01*
G01X741965Y513249D02*
X742001Y513222D01*
G01X741928Y513265D02*
X741965Y513249D01*
G01X741890Y513270D02*
X741928Y513265D01*
G01X769639Y513069D02*
X769646Y512993D01*
G01X769620Y513132D02*
X769639Y513069D01*
G01X769592Y513183D02*
X769620Y513132D01*
G01X769560Y513222D02*
X769592Y513183D01*
G01X769524Y513249D02*
X769560Y513222D01*
G01X769488Y513265D02*
X769524Y513249D01*
G01X769449Y513270D02*
X769488Y513265D01*
G01X771607Y513069D02*
X771615Y512993D01*
G01X771588Y513132D02*
X771607Y513069D01*
G01X771561Y513183D02*
X771588Y513132D01*
G01X771528Y513222D02*
X771561Y513183D01*
G01X771493Y513249D02*
X771528Y513222D01*
G01X771456Y513265D02*
X771493Y513249D01*
G01X771418Y513270D02*
X771456Y513265D01*
G01X773576Y513069D02*
X773583Y512993D01*
G01X773557Y513132D02*
X773576Y513069D01*
G01X773529Y513183D02*
X773557Y513132D01*
G01X773497Y513222D02*
X773529Y513183D01*
G01X773461Y513249D02*
X773497Y513222D01*
G01X773425Y513265D02*
X773461Y513249D01*
G01X773386Y513270D02*
X773425Y513265D01*
G01X775544Y513069D02*
X775552Y512993D01*
G01X775525Y513132D02*
X775544Y513069D01*
G01X775498Y513183D02*
X775525Y513132D01*
G01X775465Y513222D02*
X775498Y513183D01*
G01X775430Y513249D02*
X775465Y513222D01*
G01X775393Y513265D02*
X775430Y513249D01*
G01X775355Y513270D02*
X775393Y513265D01*
G01X777513Y513069D02*
X777520Y512993D01*
G01X777494Y513132D02*
X777513Y513069D01*
G01X777466Y513183D02*
X777494Y513132D01*
G01X777434Y513222D02*
X777466Y513183D01*
G01X777398Y513249D02*
X777434Y513222D01*
G01X777362Y513265D02*
X777398Y513249D01*
G01X777323Y513270D02*
X777362Y513265D01*
G01X779481Y513069D02*
X779489Y512993D01*
G01X779462Y513132D02*
X779481Y513069D01*
G01X779435Y513183D02*
X779462Y513132D01*
G01X779402Y513222D02*
X779435Y513183D01*
G01X779367Y513249D02*
X779402Y513222D01*
G01X779330Y513265D02*
X779367Y513249D01*
G01X779292Y513270D02*
X779330Y513265D01*
G01X781450Y513069D02*
X781457Y512993D01*
G01X781431Y513132D02*
X781450Y513069D01*
G01X781403Y513183D02*
X781431Y513132D01*
G01X781371Y513222D02*
X781403Y513183D01*
G01X781335Y513249D02*
X781371Y513222D01*
G01X781299Y513265D02*
X781335Y513249D01*
G01X781260Y513270D02*
X781299Y513265D01*
G01X783418Y513069D02*
X783426Y512993D01*
G01X783399Y513132D02*
X783418Y513069D01*
G01X783372Y513183D02*
X783399Y513132D01*
G01X783339Y513222D02*
X783372Y513183D01*
G01X783304Y513249D02*
X783339Y513222D01*
G01X783267Y513265D02*
X783304Y513249D01*
G01X783229Y513270D02*
X783267Y513265D01*
G01X785387Y513069D02*
X785394Y512993D01*
G01X785368Y513132D02*
X785387Y513069D01*
G01X785340Y513183D02*
X785368Y513132D01*
G01X785308Y513222D02*
X785340Y513183D01*
G01X785272Y513249D02*
X785308Y513222D01*
G01X785236Y513265D02*
X785272Y513249D01*
G01X785197Y513270D02*
X785236Y513265D01*
G01X715946D02*
X715985Y513270D01*
G01X715909Y513249D02*
X715946Y513265D01*
G01X715874Y513222D02*
X715909Y513249D01*
G01X715841Y513183D02*
X715874Y513222D01*
G01X715814Y513132D02*
X715841Y513183D01*
G01X715795Y513069D02*
X715814Y513132D01*
G01X715788Y512993D02*
X715795Y513069D01*
G01X717915Y513265D02*
X717953Y513270D01*
G01X717878Y513249D02*
X717915Y513265D01*
G01X717843Y513222D02*
X717878Y513249D01*
G01X717810Y513183D02*
X717843Y513222D01*
G01X717783Y513132D02*
X717810Y513183D01*
G01X717764Y513069D02*
X717783Y513132D01*
G01X717756Y512993D02*
X717764Y513069D01*
G01X719883Y513265D02*
X719922Y513270D01*
G01X719846Y513249D02*
X719883Y513265D01*
G01X719811Y513222D02*
X719846Y513249D01*
G01X719778Y513183D02*
X719811Y513222D01*
G01X719751Y513132D02*
X719778Y513183D01*
G01X719732Y513069D02*
X719751Y513132D01*
G01X719725Y512993D02*
X719732Y513069D01*
G01X721852Y513265D02*
X721890Y513270D01*
G01X721815Y513249D02*
X721852Y513265D01*
G01X721780Y513222D02*
X721815Y513249D01*
G01X721747Y513183D02*
X721780Y513222D01*
G01X721720Y513132D02*
X721747Y513183D01*
G01X721701Y513069D02*
X721720Y513132D01*
G01X721693Y512993D02*
X721701Y513069D01*
G01X715946Y513412D02*
X715985Y513414D01*
G01X715909Y513404D02*
X715946Y513412D01*
G01X715875Y513391D02*
X715909Y513404D01*
G01X715845Y513373D02*
X715875Y513391D01*
G01X715821Y513352D02*
X715845Y513373D01*
G01X715803Y513328D02*
X715821Y513352D01*
G01X715792Y513302D02*
X715803Y513328D01*
G01X715788Y513274D02*
X715792Y513302D01*
G01X717914Y513412D02*
X717953Y513414D01*
G01X717877Y513404D02*
X717914Y513412D01*
G01X717844Y513391D02*
X717877Y513404D01*
G01X717814Y513373D02*
X717844Y513391D01*
G01X717789Y513352D02*
X717814Y513373D01*
G01X717771Y513328D02*
X717789Y513352D01*
G01X717760Y513302D02*
X717771Y513328D01*
G01X717756Y513274D02*
X717760Y513302D01*
G01X719883Y513412D02*
X719922Y513414D01*
G01X719846Y513404D02*
X719883Y513412D01*
G01X719812Y513391D02*
X719846Y513404D01*
G01X719782Y513373D02*
X719812Y513391D01*
G01X719758Y513352D02*
X719782Y513373D01*
G01X719740Y513328D02*
X719758Y513352D01*
G01X719729Y513302D02*
X719740Y513328D01*
G01X719725Y513274D02*
X719729Y513302D01*
G01X721851Y513412D02*
X721890Y513414D01*
G01X721814Y513404D02*
X721851Y513412D01*
G01X721781Y513391D02*
X721814Y513404D01*
G01X721751Y513373D02*
X721781Y513391D01*
G01X721726Y513352D02*
X721751Y513373D01*
G01X721708Y513328D02*
X721726Y513352D01*
G01X721697Y513302D02*
X721708Y513328D01*
G01X721693Y513274D02*
X721697Y513302D01*
G01X723820Y513412D02*
X723859Y513414D01*
G01X723783Y513404D02*
X723820Y513412D01*
G01X723749Y513391D02*
X723783Y513404D01*
G01X723719Y513373D02*
X723749Y513391D01*
G01X723695Y513352D02*
X723719Y513373D01*
G01X723677Y513328D02*
X723695Y513352D01*
G01X723666Y513302D02*
X723677Y513328D01*
G01X723662Y513274D02*
X723666Y513302D01*
G01X725788Y513412D02*
X725827Y513414D01*
G01X725751Y513404D02*
X725788Y513412D01*
G01X725718Y513391D02*
X725751Y513404D01*
G01X725688Y513373D02*
X725718Y513391D01*
G01X725663Y513352D02*
X725688Y513373D01*
G01X725645Y513328D02*
X725663Y513352D01*
G01X725634Y513302D02*
X725645Y513328D01*
G01X725630Y513274D02*
X725634Y513302D01*
G01X723820Y513265D02*
X723859Y513270D01*
G01X723783Y513249D02*
X723820Y513265D01*
G01X723748Y513222D02*
X723783Y513249D01*
G01X723715Y513183D02*
X723748Y513222D01*
G01X723688Y513132D02*
X723715Y513183D01*
G01X723669Y513069D02*
X723688Y513132D01*
G01X723662Y512993D02*
X723669Y513069D01*
G01X725789Y513265D02*
X725827Y513270D01*
G01X725752Y513249D02*
X725789Y513265D01*
G01X725717Y513222D02*
X725752Y513249D01*
G01X725684Y513183D02*
X725717Y513222D01*
G01X725657Y513132D02*
X725684Y513183D01*
G01X725638Y513069D02*
X725657Y513132D01*
G01X725630Y512993D02*
X725638Y513069D01*
G01X735631Y513265D02*
X735670Y513270D01*
G01X735594Y513249D02*
X735631Y513265D01*
G01X735559Y513222D02*
X735594Y513249D01*
G01X735527Y513183D02*
X735559Y513222D01*
G01X735499Y513132D02*
X735527Y513183D01*
G01X735480Y513069D02*
X735499Y513132D01*
G01X735473Y512993D02*
X735480Y513069D01*
G01X737600Y513265D02*
X737638Y513270D01*
G01X737563Y513249D02*
X737600Y513265D01*
G01X737528Y513222D02*
X737563Y513249D01*
G01X737495Y513183D02*
X737528Y513222D01*
G01X737468Y513132D02*
X737495Y513183D01*
G01X737449Y513069D02*
X737468Y513132D01*
G01X737441Y512993D02*
X737449Y513069D01*
G01X739568Y513265D02*
X739607Y513270D01*
G01X739531Y513249D02*
X739568Y513265D01*
G01X739496Y513222D02*
X739531Y513249D01*
G01X739464Y513183D02*
X739496Y513222D01*
G01X739436Y513132D02*
X739464Y513183D01*
G01X739417Y513069D02*
X739436Y513132D01*
G01X739410Y512993D02*
X739417Y513069D01*
G01X741537Y513265D02*
X741575Y513270D01*
G01X741500Y513249D02*
X741537Y513265D01*
G01X741465Y513222D02*
X741500Y513249D01*
G01X741432Y513183D02*
X741465Y513222D01*
G01X741405Y513132D02*
X741432Y513183D01*
G01X741386Y513069D02*
X741405Y513132D01*
G01X741378Y512993D02*
X741386Y513069D01*
G01X735631Y513412D02*
X735670Y513414D01*
G01X735594Y513404D02*
X735631Y513412D01*
G01X735560Y513391D02*
X735594Y513404D01*
G01X735530Y513373D02*
X735560Y513391D01*
G01X735506Y513352D02*
X735530Y513373D01*
G01X735488Y513328D02*
X735506Y513352D01*
G01X735477Y513302D02*
X735488Y513328D01*
G01X735473Y513274D02*
X735477Y513302D01*
G01X737599Y513412D02*
X737638Y513414D01*
G01X737563Y513404D02*
X737599Y513412D01*
G01X737529Y513391D02*
X737563Y513404D01*
G01X737499Y513373D02*
X737529Y513391D01*
G01X737474Y513352D02*
X737499Y513373D01*
G01X737456Y513328D02*
X737474Y513352D01*
G01X737445Y513302D02*
X737456Y513328D01*
G01X737441Y513274D02*
X737445Y513302D01*
G01X739568Y513412D02*
X739607Y513414D01*
G01X739531Y513404D02*
X739568Y513412D01*
G01X739497Y513391D02*
X739531Y513404D01*
G01X739467Y513373D02*
X739497Y513391D01*
G01X739443Y513352D02*
X739467Y513373D01*
G01X739425Y513328D02*
X739443Y513352D01*
G01X739414Y513302D02*
X739425Y513328D01*
G01X739410Y513274D02*
X739414Y513302D01*
G01X741536Y513412D02*
X741575Y513414D01*
G01X741500Y513404D02*
X741536Y513412D01*
G01X741466Y513391D02*
X741500Y513404D01*
G01X741436Y513373D02*
X741466Y513391D01*
G01X741411Y513352D02*
X741436Y513373D01*
G01X741393Y513328D02*
X741411Y513352D01*
G01X741382Y513302D02*
X741393Y513328D01*
G01X741378Y513274D02*
X741382Y513302D01*
G01X769095Y513412D02*
X769134Y513414D01*
G01X769059Y513404D02*
X769095Y513412D01*
G01X769025Y513391D02*
X769059Y513404D01*
G01X768995Y513373D02*
X769025Y513391D01*
G01X768970Y513352D02*
X768995Y513373D01*
G01X768952Y513328D02*
X768970Y513352D01*
G01X768941Y513302D02*
X768952Y513328D01*
G01X768937Y513274D02*
X768941Y513302D01*
G01X769096Y513265D02*
X769134Y513270D01*
G01X769059Y513249D02*
X769096Y513265D01*
G01X769024Y513222D02*
X769059Y513249D01*
G01X768991Y513183D02*
X769024Y513222D01*
G01X768964Y513132D02*
X768991Y513183D01*
G01X768945Y513069D02*
X768964Y513132D01*
G01X768937Y512993D02*
X768945Y513069D01*
G01X771064Y513265D02*
X771103Y513270D01*
G01X771027Y513249D02*
X771064Y513265D01*
G01X770992Y513222D02*
X771027Y513249D01*
G01X770960Y513183D02*
X770992Y513222D01*
G01X770932Y513132D02*
X770960Y513183D01*
G01X770913Y513069D02*
X770932Y513132D01*
G01X770906Y512993D02*
X770913Y513069D01*
G01X773033Y513265D02*
X773071Y513270D01*
G01X772996Y513249D02*
X773033Y513265D01*
G01X772961Y513222D02*
X772996Y513249D01*
G01X772928Y513183D02*
X772961Y513222D01*
G01X772901Y513132D02*
X772928Y513183D01*
G01X772882Y513069D02*
X772901Y513132D01*
G01X772874Y512993D02*
X772882Y513069D01*
G01X775001Y513265D02*
X775040Y513270D01*
G01X774965Y513249D02*
X775001Y513265D01*
G01X774929Y513222D02*
X774965Y513249D01*
G01X774897Y513183D02*
X774929Y513222D01*
G01X774869Y513132D02*
X774897Y513183D01*
G01X774850Y513069D02*
X774869Y513132D01*
G01X774843Y512993D02*
X774850Y513069D01*
G01X776970Y513265D02*
X777008Y513270D01*
G01X776933Y513249D02*
X776970Y513265D01*
G01X776898Y513222D02*
X776933Y513249D01*
G01X776865Y513183D02*
X776898Y513222D01*
G01X776838Y513132D02*
X776865Y513183D01*
G01X776819Y513069D02*
X776838Y513132D01*
G01X776811Y512993D02*
X776819Y513069D01*
G01X778938Y513265D02*
X778977Y513270D01*
G01X778902Y513249D02*
X778938Y513265D01*
G01X778866Y513222D02*
X778902Y513249D01*
G01X778834Y513183D02*
X778866Y513222D01*
G01X778806Y513132D02*
X778834Y513183D01*
G01X778787Y513069D02*
X778806Y513132D01*
G01X778780Y512993D02*
X778787Y513069D01*
G01X780907Y513265D02*
X780945Y513270D01*
G01X780870Y513249D02*
X780907Y513265D01*
G01X780835Y513222D02*
X780870Y513249D01*
G01X780802Y513183D02*
X780835Y513222D01*
G01X780775Y513132D02*
X780802Y513183D01*
G01X780756Y513069D02*
X780775Y513132D01*
G01X780748Y512993D02*
X780756Y513069D01*
G01X782875Y513265D02*
X782914Y513270D01*
G01X782839Y513249D02*
X782875Y513265D01*
G01X782803Y513222D02*
X782839Y513249D01*
G01X782771Y513183D02*
X782803Y513222D01*
G01X782743Y513132D02*
X782771Y513183D01*
G01X782724Y513069D02*
X782743Y513132D01*
G01X782717Y512993D02*
X782724Y513069D01*
G01X784844Y513265D02*
X784882Y513270D01*
G01X784807Y513249D02*
X784844Y513265D01*
G01X784772Y513222D02*
X784807Y513249D01*
G01X784739Y513183D02*
X784772Y513222D01*
G01X784712Y513132D02*
X784739Y513183D01*
G01X784693Y513069D02*
X784712Y513132D01*
G01X784685Y512993D02*
X784693Y513069D01*
G01X786708Y513183D02*
X786740Y513222D01*
G01X786680Y513132D02*
X786708Y513183D01*
G01X786661Y513069D02*
X786680Y513132D01*
G01X771064Y513412D02*
X771103Y513414D01*
G01X771027Y513404D02*
X771064Y513412D01*
G01X770993Y513391D02*
X771027Y513404D01*
G01X770964Y513373D02*
X770993Y513391D01*
G01X770939Y513352D02*
X770964Y513373D01*
G01X770921Y513328D02*
X770939Y513352D01*
G01X770910Y513302D02*
X770921Y513328D01*
G01X770906Y513274D02*
X770910Y513302D01*
G01X773032Y513412D02*
X773071Y513414D01*
G01X772996Y513404D02*
X773032Y513412D01*
G01X772962Y513391D02*
X772996Y513404D01*
G01X772932Y513373D02*
X772962Y513391D01*
G01X772907Y513352D02*
X772932Y513373D01*
G01X772889Y513328D02*
X772907Y513352D01*
G01X772878Y513302D02*
X772889Y513328D01*
G01X772874Y513274D02*
X772878Y513302D01*
G01X775001Y513412D02*
X775040Y513414D01*
G01X774964Y513404D02*
X775001Y513412D01*
G01X774930Y513391D02*
X774964Y513404D01*
G01X774901Y513373D02*
X774930Y513391D01*
G01X774876Y513352D02*
X774901Y513373D01*
G01X774858Y513328D02*
X774876Y513352D01*
G01X774847Y513302D02*
X774858Y513328D01*
G01X774843Y513274D02*
X774847Y513302D01*
G01X776969Y513412D02*
X777008Y513414D01*
G01X776933Y513404D02*
X776969Y513412D01*
G01X776899Y513391D02*
X776933Y513404D01*
G01X776869Y513373D02*
X776899Y513391D01*
G01X776844Y513352D02*
X776869Y513373D01*
G01X776826Y513328D02*
X776844Y513352D01*
G01X776815Y513302D02*
X776826Y513328D01*
G01X776811Y513274D02*
X776815Y513302D01*
G01X778938Y513412D02*
X778977Y513414D01*
G01X778901Y513404D02*
X778938Y513412D01*
G01X778867Y513391D02*
X778901Y513404D01*
G01X778838Y513373D02*
X778867Y513391D01*
G01X778813Y513352D02*
X778838Y513373D01*
G01X778795Y513328D02*
X778813Y513352D01*
G01X778784Y513302D02*
X778795Y513328D01*
G01X778780Y513274D02*
X778784Y513302D01*
G01X780906Y513412D02*
X780945Y513414D01*
G01X780870Y513404D02*
X780906Y513412D01*
G01X780836Y513391D02*
X780870Y513404D01*
G01X780806Y513373D02*
X780836Y513391D01*
G01X780781Y513352D02*
X780806Y513373D01*
G01X780763Y513328D02*
X780781Y513352D01*
G01X780752Y513302D02*
X780763Y513328D01*
G01X780748Y513274D02*
X780752Y513302D01*
G01X782875Y513412D02*
X782914Y513414D01*
G01X782838Y513404D02*
X782875Y513412D01*
G01X782804Y513391D02*
X782838Y513404D01*
G01X782775Y513373D02*
X782804Y513391D01*
G01X782750Y513352D02*
X782775Y513373D01*
G01X782732Y513328D02*
X782750Y513352D01*
G01X782721Y513302D02*
X782732Y513328D01*
G01X782717Y513274D02*
X782721Y513302D01*
G01X784843Y513412D02*
X784882Y513414D01*
G01X784807Y513404D02*
X784843Y513412D01*
G01X784773Y513391D02*
X784807Y513404D01*
G01X784743Y513373D02*
X784773Y513391D01*
G01X784718Y513352D02*
X784743Y513373D01*
G01X784700Y513328D02*
X784718Y513352D01*
G01X784689Y513302D02*
X784700Y513328D01*
G01X784685Y513274D02*
X784689Y513302D01*
G01X786687Y513352D02*
X786712Y513373D01*
G01X786669Y513328D02*
X786687Y513352D01*
G01X786658Y513302D02*
X786669Y513328D01*
G01X785827Y531183D02*
G03X785630Y530986I0J-197D01*
G01X786418D02*
G03X786221Y531183I-197J0D01*
G01X783859D02*
G03X783662Y530986I0J-197D01*
G01X784449D02*
G03X784252Y531183I-197J0D01*
G01X781890D02*
G03X781693Y530986I0J-197D01*
G01X782481D02*
G03X782284Y531183I-197J0D01*
G01X779922D02*
G03X779725Y530986I0J-197D01*
G01X780512D02*
G03X780315Y531183I-197J0D01*
G01X787087Y523898D02*
G03X786300Y524685I-787J0D01*
G01Y514252D02*
G03X787087Y515040I0J787D01*
G01X785237Y499213D02*
G03X785433Y499410I0J196D01*
G01X784646D02*
G03X784843Y499213I197J0D01*
G01X783268D02*
G03X783465Y499410I0J197D01*
G01X782678D02*
G03X782874Y499213I197J0D01*
G01X781300D02*
G03X781496Y499410I0J196D01*
G01X780709D02*
G03X780906Y499213I197J0D01*
G01X779331D02*
G03X779528Y499410I0J197D01*
G01X778741D02*
G03X778937Y499213I197J0D01*
G01X777953Y531183D02*
G03X777756Y530986I0J-197D01*
G01X778544D02*
G03X778347Y531183I-197J0D01*
G01X775985D02*
G03X775788Y530986I0J-197D01*
G01X776575D02*
G03X776378Y531183I-197J0D01*
G01X774016D02*
G03X773819Y530986I0J-197D01*
G01X774607D02*
G03X774410Y531183I-197J0D01*
G01X772048D02*
G03X771851Y530986I0J-197D01*
G01X772638D02*
G03X772441Y531183I-197J0D01*
G01X770079D02*
G03X769882Y530986I0J-197D01*
G01X770670D02*
G03X770473Y531183I-197J0D01*
G01X768111D02*
G03X767914Y530986I0J-197D01*
G01X768701D02*
G03X768504Y531183I-197J0D01*
G01X764764Y530709D02*
G03X763977I-394J0D01*
G01X763583Y532678D02*
G03X762796Y531890I0J-787D01*
G01X763977Y525197D02*
G03X764764I393J0D01*
G01X766654Y524685D02*
G03X765867Y523898I0J-787D01*
G01X762796Y524016D02*
G03X763583Y523229I787J0D01*
G01X747048Y530709D02*
G03X746260I-394J0D01*
G01X749607Y531890D02*
G03X748819Y532678I-788J0D01*
G01X748229Y531890D02*
G03X747441Y532678I-788J0D01*
G01X762205D02*
G03X761418Y531890I0J-787D01*
G01X746260Y525197D02*
G03X747048I394J0D01*
G01X747441Y523229D02*
G03X748229Y524016I0J788D01*
G01X765867Y515040D02*
G03X766654Y514252I788J0D01*
G01X766339Y510237D02*
G03I-984J0D01*
G01X763878Y506103D02*
G03X765059Y507284I0J1181D01*
G01X767126Y510237D02*
G03I-1771J0D01*
G01X777363Y499213D02*
G03X777559Y499410I0J196D01*
G01X776772D02*
G03X776969Y499213I197J0D01*
G01X775394D02*
G03X775591Y499410I0J197D01*
G01X774804D02*
G03X775000Y499213I197J0D01*
G01X773426D02*
G03X773622Y499410I0J196D01*
G01X772835D02*
G03X773032Y499213I197J0D01*
G01X771457D02*
G03X771654Y499410I0J197D01*
G01X770867D02*
G03X771063Y499213I197J0D01*
G01X769489D02*
G03X769685Y499410I0J196D01*
G01X768898D02*
G03X769095Y499213I197J0D01*
G01X745965Y507284D02*
G03X747146Y506103I1181J0D01*
G01X748819Y500591D02*
G03X749607Y501378I0J788D01*
G01X761418D02*
G03X762205Y500591I787J0D01*
G01X742520Y531183D02*
G03X742323Y530986I0J-197D01*
G01X743111D02*
G03X742914Y531183I-197J0D01*
G01X740552D02*
G03X740355Y530986I0J-197D01*
G01X741142D02*
G03X740945Y531183I-197J0D01*
G01X738583D02*
G03X738386Y530986I0J-197D01*
G01X739174D02*
G03X738977Y531183I-197J0D01*
G01X736615D02*
G03X736418Y530986I0J-197D01*
G01X737205D02*
G03X737008Y531183I-197J0D01*
G01X734646D02*
G03X734449Y530986I0J-197D01*
G01X735237D02*
G03X735040Y531183I-197J0D01*
G01X724804D02*
G03X724607Y530986I0J-197D01*
G01X725394D02*
G03X725197Y531183I-197J0D01*
G01X722835D02*
G03X722638Y530986I0J-197D01*
G01X723426D02*
G03X723229Y531183I-197J0D01*
G01X720867D02*
G03X720670Y530986I0J-197D01*
G01X721457D02*
G03X721260Y531183I-197J0D01*
G01X718898D02*
G03X718701Y530986I0J-197D01*
G01X719489D02*
G03X719292Y531183I-197J0D01*
G01X716929D02*
G03X716733Y530986I0J-196D01*
G01X717520D02*
G03X717323Y531183I-197J0D01*
G01X715552Y530986D02*
G03X715355Y531183I-197J0D01*
G01X747638Y510237D02*
G03I-1968J0D01*
G01X728248Y508268D02*
G03X732579I2166J0D01*
G01X748426Y510237D02*
G03I-2756J0D01*
G01X741929Y499213D02*
G03X742126Y499410I0J197D01*
G01X741339D02*
G03X741536Y499213I197J0D01*
G01X739961D02*
G03X740158Y499410I0J197D01*
G01X739370D02*
G03X739567Y499213I197J0D01*
G01X737992D02*
G03X738189Y499410I0J197D01*
G01X737402D02*
G03X737599Y499213I197J0D01*
G01X736024D02*
G03X736221Y499410I0J197D01*
G01X735433D02*
G03X735630Y499213I197J0D01*
G01X726181D02*
G03X726378Y499410I0J197D01*
G01X725591D02*
G03X725788Y499213I197J0D01*
G01X724213D02*
G03X724410Y499410I0J197D01*
G01X723622D02*
G03X723819Y499213I197J0D01*
G01X722244D02*
G03X722441Y499410I0J197D01*
G01X721654D02*
G03X721851Y499213I197J0D01*
G01X720276D02*
G03X720473Y499410I0J197D01*
G01X719685D02*
G03X719882Y499213I197J0D01*
G01X718307D02*
G03X718504Y499410I0J197D01*
G01X717717D02*
G03X717914Y499213I197J0D01*
G01X716339D02*
G03X716536Y499410I0J197D01*
G01X715748D02*
G03X715945Y499213I197J0D01*
G01X778019Y521545D02*
X778084Y521143D01*
G01X782415Y522081D02*
X782481Y521746D01*
G01X782087Y522081D02*
X782153Y521746D01*
G01X777428Y522148D02*
X777494Y521813D01*
G01X785040Y521947D02*
X785105Y521679D01*
G01X784712Y521947D02*
X784777Y521679D01*
G01X783334Y521411D02*
X783399Y521143D01*
G01X780053Y522081D02*
X780118Y521813D01*
G01X777100Y522081D02*
X777166Y521813D01*
G01X775066Y522081D02*
X775132Y521813D01*
G01X783006Y521411D02*
X783137Y520942D01*
G01X784974Y522148D02*
X785040Y521947D01*
G01X782349Y522282D02*
X782415Y522081D01*
G01X778347Y521411D02*
X778412Y521210D01*
G01X774738Y521947D02*
X774804Y521746D01*
G01X768242Y523354D02*
X768832Y521545D01*
G01X768898Y521277D02*
X769160Y520473D01*
G01X768504Y523622D02*
X769554Y520473D01*
G01X775394Y518386D02*
X776378Y515572D01*
G01X775197Y517716D02*
X776116Y515237D01*
G01X772376Y522416D02*
X772507Y522081D01*
G01X778412Y521210D02*
X778478Y521076D01*
G01X778084Y521143D02*
X778216Y520875D01*
G01X777363Y522282D02*
X777428Y522148D01*
G01X775000Y522215D02*
X775066Y522081D01*
G01X773360Y520875D02*
X773426Y520741D01*
G01X772113Y522215D02*
X772179Y522081D01*
G01X771063Y522215D02*
X771129Y522081D01*
G01X784843Y522349D02*
X784974Y522148D01*
G01X784580D02*
X784712Y521947D01*
G01X783399Y521143D02*
X783531Y520942D01*
G01X783137D02*
X783268Y520741D01*
G01X779659Y522148D02*
X779790Y521947D01*
G01X774607Y522148D02*
X774738Y521947D01*
G01X773360Y521210D02*
X773491Y521009D01*
G01X779856Y522349D02*
X780053Y522081D01*
G01X784712Y522483D02*
X784843Y522349D01*
G01X784449Y522282D02*
X784580Y522148D01*
G01X782218Y522416D02*
X782349Y522282D01*
G01X783531Y520942D02*
X783662Y520808D01*
G01X781956Y522215D02*
X782087Y522081D01*
G01X783268Y520741D02*
X783399Y520607D01*
G01X785724Y510554D02*
X785683Y511604D01*
G01X785630Y512555D02*
X785638Y512398D01*
G01X783662Y512555D02*
X783670Y512398D01*
G01X785724Y510554D02*
X785630Y512214D01*
G01X783755Y510554D02*
X783662Y512214D01*
G01X785683Y511604D02*
X785638Y512398D01*
G01X783715Y511604D02*
X783670Y512398D01*
G01X777231Y522416D02*
X777363Y522282D01*
G01X778478Y521076D02*
X778675Y520875D01*
G01X776969Y522215D02*
X777100Y522081D01*
G01X778216Y520875D02*
X778347Y520741D01*
G01X774804Y522416D02*
X775000Y522215D01*
G01X772244Y522550D02*
X772376Y522416D01*
G01X772048Y522282D02*
X772113Y522215D01*
G01X773426Y520741D02*
X773557Y520607D01*
G01X771195Y522550D02*
X771391Y522349D01*
G01X770998Y522282D02*
X771063Y522215D01*
G01X782021Y522550D02*
X782218Y522416D01*
G01X779462Y522282D02*
X779659Y522148D01*
G01X777034Y522550D02*
X777231Y522416D01*
G01X778347Y520741D02*
X778544Y520607D01*
G01X774607Y522550D02*
X774804Y522416D01*
G01X773491Y521009D02*
X773688Y520875D01*
G01X779856Y522349D02*
X779528Y522550D01*
G01X778084Y521947D02*
X778019Y521545D01*
G01X786324Y510554D02*
X786418Y512214D01*
G01X786410Y512398D02*
X786365Y511604D01*
G01X784356Y510554D02*
X784449Y512214D01*
G01X784441Y512398D02*
X784396Y511604D01*
G01X782387Y510554D02*
X782481Y512214D01*
G01X782473Y512398D02*
X782428Y511604D01*
G01X780419Y510554D02*
X780512Y512214D01*
G01X780504Y512398D02*
X780459Y511604D01*
G01X778450Y510554D02*
X778544Y512214D01*
G01X778536Y512398D02*
X778491Y511604D01*
G01X776482Y510554D02*
X776575Y512214D01*
G01X776567Y512398D02*
X776522Y511604D01*
G01X774513Y510554D02*
X774607Y512214D01*
G01X774599Y512398D02*
X774554Y511604D01*
G01X772545Y510554D02*
X772638Y512214D01*
G01X772630Y512398D02*
X772585Y511604D01*
G01X770576Y510554D02*
X770670Y512214D01*
G01X770662Y512398D02*
X770617Y511604D01*
G01X768608Y510554D02*
X768701Y512214D01*
G01X768693Y512398D02*
X768648Y511604D01*
G01X786410Y512398D02*
X786418Y512555D01*
G01X784441Y512398D02*
X784449Y512555D01*
G01X782473Y512398D02*
X782481Y512555D01*
G01X780504Y512398D02*
X780512Y512555D01*
G01X778536Y512398D02*
X778544Y512555D01*
G01X776567Y512398D02*
X776575Y512555D01*
G01X774599Y512398D02*
X774607Y512555D01*
G01X772630Y512398D02*
X772638Y512555D01*
G01X770662Y512398D02*
X770670Y512555D01*
G01X768693Y512398D02*
X768701Y512555D01*
G01X786324Y510554D02*
X786365Y511604D01*
G01X784356Y510554D02*
X784396Y511604D01*
G01X782387Y510554D02*
X782428Y511604D01*
G01X780419Y510554D02*
X780459Y511604D01*
G01X778450Y510554D02*
X778491Y511604D01*
G01X776482Y510554D02*
X776522Y511604D01*
G01X774513Y510554D02*
X774554Y511604D01*
G01X772545Y510554D02*
X772585Y511604D01*
G01X770576Y510554D02*
X770617Y511604D01*
G01X768608Y510554D02*
X768648Y511604D01*
G01X786418Y514571D02*
Y512214D01*
G01Y530986D02*
Y528665D01*
G01X785958Y523622D02*
Y520473D01*
G01X785630Y512214D02*
Y514571D01*
G01Y523622D02*
Y520473D01*
G01Y530986D02*
Y528665D01*
G01X785433Y501731D02*
Y499410D01*
G01X785394Y513274D02*
Y509095D01*
G01X785197Y513414D02*
Y513270D01*
G01X785105Y521679D02*
Y521411D01*
G01X784882Y513270D02*
Y513414D01*
G01X784777Y521679D02*
Y521411D01*
G01X784685Y513274D02*
Y509095D01*
G01X784646Y499410D02*
Y501731D01*
G01X784449Y514571D02*
Y512214D01*
G01Y530986D02*
Y528665D01*
G01X783662Y512214D02*
Y514571D01*
G01Y530986D02*
Y528665D01*
G01X783465Y501731D02*
Y499410D01*
G01X783426Y513274D02*
Y509095D01*
G01X783334Y521679D02*
Y521411D01*
G01X783229Y513414D02*
Y513270D01*
G01X783006Y521679D02*
Y521411D01*
G01X782914Y513270D02*
Y513414D01*
G01X782717Y513274D02*
Y509095D01*
G01X782678Y499410D02*
Y501731D01*
G01X782481Y514571D02*
Y512214D01*
G01Y521746D02*
Y520473D01*
G01Y530986D02*
Y528665D01*
G01X782153Y521746D02*
Y520473D01*
G01X781693Y512214D02*
Y514571D01*
G01Y530986D02*
Y528665D01*
G01X781496Y501731D02*
Y499410D01*
G01X781457Y513274D02*
Y509095D01*
G01X781260Y513414D02*
Y513270D01*
G01X780971Y522014D02*
Y520473D01*
G01Y522617D02*
Y522282D01*
G01X780945Y513270D02*
Y513414D01*
G01X780748Y513274D02*
Y509095D01*
G01X780709Y499410D02*
Y501731D01*
G01X780643Y522617D02*
Y520473D01*
G01X780512Y514571D02*
Y512214D01*
G01Y530986D02*
Y528665D01*
G01X780118Y521813D02*
Y521545D01*
G01X779790Y521947D02*
Y521813D01*
G01X779725Y512214D02*
Y514571D01*
G01Y530986D02*
Y528665D01*
G01X779528Y501731D02*
Y499410D01*
G01X779489Y513274D02*
Y509095D01*
G01X779292Y513414D02*
Y513270D01*
G01X778977D02*
Y513414D01*
G01X778780Y513274D02*
Y509095D01*
G01X778741Y499410D02*
Y501731D01*
G01X778544Y514571D02*
Y512214D01*
G01Y530986D02*
Y528665D01*
G01X778412Y521880D02*
Y521813D01*
G01X778347Y521545D02*
Y521411D01*
G01X777953Y518386D02*
Y515237D01*
G01X777756Y512214D02*
Y514571D01*
G01Y530986D02*
Y528665D01*
G01X777559Y501731D02*
Y499410D01*
G01Y517716D02*
Y515237D01*
G01X777520Y513274D02*
Y509095D01*
G01X777494Y521813D02*
Y520473D01*
G01X777323Y513414D02*
Y513270D01*
G01X777166Y521813D02*
Y520473D01*
G01X777008Y513270D02*
Y513414D01*
G01X776811Y513274D02*
Y509095D01*
G01X776772Y499410D02*
Y501731D01*
G01X776575Y514571D02*
Y512214D01*
G01Y530986D02*
Y528665D01*
G01X775985Y522014D02*
Y520473D01*
G01Y523622D02*
Y522282D01*
G01X775788Y512214D02*
Y514571D01*
G01Y530986D02*
Y528665D01*
G01X775657Y523622D02*
Y520473D01*
G01X775591Y501731D02*
Y499410D01*
G01X775552Y513274D02*
Y509095D01*
G01X775355Y513414D02*
Y513270D01*
G01X775197Y517716D02*
Y515237D01*
G01X775132Y521813D02*
Y521277D01*
G01X775040Y513270D02*
Y513414D01*
G01X774843Y513274D02*
Y509095D01*
G01X774804Y499410D02*
Y501731D01*
G01Y518386D02*
Y515237D01*
G01Y521746D02*
Y521344D01*
G01X774607Y514571D02*
Y512214D01*
G01Y530986D02*
Y528665D01*
G01X773819Y512214D02*
Y514571D01*
G01Y530986D02*
Y528665D01*
G01X773622Y501731D02*
Y499410D01*
G01X773583Y513274D02*
Y509095D01*
G01X773386Y513414D02*
Y513270D01*
G01X773360Y521880D02*
Y521210D01*
G01Y520875D02*
Y519401D01*
G01Y522617D02*
Y522215D01*
G01X773071Y513270D02*
Y513414D01*
G01X773032Y522617D02*
Y519401D01*
G01X772874Y513274D02*
Y509095D01*
G01X772835Y499410D02*
Y501731D01*
G01X772638Y514571D02*
Y512214D01*
G01Y530986D02*
Y528665D01*
G01X772507Y522081D02*
Y520473D01*
G01X772179Y522081D02*
Y520473D01*
G01X771851Y512214D02*
Y514571D01*
G01Y530986D02*
Y528665D01*
G01X771654Y501731D02*
Y499410D01*
G01X771615Y513274D02*
Y509095D01*
G01X771457Y522081D02*
Y520473D01*
G01X771418Y513414D02*
Y513270D01*
G01X771260Y522638D02*
Y526575D01*
G01X771129Y522081D02*
Y520473D01*
G01X771103Y513270D02*
Y513414D01*
G01X770906Y513274D02*
Y509095D01*
G01X770867Y499410D02*
Y501731D01*
G01X770670Y514571D02*
Y512214D01*
G01Y530986D02*
Y528665D01*
G01X770407Y522148D02*
Y520473D01*
G01Y522617D02*
Y522416D01*
G01X770079Y522617D02*
Y520473D01*
G01X769882Y512214D02*
Y514571D01*
G01Y530986D02*
Y528665D01*
G01X769685Y501731D02*
Y499410D01*
G01X769646Y513274D02*
Y509095D01*
G01X769449Y513414D02*
Y513270D01*
G01X769292Y526575D02*
Y522638D01*
G01X769134Y513270D02*
Y513414D01*
G01X768937Y513274D02*
Y509095D01*
G01X768898Y499410D02*
Y501731D01*
G01X768701Y514571D02*
Y512214D01*
G01Y530986D02*
Y528665D01*
G01X767914Y512214D02*
Y514571D01*
G01Y530986D02*
Y528665D01*
G01X766181Y529725D02*
Y532678D01*
G01X766142Y508650D02*
Y500591D01*
G01X765867Y523898D02*
Y515040D01*
G01X765748Y532678D02*
Y529725D01*
G01X765460Y523229D02*
Y529725D01*
G01X765158Y532678D02*
Y523229D01*
G01X765059Y507284D02*
Y517126D01*
G01X764764Y530709D02*
Y525197D01*
G01X764567Y526575D02*
Y532678D01*
G01X763977Y525197D02*
Y530709D01*
G01X763878Y506103D02*
Y510040D01*
G01X762796Y524016D02*
Y531890D01*
G01X762402Y526575D02*
Y532678D01*
G01X761418Y531890D02*
Y500591D01*
G01X749607Y531890D02*
Y500591D01*
G01X783755Y510554D02*
X783715Y511604D01*
G01X781787Y510554D02*
X781746Y511604D01*
G01X779818Y510554D02*
X779778Y511604D01*
G01X777850Y510554D02*
X777809Y511604D01*
G01X775881Y510554D02*
X775841Y511604D01*
G01X773913Y510554D02*
X773872Y511604D01*
G01X771944Y510554D02*
X771904Y511604D01*
G01X769976Y510554D02*
X769935Y511604D01*
G01X768007Y510554D02*
X767967Y511604D01*
G01X781693Y512555D02*
X781701Y512398D01*
G01X779725Y512555D02*
X779733Y512398D01*
G01X777756Y512555D02*
X777764Y512398D01*
G01X775788Y512555D02*
X775796Y512398D01*
G01X773819Y512555D02*
X773827Y512398D01*
G01X771851Y512555D02*
X771859Y512398D01*
G01X769882Y512555D02*
X769890Y512398D01*
G01X767914Y512555D02*
X767922Y512398D01*
G01X781787Y510554D02*
X781693Y512214D01*
G01X779818Y510554D02*
X779725Y512214D01*
G01X777850Y510554D02*
X777756Y512214D01*
G01X775881Y510554D02*
X775788Y512214D01*
G01X773913Y510554D02*
X773819Y512214D01*
G01X771944Y510554D02*
X771851Y512214D01*
G01X769976Y510554D02*
X769882Y512214D01*
G01X768007Y510554D02*
X767914Y512214D01*
G01X742416Y510554D02*
X742323Y512214D01*
G01X781746Y511604D02*
X781701Y512398D01*
G01X779778Y511604D02*
X779733Y512398D01*
G01X777809Y511604D02*
X777764Y512398D01*
G01X775841Y511604D02*
X775796Y512398D01*
G01X773872Y511604D02*
X773827Y512398D01*
G01X771904Y511604D02*
X771859Y512398D01*
G01X769935Y511604D02*
X769890Y512398D01*
G01X767967Y511604D02*
X767922Y512398D01*
G01X742376Y511604D02*
X742331Y512398D01*
G01X784712Y522483D02*
X784580Y522550D01*
G01X781956Y522215D02*
X781825Y522282D01*
G01X783531Y520540D02*
X783399Y520607D01*
G01X776969Y522215D02*
X776838Y522282D01*
G01X778806Y520808D02*
X778675Y520875D01*
G01X774607Y522148D02*
X774344Y522282D01*
G01X772048D02*
X771916Y522349D01*
G01X770998Y522282D02*
X770867Y522349D01*
G01X773688Y520540D02*
X773557Y520607D01*
G01X777559Y517716D02*
X776641Y515237D01*
G01X777363Y518386D02*
X776378Y515572D01*
G01X783137Y522148D02*
X783071Y521947D01*
G01X779790Y521143D02*
X779725Y520942D01*
G01X774804Y521344D02*
X774738Y521143D01*
G01X785105Y521411D02*
X784974Y520942D01*
G01X784777Y521411D02*
X784712Y521143D01*
G01X783399Y521947D02*
X783334Y521679D01*
G01X783071Y521947D02*
X783006Y521679D01*
G01X780118Y521143D02*
X780053Y520875D01*
G01X775132Y521277D02*
X775066Y521009D01*
G01X743017Y510554D02*
X743111Y512214D01*
G01X743103Y512398D02*
X743058Y511604D01*
G01X741049Y510554D02*
X741142Y512214D01*
G01X741134Y512398D02*
X741089Y511604D01*
G01X739080Y510554D02*
X739174Y512214D01*
G01X739166Y512398D02*
X739121Y511604D01*
G01X737112Y510554D02*
X737205Y512214D01*
G01X737197Y512398D02*
X737152Y511604D01*
G01X735143Y510554D02*
X735237Y512214D01*
G01X735229Y512398D02*
X735184Y511604D01*
G01X725301Y510554D02*
X725394Y512214D01*
G01X725386Y512398D02*
X725341Y511604D01*
G01X723332Y510554D02*
X723426Y512214D01*
G01X723418Y512398D02*
X723373Y511604D01*
G01X721364Y510554D02*
X721457Y512214D01*
G01X721449Y512398D02*
X721404Y511604D01*
G01X719395Y510554D02*
X719489Y512214D01*
G01X719481Y512398D02*
X719436Y511604D01*
G01X717427Y510554D02*
X717520Y512214D01*
G01X717512Y512398D02*
X717467Y511604D01*
G01X743103Y512398D02*
X743111Y512555D01*
G01X741134Y512398D02*
X741142Y512555D01*
G01X739166Y512398D02*
X739174Y512555D01*
G01X737197Y512398D02*
X737205Y512555D01*
G01X735229Y512398D02*
X735237Y512555D01*
G01X725386Y512398D02*
X725394Y512555D01*
G01X723418Y512398D02*
X723426Y512555D01*
G01X721449Y512398D02*
X721457Y512555D01*
G01X719481Y512398D02*
X719489Y512555D01*
G01X717512Y512398D02*
X717520Y512555D01*
G01X743017Y510554D02*
X743058Y511604D01*
G01X741049Y510554D02*
X741089Y511604D01*
G01X739080Y510554D02*
X739121Y511604D01*
G01X737112Y510554D02*
X737152Y511604D01*
G01X735143Y510554D02*
X735184Y511604D01*
G01X725301Y510554D02*
X725341Y511604D01*
G01X723332Y510554D02*
X723373Y511604D01*
G01X721364Y510554D02*
X721404Y511604D01*
G01X719395Y510554D02*
X719436Y511604D01*
G01X717427Y510554D02*
X717467Y511604D01*
G01X715458Y510554D02*
X715499Y511604D01*
G01X748622Y526575D02*
Y532678D01*
G01X748229Y531890D02*
Y524016D01*
G01X747146Y510040D02*
Y506103D01*
G01X747048Y530709D02*
Y525197D01*
G01X746457Y526575D02*
Y532678D01*
G01X746260Y525197D02*
Y530709D01*
G01X745965Y517126D02*
Y507284D01*
G01X745867Y523229D02*
Y532678D01*
G01X745564Y529725D02*
Y523229D01*
G01X745276Y532678D02*
Y529725D01*
G01X744882Y507596D02*
Y500591D01*
G01X744844Y532678D02*
Y529725D01*
G01X743111Y514571D02*
Y512214D01*
G01Y530986D02*
Y528665D01*
G01X742323Y512214D02*
Y514571D01*
G01Y530986D02*
Y528665D01*
G01X742126Y501731D02*
Y499410D01*
G01X742087Y513274D02*
Y509095D01*
G01X741890Y513414D02*
Y513270D01*
G01X741733Y526575D02*
Y522638D01*
G01X741575Y513270D02*
Y513414D01*
G01X741378Y513274D02*
Y509095D01*
G01X741339Y499410D02*
Y501731D01*
G01X741142Y514571D02*
Y512214D01*
G01Y530986D02*
Y528665D01*
G01X740355Y512214D02*
Y514571D01*
G01Y530986D02*
Y528665D01*
G01X740158Y501731D02*
Y499410D01*
G01X740118Y513274D02*
Y509095D01*
G01X739922Y513414D02*
Y513270D01*
G01X739764Y526575D02*
Y522638D01*
G01X739607Y513270D02*
Y513414D01*
G01X739410Y513274D02*
Y509095D01*
G01X739370Y499410D02*
Y501731D01*
G01X739174Y514571D02*
Y512214D01*
G01Y530986D02*
Y528665D01*
G01X738386Y512214D02*
Y514571D01*
G01Y530986D02*
Y528665D01*
G01X738189Y501731D02*
Y499410D01*
G01X738150Y513274D02*
Y509095D01*
G01X737953Y513414D02*
Y513270D01*
G01X737638D02*
Y513414D01*
G01X737441Y513274D02*
Y509095D01*
G01X737402Y499410D02*
Y501731D01*
G01X737205Y514571D02*
Y512214D01*
G01Y530986D02*
Y528665D01*
G01X736418Y512214D02*
Y514571D01*
G01Y530986D02*
Y528665D01*
G01X736221Y501731D02*
Y499410D01*
G01X736181Y513274D02*
Y509095D01*
G01X735985Y513414D02*
Y513270D01*
G01X735670D02*
Y513414D01*
G01X735473Y513274D02*
Y509095D01*
G01X735433Y499410D02*
Y501731D01*
G01X735237Y514571D02*
Y512214D01*
G01Y530986D02*
Y528665D01*
G01X734449Y512214D02*
Y514571D01*
G01Y530986D02*
Y528665D01*
G01X732579Y508268D02*
Y517126D01*
G01X728248D02*
Y508268D01*
G01X726378Y501731D02*
Y499410D01*
G01X726339Y513274D02*
Y509095D01*
G01X726142Y513414D02*
Y513270D01*
G01X725827D02*
Y513414D01*
G01X725630Y513274D02*
Y509095D01*
G01X725591Y499410D02*
Y501731D01*
G01X725394Y514571D02*
Y512214D01*
G01Y530986D02*
Y528665D01*
G01X724607Y512214D02*
Y514571D01*
G01Y530986D02*
Y528665D01*
G01X724410Y501731D02*
Y499410D01*
G01X724370Y513274D02*
Y509095D01*
G01X724174Y513414D02*
Y513270D01*
G01X723859D02*
Y513414D01*
G01X723662Y513274D02*
Y509095D01*
G01X723622Y499410D02*
Y501731D01*
G01X723426Y514571D02*
Y512214D01*
G01Y530986D02*
Y528665D01*
G01X722638Y512214D02*
Y514571D01*
G01Y530986D02*
Y528665D01*
G01X722441Y501731D02*
Y499410D01*
G01X722402Y513274D02*
Y509095D01*
G01X722205Y513414D02*
Y513270D01*
G01X721890D02*
Y513414D01*
G01X721693Y513274D02*
Y509095D01*
G01X721654Y499410D02*
Y501731D01*
G01X721457Y514571D02*
Y512214D01*
G01Y530986D02*
Y528665D01*
G01X720670Y512214D02*
Y514571D01*
G01Y530986D02*
Y528665D01*
G01X720473Y501731D02*
Y499410D01*
G01X720433Y513274D02*
Y509095D01*
G01X720237Y513414D02*
Y513270D01*
G01X719922D02*
Y513414D01*
G01X719725Y513274D02*
Y509095D01*
G01X719685Y499410D02*
Y501731D01*
G01X719489Y514571D02*
Y512214D01*
G01Y530986D02*
Y528665D01*
G01X718701Y512214D02*
Y514571D01*
G01Y530986D02*
Y528665D01*
G01X718504Y501731D02*
Y499410D01*
G01X718465Y513274D02*
Y509095D01*
G01X718268Y513414D02*
Y513270D01*
G01X717953D02*
Y513414D01*
G01X717756Y513274D02*
Y509095D01*
G01X717717Y499410D02*
Y501731D01*
G01X717520Y514571D02*
Y512214D01*
G01Y530986D02*
Y528665D01*
G01X716733Y512214D02*
Y514571D01*
G01Y530986D02*
Y528665D01*
G01X716536Y501731D02*
Y499410D01*
G01X716496Y513274D02*
Y509095D01*
G01X716300Y513414D02*
Y513270D01*
G01X715985D02*
Y513414D01*
G01X715788Y513274D02*
Y509095D01*
G01X715748Y499410D02*
Y501731D01*
G01X715552Y514571D02*
Y512214D01*
G01Y530986D02*
Y528665D01*
G01X742416Y510554D02*
X742376Y511604D01*
G01X740448Y510554D02*
X740407Y511604D01*
G01X738479Y510554D02*
X738439Y511604D01*
G01X736511Y510554D02*
X736470Y511604D01*
G01X734542Y510554D02*
X734502Y511604D01*
G01X724700Y510554D02*
X724659Y511604D01*
G01X722731Y510554D02*
X722691Y511604D01*
G01X720763Y510554D02*
X720722Y511604D01*
G01X718794Y510554D02*
X718754Y511604D01*
G01X716826Y510554D02*
X716785Y511604D01*
G01X714857Y510554D02*
X714817Y511604D01*
G01X742323Y512555D02*
X742331Y512398D01*
G01X740355Y512555D02*
X740363Y512398D01*
G01X738386Y512555D02*
X738394Y512398D01*
G01X736418Y512555D02*
X736426Y512398D01*
G01X734449Y512555D02*
X734457Y512398D01*
G01X724607Y512555D02*
X724615Y512398D01*
G01X722638Y512555D02*
X722646Y512398D01*
G01X720670Y512555D02*
X720678Y512398D01*
G01X718701Y512555D02*
X718709Y512398D01*
G01X716733Y512555D02*
X716741Y512398D01*
G01X740448Y510554D02*
X740355Y512214D01*
G01X738479Y510554D02*
X738386Y512214D01*
G01X736511Y510554D02*
X736418Y512214D01*
G01X734542Y510554D02*
X734449Y512214D01*
G01X724700Y510554D02*
X724607Y512214D01*
G01X722731Y510554D02*
X722638Y512214D01*
G01X720763Y510554D02*
X720670Y512214D01*
G01X718794Y510554D02*
X718701Y512214D01*
G01X716826Y510554D02*
X716733Y512214D01*
G01X740407Y511604D02*
X740363Y512398D01*
G01X738439Y511604D02*
X738394Y512398D01*
G01X736470Y511604D02*
X736426Y512398D01*
G01X734502Y511604D02*
X734457Y512398D01*
G01X724659Y511604D02*
X724615Y512398D01*
G01X722691Y511604D02*
X722646Y512398D01*
G01X720722Y511604D02*
X720678Y512398D01*
G01X718754Y511604D02*
X718709Y512398D01*
G01X716785Y511604D02*
X716741Y512398D01*
G01X782021Y522550D02*
X781825Y522617D01*
G01X777034Y522550D02*
X776838Y522617D01*
G01X778741Y520540D02*
X778544Y520607D01*
G01X772244Y522550D02*
X772048Y522617D01*
G01X771195Y522550D02*
X770998Y522617D01*
G01X784580Y522550D02*
X784318Y522617D01*
G01X784449Y522282D02*
X784187Y522349D01*
G01X781825Y522282D02*
X781562Y522349D01*
G01X783924Y520741D02*
X783662Y520808D01*
G01X776838Y522282D02*
X776575Y522349D01*
G01X783793Y520473D02*
X783531Y520540D01*
G01X774607Y522550D02*
X774344Y522617D01*
G01X779069Y520741D02*
X778806Y520808D01*
G01X773950D02*
X773688Y520875D01*
G01X773950Y520473D02*
X773688Y520540D01*
G01X778478Y522014D02*
X778412Y521880D01*
G01X778216Y522215D02*
X778084Y521947D01*
G01X774738Y521143D02*
X774672Y521009D01*
G01X773426Y522349D02*
X773360Y522215D01*
G01X771523D02*
X771457Y522081D01*
G01X767979Y523622D02*
X766929Y520473D01*
G01X767586Y521277D02*
X767323Y520473D01*
G01X768242Y523354D02*
X767651Y521545D01*
G01X715458Y510554D02*
X715552Y512214D01*
G01X715544Y512398D02*
X715499Y511604D01*
G01X715544Y512398D02*
X715552Y512555D01*
G01X779528Y522550D02*
X779134Y522617D01*
G01X779462Y522282D02*
X779069Y522349D01*
G01X779134Y520473D02*
X778741Y520540D01*
G01X784974Y520942D02*
X784843Y520741D01*
G01X784712Y521143D02*
X784580Y520942D01*
G01X783531Y522148D02*
X783399Y521947D01*
G01X783268Y522349D02*
X783137Y522148D01*
G01X773491Y522081D02*
X773360Y521880D01*
G01X762205Y532678D02*
X766339D01*
G01X744685D02*
X748819D01*
G01X717323Y531183D02*
X716929D01*
G01X715355D02*
X714961D01*
G01X721260D02*
X720867D01*
G01X719292D02*
X718898D01*
G01X723229D02*
X722835D01*
G01X725197D02*
X724804D01*
G01X737008D02*
X736615D01*
G01X735040D02*
X734646D01*
G01X740945D02*
X740552D01*
G01X738977D02*
X738583D01*
G01X742914D02*
X742520D01*
G01X770473D02*
X770079D01*
G01X768504D02*
X768111D01*
G01X772441D02*
X772048D01*
G01X776378D02*
X775985D01*
G01X774410D02*
X774016D01*
G01X780315D02*
X779922D01*
G01X778347D02*
X777953D01*
G01X784252D02*
X783859D01*
G01X782284D02*
X781890D01*
G01X786221D02*
X785827D01*
G01X764567Y529725D02*
X844882D01*
G01X717520Y529214D02*
X716733D01*
G01X721457D02*
X720670D01*
G01X719489D02*
X718701D01*
G01X723426D02*
X722638D01*
G01X725394D02*
X724607D01*
G01X737205D02*
X736418D01*
G01X735237D02*
X734449D01*
G01X741142D02*
X740355D01*
G01X739174D02*
X738386D01*
G01X743111D02*
X742323D01*
G01X770670D02*
X769882D01*
G01X768701D02*
X767914D01*
G01X774607D02*
X773819D01*
G01X772638D02*
X771851D01*
G01X776575D02*
X775788D01*
G01X780512D02*
X779725D01*
G01X778544D02*
X777756D01*
G01X784449D02*
X783662D01*
G01X782481D02*
X781693D01*
G01X786418D02*
X785630D01*
G01Y528665D02*
X786418D01*
G01X783662D02*
X784449D01*
G01X781693D02*
X782481D01*
G01X779725D02*
X780512D01*
G01X777756D02*
X778544D01*
G01X775788D02*
X776575D01*
G01X773819D02*
X774607D01*
G01X771851D02*
X772638D01*
G01X769882D02*
X770670D01*
G01X767914D02*
X768701D01*
G01X742323D02*
X743111D01*
G01X740355D02*
X741142D01*
G01X738386D02*
X739174D01*
G01X736418D02*
X737205D01*
G01X734449D02*
X735237D01*
G01X724607D02*
X725394D01*
G01X722638D02*
X723426D01*
G01X720670D02*
X721457D01*
G01X718701D02*
X719489D01*
G01X716733D02*
X717520D01*
G01X844882Y527363D02*
X764567D01*
G01X741733Y526575D02*
X739764D01*
G01X747048D02*
X746457D01*
G01X749607D02*
X748229D01*
G01X764567D02*
X763977D01*
G01X762796D02*
X761418D01*
G01X771260D02*
X769292D01*
G01X786300Y524685D02*
X766654D01*
G01X768504Y523622D02*
X767979D01*
G01X775985D02*
X775657D01*
G01X785958D02*
X785630D01*
G01X763583Y523229D02*
X765460D01*
G01X747441D02*
X745564D01*
G01X739764Y522638D02*
X741733D01*
G01X771260D02*
X769292D01*
G01X770407Y522617D02*
X770079D01*
G01X773360D02*
X773032D01*
G01X770998D02*
X770735D01*
G01X772048D02*
X771785D01*
G01X776838D02*
X776575D01*
G01X774344D02*
X773950D01*
G01X784318D02*
X783793D01*
G01X780971D02*
X780643D01*
G01X781825D02*
X781562D01*
G01X770867Y522349D02*
X770735D01*
G01X771916D02*
X771720D01*
G01X784187D02*
X783924D01*
G01X774344Y522282D02*
X773950D01*
G01X779790Y521813D02*
X778412D01*
G01X768832Y521545D02*
X767651D01*
G01X780118D02*
X778347D01*
G01X768898Y521277D02*
X767586D01*
G01X780118Y521143D02*
X779790D01*
G01X774213Y520808D02*
X773950D01*
G01X784187Y520741D02*
X783924D01*
G01X767323Y520473D02*
X766929D01*
G01X770407D02*
X770079D01*
G01X769554D02*
X769160D01*
G01X771457D02*
X771129D01*
G01X772507D02*
X772179D01*
G01X777494D02*
X777166D01*
G01X775985D02*
X775657D01*
G01X774344D02*
X773950D01*
G01X784318D02*
X783793D01*
G01X782481D02*
X782153D01*
G01X780971D02*
X780643D01*
G01X785958D02*
X785630D01*
G01X773360Y519401D02*
X773032D01*
G01X775394Y518386D02*
X774804D01*
G01X777953D02*
X777363D01*
G01X745965Y517126D02*
X732579D01*
G01X826674D02*
X765059D01*
G01X775197Y515237D02*
X774804D01*
G01X776641D02*
X776116D01*
G01X777953D02*
X777559D01*
G01X717520Y514571D02*
X716733D01*
G01X719489D02*
X718701D01*
G01X721457D02*
X720670D01*
G01X723426D02*
X722638D01*
G01X725394D02*
X724607D01*
G01X735237D02*
X734449D01*
G01X737205D02*
X736418D01*
G01X739174D02*
X738386D01*
G01X741142D02*
X740355D01*
G01X743111D02*
X742323D01*
G01X768701D02*
X767914D01*
G01X770670D02*
X769882D01*
G01X772638D02*
X771851D01*
G01X774607D02*
X773819D01*
G01X776575D02*
X775788D01*
G01X778544D02*
X777756D01*
G01X780512D02*
X779725D01*
G01X782481D02*
X781693D01*
G01X784449D02*
X783662D01*
G01X786418D02*
X785630D01*
G01X786300Y514252D02*
X766654D01*
G01X717520Y513888D02*
X716733D01*
G01X719489D02*
X718701D01*
G01X721457D02*
X720670D01*
G01X723426D02*
X722638D01*
G01X725394D02*
X724607D01*
G01X735237D02*
X734449D01*
G01X737205D02*
X736418D01*
G01X739174D02*
X738386D01*
G01X741142D02*
X740355D01*
G01X743111D02*
X742323D01*
G01X768701D02*
X767914D01*
G01X770670D02*
X769882D01*
G01X772638D02*
X771851D01*
G01X774607D02*
X773819D01*
G01X776575D02*
X775788D01*
G01X778544D02*
X777756D01*
G01X780512D02*
X779725D01*
G01X782481D02*
X781693D01*
G01X784449D02*
X783662D01*
G01X786418D02*
X785630D01*
G01X717520Y513826D02*
X716733D01*
G01X719489D02*
X718701D01*
G01X721457D02*
X720670D01*
G01X723426D02*
X722638D01*
G01X725394D02*
X724607D01*
G01X735237D02*
X734449D01*
G01X737205D02*
X736418D01*
G01X739174D02*
X738386D01*
G01X741142D02*
X740355D01*
G01X743111D02*
X742323D01*
G01X768701D02*
X767914D01*
G01X770670D02*
X769882D01*
G01X772638D02*
X771851D01*
G01X774607D02*
X773819D01*
G01X776575D02*
X775788D01*
G01X778544D02*
X777756D01*
G01X780512D02*
X779725D01*
G01X782481D02*
X781693D01*
G01X784449D02*
X783662D01*
G01X786418D02*
X785630D01*
G01Y513499D02*
X786418D01*
G01X781693D02*
X782481D01*
G01X783662D02*
X784449D01*
G01X777756D02*
X778544D01*
G01X779725D02*
X780512D01*
G01X775788D02*
X776575D01*
G01X771851D02*
X772638D01*
G01X773819D02*
X774607D01*
G01X767914D02*
X768701D01*
G01X769882D02*
X770670D01*
G01X742323D02*
X743111D01*
G01X738386D02*
X739174D01*
G01X740355D02*
X741142D01*
G01X734449D02*
X735237D01*
G01X736418D02*
X737205D01*
G01X724607D02*
X725394D01*
G01X722638D02*
X723426D01*
G01X718701D02*
X719489D01*
G01X720670D02*
X721457D01*
G01X716733D02*
X717520D01*
G01X784882Y513414D02*
X785197D01*
G01X780945D02*
X781260D01*
G01X782914D02*
X783229D01*
G01X778977D02*
X779292D01*
G01X775040D02*
X775355D01*
G01X777008D02*
X777323D01*
G01X771103D02*
X771418D01*
G01X773071D02*
X773386D01*
G01X769134D02*
X769449D01*
G01X741575D02*
X741890D01*
G01X737638D02*
X737953D01*
G01X739607D02*
X739922D01*
G01X735670D02*
X735985D01*
G01X725827D02*
X726142D01*
G01X721890D02*
X722205D01*
G01X723859D02*
X724174D01*
G01X717953D02*
X718268D01*
G01X719922D02*
X720237D01*
G01X715985D02*
X716300D01*
G01X784882Y513270D02*
X785197D01*
G01X780945D02*
X781260D01*
G01X782914D02*
X783229D01*
G01X778977D02*
X779292D01*
G01X775040D02*
X775355D01*
G01X777008D02*
X777323D01*
G01X771103D02*
X771418D01*
G01X773071D02*
X773386D01*
G01X769134D02*
X769449D01*
G01X741575D02*
X741890D01*
G01X737638D02*
X737953D01*
G01X739607D02*
X739922D01*
G01X735670D02*
X735985D01*
G01X725827D02*
X726142D01*
G01X721890D02*
X722205D01*
G01X723859D02*
X724174D01*
G01X717953D02*
X718268D01*
G01X719922D02*
X720237D01*
G01X715985D02*
X716300D01*
G01X716496Y512890D02*
X715788D01*
G01X718465D02*
X717756D01*
G01X720433D02*
X719725D01*
G01X722402D02*
X721693D01*
G01X724370D02*
X723662D01*
G01X726339D02*
X725630D01*
G01X736181D02*
X735473D01*
G01X738150D02*
X737441D01*
G01X740118D02*
X739410D01*
G01X742087D02*
X741378D01*
G01X769646D02*
X768937D01*
G01X771615D02*
X770906D01*
G01X773583D02*
X772874D01*
G01X775552D02*
X774843D01*
G01X777520D02*
X776811D01*
G01X779489D02*
X778780D01*
G01X781457D02*
X780748D01*
G01X783426D02*
X782717D01*
G01X785394D02*
X784685D01*
G01Y512854D02*
X785394D01*
G01X780748D02*
X781457D01*
G01X782717D02*
X783426D01*
G01X778780D02*
X779489D01*
G01X774843D02*
X775552D01*
G01X776811D02*
X777520D01*
G01X770906D02*
X771615D01*
G01X772874D02*
X773583D01*
G01X768937D02*
X769646D01*
G01X741378D02*
X742087D01*
G01X739410D02*
X740118D01*
G01X735473D02*
X736181D01*
G01X737441D02*
X738150D01*
G01X725630D02*
X726339D01*
G01X721693D02*
X722402D01*
G01X723662D02*
X724370D01*
G01X717756D02*
X718465D01*
G01X719725D02*
X720433D01*
G01X715788D02*
X716496D01*
G01X765059Y512796D02*
X826674D01*
G01X732579D02*
X745965D01*
G01X716496Y512522D02*
X715788D01*
G01X718465D02*
X717756D01*
G01X720433D02*
X719725D01*
G01X722402D02*
X721693D01*
G01X724370D02*
X723662D01*
G01X726339D02*
X725630D01*
G01X736181D02*
X735473D01*
G01X738150D02*
X737441D01*
G01X740118D02*
X739410D01*
G01X742087D02*
X741378D01*
G01X769646D02*
X768937D01*
G01X771615D02*
X770906D01*
G01X773583D02*
X772874D01*
G01X775552D02*
X774843D01*
G01X777520D02*
X776811D01*
G01X779489D02*
X778780D01*
G01X781457D02*
X780748D01*
G01X783426D02*
X782717D01*
G01X785394D02*
X784685D01*
G01X717512Y512398D02*
X716741D01*
G01X719481D02*
X718709D01*
G01X721449D02*
X720678D01*
G01X723418D02*
X722646D01*
G01X725386D02*
X724615D01*
G01X735229D02*
X734457D01*
G01X737197D02*
X736426D01*
G01X739166D02*
X738394D01*
G01X741134D02*
X740363D01*
G01X743103D02*
X742331D01*
G01X768693D02*
X767922D01*
G01X770662D02*
X769890D01*
G01X772630D02*
X771859D01*
G01X774599D02*
X773827D01*
G01X776567D02*
X775796D01*
G01X778536D02*
X777764D01*
G01X780504D02*
X779733D01*
G01X782473D02*
X781701D01*
G01X784441D02*
X783670D01*
G01X786410D02*
X785638D01*
G01Y512064D02*
X786410D01*
G01X781701D02*
X782473D01*
G01X783670D02*
X784441D01*
G01X777764D02*
X778536D01*
G01X779733D02*
X780504D01*
G01X775796D02*
X776567D01*
G01X771859D02*
X772630D01*
G01X773827D02*
X774599D01*
G01X767922D02*
X768693D01*
G01X769890D02*
X770662D01*
G01X742331D02*
X743103D01*
G01X738394D02*
X739166D01*
G01X740363D02*
X741134D01*
G01X734457D02*
X735229D01*
G01X736426D02*
X737197D01*
G01X724615D02*
X725386D01*
G01X722646D02*
X723418D01*
G01X718709D02*
X719481D01*
G01X720678D02*
X721449D01*
G01X716741D02*
X717512D01*
G01X784685Y511674D02*
X785394D01*
G01X780748D02*
X781457D01*
G01X782717D02*
X783426D01*
G01X778780D02*
X779489D01*
G01X774843D02*
X775552D01*
G01X776811D02*
X777520D01*
G01X770906D02*
X771615D01*
G01X772874D02*
X773583D01*
G01X768937D02*
X769646D01*
G01X741378D02*
X742087D01*
G01X739410D02*
X740118D01*
G01X735473D02*
X736181D01*
G01X737441D02*
X738150D01*
G01X725630D02*
X726339D01*
G01X721693D02*
X722402D01*
G01X723662D02*
X724370D01*
G01X717756D02*
X718465D01*
G01X719725D02*
X720433D01*
G01X715788D02*
X716496D01*
G01X715499Y511604D02*
X714817D01*
G01X717467D02*
X716785D01*
G01X719436D02*
X718754D01*
G01X721404D02*
X720722D01*
G01X723373D02*
X722691D01*
G01X725341D02*
X724659D01*
G01X735184D02*
X734502D01*
G01X737152D02*
X736470D01*
G01X739121D02*
X738439D01*
G01X741089D02*
X740407D01*
G01X743058D02*
X742376D01*
G01X768648D02*
X767967D01*
G01X770617D02*
X769935D01*
G01X772585D02*
X771904D01*
G01X774554D02*
X773872D01*
G01X776522D02*
X775841D01*
G01X778491D02*
X777809D01*
G01X780459D02*
X779778D01*
G01X782428D02*
X781746D01*
G01X784396D02*
X783715D01*
G01X786365D02*
X785683D01*
G01X716496Y511497D02*
X715788D01*
G01X718465D02*
X717756D01*
G01X720433D02*
X719725D01*
G01X722402D02*
X721693D01*
G01X724370D02*
X723662D01*
G01X726339D02*
X725630D01*
G01X736181D02*
X735473D01*
G01X738150D02*
X737441D01*
G01X740118D02*
X739410D01*
G01X742087D02*
X741378D01*
G01X769646D02*
X768937D01*
G01X771615D02*
X770906D01*
G01X773583D02*
X772874D01*
G01X775552D02*
X774843D01*
G01X777520D02*
X776811D01*
G01X779489D02*
X778780D01*
G01X781457D02*
X780748D01*
G01X783426D02*
X782717D01*
G01X785394D02*
X784685D01*
G01X715458Y510554D02*
X714857D01*
G01X717427D02*
X716826D01*
G01X719395D02*
X718794D01*
G01X721364D02*
X720763D01*
G01X723332D02*
X722731D01*
G01X725301D02*
X724700D01*
G01X735143D02*
X734542D01*
G01X737112D02*
X736511D01*
G01X739080D02*
X738479D01*
G01X741049D02*
X740448D01*
G01X743017D02*
X742416D01*
G01X768608D02*
X768007D01*
G01X770576D02*
X769976D01*
G01X772545D02*
X771944D01*
G01X774513D02*
X773913D01*
G01X776482D02*
X775881D01*
G01X778450D02*
X777850D01*
G01X780419D02*
X779818D01*
G01X782387D02*
X781787D01*
G01X784356D02*
X783755D01*
G01X786324D02*
X785724D01*
G01X716496Y510355D02*
X715788D01*
G01X718465D02*
X717756D01*
G01X720433D02*
X719725D01*
G01X722402D02*
X721693D01*
G01X724370D02*
X723662D01*
G01X726339D02*
X725630D01*
G01X736181D02*
X735473D01*
G01X738150D02*
X737441D01*
G01X740118D02*
X739410D01*
G01X742087D02*
X741378D01*
G01X769646D02*
X768937D01*
G01X771615D02*
X770906D01*
G01X773583D02*
X772874D01*
G01X775552D02*
X774843D01*
G01X777520D02*
X776811D01*
G01X779489D02*
X778780D01*
G01X781457D02*
X780748D01*
G01X783426D02*
X782717D01*
G01X785394D02*
X784685D01*
G01X749607Y510237D02*
X748426D01*
G01X763583D02*
X761418D01*
G01Y510040D02*
X848032D01*
G01X716496Y509095D02*
X715788D01*
G01X718465D02*
X717756D01*
G01X720433D02*
X719725D01*
G01X722402D02*
X721693D01*
G01X724370D02*
X723662D01*
G01X726339D02*
X725630D01*
G01X736181D02*
X735473D01*
G01X738150D02*
X737441D01*
G01X740118D02*
X739410D01*
G01X742087D02*
X741378D01*
G01X769646D02*
X768937D01*
G01X771615D02*
X770906D01*
G01X773583D02*
X772874D01*
G01X775552D02*
X774843D01*
G01X777520D02*
X776811D01*
G01X779489D02*
X778780D01*
G01X781457D02*
X780748D01*
G01X783426D02*
X782717D01*
G01X785394D02*
X784685D01*
G01X749607Y506103D02*
X747146D01*
G01X763878D02*
X761418D01*
G01X784843Y520741D02*
X784712Y520607D01*
G01X784580Y520942D02*
X784449Y520808D01*
G01X783662Y522282D02*
X783531Y522148D01*
G01X783399Y522483D02*
X783268Y522349D01*
G01X780053Y520875D02*
X779856Y520674D01*
G01X781103Y522148D02*
X780971Y522014D01*
G01X781103Y522416D02*
X780971Y522282D01*
G01X775066Y521009D02*
X774804Y520674D01*
G01X716536Y501731D02*
X715748D01*
G01X720473D02*
X719685D01*
G01X718504D02*
X717717D01*
G01X724410D02*
X723622D01*
G01X722441D02*
X721654D01*
G01X726378D02*
X725591D01*
G01X738189D02*
X737402D01*
G01X736221D02*
X735433D01*
G01X740158D02*
X739370D01*
G01X742126D02*
X741339D01*
G01X769685D02*
X768898D01*
G01X773622D02*
X772835D01*
G01X771654D02*
X770867D01*
G01X777559D02*
X776772D01*
G01X775591D02*
X774804D01*
G01X779528D02*
X778741D01*
G01X783465D02*
X782678D01*
G01X781496D02*
X780709D01*
G01X785433D02*
X784646D01*
G01Y501182D02*
X785433D01*
G01X782678D02*
X783465D01*
G01X780709D02*
X781496D01*
G01X778741D02*
X779528D01*
G01X776772D02*
X777559D01*
G01X774804D02*
X775591D01*
G01X772835D02*
X773622D01*
G01X770867D02*
X771654D01*
G01X768898D02*
X769685D01*
G01X741339D02*
X742126D01*
G01X739370D02*
X740158D01*
G01X737402D02*
X738189D01*
G01X735433D02*
X736221D01*
G01X725591D02*
X726378D01*
G01X723622D02*
X724410D01*
G01X721654D02*
X722441D01*
G01X719685D02*
X720473D01*
G01X717717D02*
X718504D01*
G01X715748D02*
X716536D01*
G01X848032Y500591D02*
X761418D01*
G01X716339Y499213D02*
X715945D01*
G01X720276D02*
X719882D01*
G01X718307D02*
X717914D01*
G01X724213D02*
X723819D01*
G01X722244D02*
X721851D01*
G01X726181D02*
X725788D01*
G01X736024D02*
X735630D01*
G01X739961D02*
X739567D01*
G01X737992D02*
X737599D01*
G01X741929D02*
X741536D01*
G01X769489D02*
X769095D01*
G01X773426D02*
X773032D01*
G01X771457D02*
X771063D01*
G01X777363D02*
X776969D01*
G01X775394D02*
X775000D01*
G01X779331D02*
X778937D01*
G01X783268D02*
X782874D01*
G01X781300D02*
X780906D01*
G01X785237D02*
X784843D01*
G01X779528Y520808D02*
X779069Y520741D01*
G01X779594Y520540D02*
X779134Y520473D01*
G01Y522617D02*
X778741Y522550D01*
G01X778675Y522215D02*
X778478Y522014D01*
G01X778347Y522349D02*
X778216Y522215D01*
G01X776116Y522148D02*
X775985Y522014D01*
G01X776116Y522416D02*
X775985Y522282D01*
G01X773557Y522483D02*
X773426Y522349D01*
G01X771588Y522282D02*
X771523Y522215D01*
G01X771588Y522550D02*
X771391Y522349D01*
G01X770538Y522282D02*
X770407Y522148D01*
G01X770538Y522550D02*
X770407Y522416D01*
G01X773950Y522617D02*
X773688Y522550D01*
G01X773950Y522282D02*
X773688Y522215D01*
G01X776575Y522617D02*
X776313Y522550D01*
G01X776575Y522349D02*
X776313Y522282D01*
G01X779069Y522349D02*
X778806Y522282D01*
G01X774475Y520875D02*
X774213Y520808D01*
G01X781562Y522617D02*
X781300Y522550D01*
G01X781562Y522349D02*
X781300Y522282D01*
G01X774607Y520540D02*
X774344Y520473D01*
G01X783793Y522617D02*
X783531Y522550D01*
G01X783924Y522349D02*
X783662Y522282D01*
G01X784449Y520808D02*
X784187Y520741D01*
G01X784580Y520540D02*
X784318Y520473D01*
G01X779725Y520942D02*
X779528Y520808D01*
G01X781300Y522282D02*
X781103Y522148D01*
G01X781300Y522550D02*
X781103Y522416D01*
G01X778544Y522483D02*
X778347Y522349D01*
G01X774804Y520674D02*
X774607Y520540D01*
G01X774672Y521009D02*
X774475Y520875D01*
G01X776313Y522282D02*
X776116Y522148D01*
G01X776313Y522550D02*
X776116Y522416D01*
G01X773688Y522215D02*
X773491Y522081D01*
G01X784712Y520607D02*
X784580Y520540D01*
G01X779856Y520674D02*
X779594Y520540D01*
G01X783531Y522550D02*
X783399Y522483D01*
G01X778806Y522282D02*
X778675Y522215D01*
G01X773688Y522550D02*
X773557Y522483D01*
G01X771720Y522349D02*
X771588Y522282D01*
G01X778741Y522550D02*
X778544Y522483D01*
G01X771785Y522617D02*
X771588Y522550D01*
G01X770735Y522349D02*
X770538Y522282D01*
G01X770735Y522617D02*
X770538Y522550D01*
G01X717150Y762380D02*
Y765180D01*
G01X738702Y1463291D02*
Y1444354D01*
G01X805315Y-511D02*
G03X816733I5709J0D01*
G01X824804Y29410D02*
Y4410D01*
G01X822835D02*
Y29410D01*
G01X822402Y25394D02*
Y23426D01*
G01X822244Y11890D02*
Y4410D01*
G01X822008Y25394D02*
Y29410D01*
G01Y25394D02*
Y23426D01*
G01X820040Y25394D02*
Y29410D01*
G01Y25394D02*
Y23426D01*
G01X819646Y25394D02*
Y23426D01*
G01X817323Y11890D02*
Y4016D01*
G01X817171Y11890D02*
Y4410D01*
G01X816733Y4016D02*
Y-511D01*
G01X812402Y25394D02*
Y23426D01*
G01X812008Y25394D02*
Y29410D01*
G01Y25394D02*
Y23426D01*
G01X810040Y25394D02*
Y23426D01*
G01Y29410D02*
Y25394D01*
G01X809646D02*
Y23426D01*
G01X805315Y4016D02*
Y-511D01*
G01X804877Y11890D02*
Y4410D01*
G01X804725Y11890D02*
Y4016D01*
G01X802402Y25394D02*
Y23426D01*
G01X802008Y25394D02*
Y29410D01*
G01Y25394D02*
Y23426D01*
G01X800040Y25394D02*
Y29410D01*
G01Y25394D02*
Y23426D01*
G01X799804Y11890D02*
Y4410D01*
G01X799646Y25394D02*
Y23426D01*
G01X799213Y29410D02*
Y4410D01*
G01X797244Y29410D02*
Y4410D01*
G01X822008Y29410D02*
X824804D01*
G01X797244D02*
X800040D01*
G01X810040D02*
X802008D01*
G01X820040D02*
X812008D01*
G01X802402Y25394D02*
X799646D01*
G01X812402D02*
X809646D01*
G01X822402D02*
X819646D01*
G01X802402Y23426D02*
X799646D01*
G01X812402D02*
X809646D01*
G01X822402D02*
X819646D01*
G01X817323Y11890D02*
X822244D01*
G01X804725D02*
X799804D01*
G01X817323D02*
X804725D01*
G01X824804Y4410D02*
X797244D01*
G01X817323Y4016D02*
X804725D01*
G01X816733Y-511D02*
X805315D01*
G01X811024Y86811D02*
G03X798426I-6299J0D01*
G01Y80512D02*
G03X811024I6299J0D01*
G01Y86811D02*
Y80512D01*
G01X798426Y86811D02*
Y80512D01*
G01X811024Y204922D02*
G03X798426I-6299J0D01*
G01Y198622D02*
G03X811024I6299J0D01*
G01Y204922D02*
Y198622D01*
G01X798426Y204922D02*
Y198622D01*
G01X787359Y513302D02*
X787363Y513274D01*
G01X787347Y513328D02*
X787359Y513302D01*
G01X787329Y513352D02*
X787347Y513328D01*
G01X787305Y513373D02*
X787329Y513352D01*
G01X787275Y513391D02*
X787305Y513373D01*
G01X787241Y513404D02*
X787275Y513391D01*
G01X787204Y513412D02*
X787241Y513404D01*
G01X787166Y513414D02*
X787204Y513412D01*
G01X789327Y513302D02*
X789331Y513274D01*
G01X789316Y513328D02*
X789327Y513302D01*
G01X789298Y513352D02*
X789316Y513328D01*
G01X789273Y513373D02*
X789298Y513352D01*
G01X789243Y513391D02*
X789273Y513373D01*
G01X789209Y513404D02*
X789243Y513391D01*
G01X789172Y513412D02*
X789209Y513404D01*
G01X789134Y513414D02*
X789172Y513412D01*
G01X791296Y513302D02*
X791300Y513274D01*
G01X791284Y513328D02*
X791296Y513302D01*
G01X791266Y513352D02*
X791284Y513328D01*
G01X791242Y513373D02*
X791266Y513352D01*
G01X791212Y513391D02*
X791242Y513373D01*
G01X791178Y513404D02*
X791212Y513391D01*
G01X791141Y513412D02*
X791178Y513404D01*
G01X791103Y513414D02*
X791141Y513412D01*
G01X793264Y513302D02*
X793268Y513274D01*
G01X793253Y513328D02*
X793264Y513302D01*
G01X793235Y513352D02*
X793253Y513328D01*
G01X793210Y513373D02*
X793235Y513352D01*
G01X793180Y513391D02*
X793210Y513373D01*
G01X793146Y513404D02*
X793180Y513391D01*
G01X793109Y513412D02*
X793146Y513404D01*
G01X793071Y513414D02*
X793109Y513412D01*
G01X795233Y513302D02*
X795237Y513274D01*
G01X795221Y513328D02*
X795233Y513302D01*
G01X795203Y513352D02*
X795221Y513328D01*
G01X795179Y513373D02*
X795203Y513352D01*
G01X795149Y513391D02*
X795179Y513373D01*
G01X795115Y513404D02*
X795149Y513391D01*
G01X795078Y513412D02*
X795115Y513404D01*
G01X795040Y513414D02*
X795078Y513412D01*
G01X797201Y513302D02*
X797205Y513274D01*
G01X797190Y513328D02*
X797201Y513302D01*
G01X797172Y513352D02*
X797190Y513328D01*
G01X797147Y513373D02*
X797172Y513352D01*
G01X797117Y513391D02*
X797147Y513373D01*
G01X797083Y513404D02*
X797117Y513391D01*
G01X797046Y513412D02*
X797083Y513404D01*
G01X797008Y513414D02*
X797046Y513412D01*
G01X799170Y513302D02*
X799174Y513274D01*
G01X799158Y513328D02*
X799170Y513302D01*
G01X799140Y513352D02*
X799158Y513328D01*
G01X799116Y513373D02*
X799140Y513352D01*
G01X799086Y513391D02*
X799116Y513373D01*
G01X799052Y513404D02*
X799086Y513391D01*
G01X799015Y513412D02*
X799052Y513404D01*
G01X798977Y513414D02*
X799015Y513412D01*
G01X801138Y513302D02*
X801142Y513274D01*
G01X801127Y513328D02*
X801138Y513302D01*
G01X801109Y513352D02*
X801127Y513328D01*
G01X801084Y513373D02*
X801109Y513352D01*
G01X801054Y513391D02*
X801084Y513373D01*
G01X801020Y513404D02*
X801054Y513391D01*
G01X800983Y513412D02*
X801020Y513404D01*
G01X800945Y513414D02*
X800983Y513412D01*
G01X803107Y513302D02*
X803111Y513274D01*
G01X803095Y513328D02*
X803107Y513302D01*
G01X803077Y513352D02*
X803095Y513328D01*
G01X803053Y513373D02*
X803077Y513352D01*
G01X803023Y513391D02*
X803053Y513373D01*
G01X802989Y513404D02*
X803023Y513391D01*
G01X802952Y513412D02*
X802989Y513404D01*
G01X802914Y513414D02*
X802952Y513412D01*
G01X805075Y513302D02*
X805079Y513274D01*
G01X805064Y513328D02*
X805075Y513302D01*
G01X805046Y513352D02*
X805064Y513328D01*
G01X805021Y513373D02*
X805046Y513352D01*
G01X804991Y513391D02*
X805021Y513373D01*
G01X804957Y513404D02*
X804991Y513391D01*
G01X804920Y513412D02*
X804957Y513404D01*
G01X804882Y513414D02*
X804920Y513412D01*
G01X807044Y513302D02*
X807048Y513274D01*
G01X807032Y513328D02*
X807044Y513302D01*
G01X807014Y513352D02*
X807032Y513328D01*
G01X806990Y513373D02*
X807014Y513352D01*
G01X806960Y513391D02*
X806990Y513373D01*
G01X806926Y513404D02*
X806960Y513391D01*
G01X806889Y513412D02*
X806926Y513404D01*
G01X806851Y513414D02*
X806889Y513412D01*
G01X809012Y513302D02*
X809016Y513274D01*
G01X809001Y513328D02*
X809012Y513302D01*
G01X808983Y513352D02*
X809001Y513328D01*
G01X808958Y513373D02*
X808983Y513352D01*
G01X808928Y513391D02*
X808958Y513373D01*
G01X808894Y513404D02*
X808928Y513391D01*
G01X808857Y513412D02*
X808894Y513404D01*
G01X808819Y513414D02*
X808857Y513412D01*
G01X810981Y513302D02*
X810985Y513274D01*
G01X810969Y513328D02*
X810981Y513302D01*
G01X810951Y513352D02*
X810969Y513328D01*
G01X810927Y513373D02*
X810951Y513352D01*
G01X810897Y513391D02*
X810927Y513373D01*
G01X810863Y513404D02*
X810897Y513391D01*
G01X810826Y513412D02*
X810863Y513404D01*
G01X810788Y513414D02*
X810826Y513412D01*
G01X812949Y513302D02*
X812953Y513274D01*
G01X812938Y513328D02*
X812949Y513302D01*
G01X812920Y513352D02*
X812938Y513328D01*
G01X812895Y513373D02*
X812920Y513352D01*
G01X812865Y513391D02*
X812895Y513373D01*
G01X812831Y513404D02*
X812865Y513391D01*
G01X812795Y513412D02*
X812831Y513404D01*
G01X812756Y513414D02*
X812795Y513412D01*
G01X814918Y513302D02*
X814922Y513274D01*
G01X814907Y513328D02*
X814918Y513302D01*
G01X814888Y513352D02*
X814907Y513328D01*
G01X814864Y513373D02*
X814888Y513352D01*
G01X814834Y513391D02*
X814864Y513373D01*
G01X814800Y513404D02*
X814834Y513391D01*
G01X814763Y513412D02*
X814800Y513404D01*
G01X814725Y513414D02*
X814763Y513412D01*
G01X816886Y513302D02*
X816890Y513274D01*
G01X816875Y513328D02*
X816886Y513302D01*
G01X816857Y513352D02*
X816875Y513328D01*
G01X816832Y513373D02*
X816857Y513352D01*
G01X816802Y513391D02*
X816832Y513373D01*
G01X816768Y513404D02*
X816802Y513391D01*
G01X816732Y513412D02*
X816768Y513404D01*
G01X816693Y513414D02*
X816732Y513412D01*
G01X818855Y513302D02*
X818859Y513274D01*
G01X818844Y513328D02*
X818855Y513302D01*
G01X818825Y513352D02*
X818844Y513328D01*
G01X818801Y513373D02*
X818825Y513352D01*
G01X818771Y513391D02*
X818801Y513373D01*
G01X818737Y513404D02*
X818771Y513391D01*
G01X818700Y513412D02*
X818737Y513404D01*
G01X818662Y513414D02*
X818700Y513412D01*
G01X820823Y513302D02*
X820827Y513274D01*
G01X820812Y513328D02*
X820823Y513302D01*
G01X820794Y513352D02*
X820812Y513328D01*
G01X820769Y513373D02*
X820794Y513352D01*
G01X820739Y513391D02*
X820769Y513373D01*
G01X820705Y513404D02*
X820739Y513391D01*
G01X820669Y513412D02*
X820705Y513404D01*
G01X820630Y513414D02*
X820669Y513412D01*
G01X822792Y513302D02*
X822796Y513274D01*
G01X822781Y513328D02*
X822792Y513302D01*
G01X822762Y513352D02*
X822781Y513328D01*
G01X822738Y513373D02*
X822762Y513352D01*
G01X822708Y513391D02*
X822738Y513373D01*
G01X822674Y513404D02*
X822708Y513391D01*
G01X822637Y513412D02*
X822674Y513404D01*
G01X822599Y513414D02*
X822637Y513412D01*
G01X824760Y513302D02*
X824764Y513274D01*
G01X824749Y513328D02*
X824760Y513302D01*
G01X824731Y513352D02*
X824749Y513328D01*
G01X824706Y513373D02*
X824731Y513352D01*
G01X824676Y513391D02*
X824706Y513373D01*
G01X824642Y513404D02*
X824676Y513391D01*
G01X824606Y513412D02*
X824642Y513404D01*
G01X824567Y513414D02*
X824606Y513412D01*
G01X834603Y513302D02*
X834607Y513274D01*
G01X834592Y513328D02*
X834603Y513302D01*
G01X834573Y513352D02*
X834592Y513328D01*
G01X834549Y513373D02*
X834573Y513352D01*
G01X834519Y513391D02*
X834549Y513373D01*
G01X834485Y513404D02*
X834519Y513391D01*
G01X834448Y513412D02*
X834485Y513404D01*
G01X834410Y513414D02*
X834448Y513412D01*
G01X836571Y513302D02*
X836575Y513274D01*
G01X836560Y513328D02*
X836571Y513302D01*
G01X836542Y513352D02*
X836560Y513328D01*
G01X836518Y513373D02*
X836542Y513352D01*
G01X836487Y513391D02*
X836518Y513373D01*
G01X836453Y513404D02*
X836487Y513391D01*
G01X836417Y513412D02*
X836453Y513404D01*
G01X836378Y513414D02*
X836417Y513412D01*
G01X838540Y513302D02*
X838544Y513274D01*
G01X838529Y513328D02*
X838540Y513302D01*
G01X838510Y513352D02*
X838529Y513328D01*
G01X838486Y513373D02*
X838510Y513352D01*
G01X838456Y513391D02*
X838486Y513373D01*
G01X838422Y513404D02*
X838456Y513391D01*
G01X838385Y513412D02*
X838422Y513404D01*
G01X838347Y513414D02*
X838385Y513412D01*
G01X840508Y513302D02*
X840512Y513274D01*
G01X840497Y513328D02*
X840508Y513302D01*
G01X840479Y513352D02*
X840497Y513328D01*
G01X840455Y513373D02*
X840479Y513352D01*
G01X840424Y513391D02*
X840455Y513373D01*
G01X840390Y513404D02*
X840424Y513391D01*
G01X840354Y513412D02*
X840390Y513404D01*
G01X840315Y513414D02*
X840354Y513412D01*
G01X787355Y513069D02*
X787363Y512993D01*
G01X787336Y513132D02*
X787355Y513069D01*
G01X787309Y513183D02*
X787336Y513132D01*
G01X787276Y513222D02*
X787309Y513183D01*
G01X787241Y513249D02*
X787276Y513222D01*
G01X787204Y513265D02*
X787241Y513249D01*
G01X787166Y513270D02*
X787204Y513265D01*
G01X789324Y513069D02*
X789331Y512993D01*
G01X789305Y513132D02*
X789324Y513069D01*
G01X789277Y513183D02*
X789305Y513132D01*
G01X789245Y513222D02*
X789277Y513183D01*
G01X789209Y513249D02*
X789245Y513222D01*
G01X789173Y513265D02*
X789209Y513249D01*
G01X789134Y513270D02*
X789173Y513265D01*
G01X791292Y513069D02*
X791300Y512993D01*
G01X791273Y513132D02*
X791292Y513069D01*
G01X791246Y513183D02*
X791273Y513132D01*
G01X791213Y513222D02*
X791246Y513183D01*
G01X791178Y513249D02*
X791213Y513222D01*
G01X791141Y513265D02*
X791178Y513249D01*
G01X791103Y513270D02*
X791141Y513265D01*
G01X793261Y513069D02*
X793268Y512993D01*
G01X793242Y513132D02*
X793261Y513069D01*
G01X793214Y513183D02*
X793242Y513132D01*
G01X793182Y513222D02*
X793214Y513183D01*
G01X793146Y513249D02*
X793182Y513222D01*
G01X793110Y513265D02*
X793146Y513249D01*
G01X793071Y513270D02*
X793110Y513265D01*
G01X795229Y513069D02*
X795237Y512993D01*
G01X795210Y513132D02*
X795229Y513069D01*
G01X795183Y513183D02*
X795210Y513132D01*
G01X795150Y513222D02*
X795183Y513183D01*
G01X795115Y513249D02*
X795150Y513222D01*
G01X795078Y513265D02*
X795115Y513249D01*
G01X795040Y513270D02*
X795078Y513265D01*
G01X797198Y513069D02*
X797205Y512993D01*
G01X797179Y513132D02*
X797198Y513069D01*
G01X797151Y513183D02*
X797179Y513132D01*
G01X797119Y513222D02*
X797151Y513183D01*
G01X797083Y513249D02*
X797119Y513222D01*
G01X797047Y513265D02*
X797083Y513249D01*
G01X797008Y513270D02*
X797047Y513265D01*
G01X799166Y513069D02*
X799174Y512993D01*
G01X799147Y513132D02*
X799166Y513069D01*
G01X799120Y513183D02*
X799147Y513132D01*
G01X799087Y513222D02*
X799120Y513183D01*
G01X799052Y513249D02*
X799087Y513222D01*
G01X799015Y513265D02*
X799052Y513249D01*
G01X798977Y513270D02*
X799015Y513265D01*
G01X801135Y513069D02*
X801142Y512993D01*
G01X801116Y513132D02*
X801135Y513069D01*
G01X801088Y513183D02*
X801116Y513132D01*
G01X801056Y513222D02*
X801088Y513183D01*
G01X801020Y513249D02*
X801056Y513222D01*
G01X800984Y513265D02*
X801020Y513249D01*
G01X800945Y513270D02*
X800984Y513265D01*
G01X803103Y513069D02*
X803111Y512993D01*
G01X803084Y513132D02*
X803103Y513069D01*
G01X803057Y513183D02*
X803084Y513132D01*
G01X803024Y513222D02*
X803057Y513183D01*
G01X802989Y513249D02*
X803024Y513222D01*
G01X802952Y513265D02*
X802989Y513249D01*
G01X802914Y513270D02*
X802952Y513265D01*
G01X805072Y513069D02*
X805079Y512993D01*
G01X805053Y513132D02*
X805072Y513069D01*
G01X805025Y513183D02*
X805053Y513132D01*
G01X804993Y513222D02*
X805025Y513183D01*
G01X804957Y513249D02*
X804993Y513222D01*
G01X804921Y513265D02*
X804957Y513249D01*
G01X804882Y513270D02*
X804921Y513265D01*
G01X807040Y513069D02*
X807048Y512993D01*
G01X807021Y513132D02*
X807040Y513069D01*
G01X806994Y513183D02*
X807021Y513132D01*
G01X806961Y513222D02*
X806994Y513183D01*
G01X806926Y513249D02*
X806961Y513222D01*
G01X806889Y513265D02*
X806926Y513249D01*
G01X806851Y513270D02*
X806889Y513265D01*
G01X809009Y513069D02*
X809016Y512993D01*
G01X808990Y513132D02*
X809009Y513069D01*
G01X808962Y513183D02*
X808990Y513132D01*
G01X808930Y513222D02*
X808962Y513183D01*
G01X808894Y513249D02*
X808930Y513222D01*
G01X808858Y513265D02*
X808894Y513249D01*
G01X808819Y513270D02*
X808858Y513265D01*
G01X810977Y513069D02*
X810985Y512993D01*
G01X810958Y513132D02*
X810977Y513069D01*
G01X810931Y513183D02*
X810958Y513132D01*
G01X810898Y513222D02*
X810931Y513183D01*
G01X810863Y513249D02*
X810898Y513222D01*
G01X810826Y513265D02*
X810863Y513249D01*
G01X810788Y513270D02*
X810826Y513265D01*
G01X812946Y513069D02*
X812953Y512993D01*
G01X812927Y513132D02*
X812946Y513069D01*
G01X812899Y513183D02*
X812927Y513132D01*
G01X812867Y513222D02*
X812899Y513183D01*
G01X812831Y513249D02*
X812867Y513222D01*
G01X812795Y513265D02*
X812831Y513249D01*
G01X812756Y513270D02*
X812795Y513265D01*
G01X814914Y513069D02*
X814922Y512993D01*
G01X814895Y513132D02*
X814914Y513069D01*
G01X814868Y513183D02*
X814895Y513132D01*
G01X814835Y513222D02*
X814868Y513183D01*
G01X814800Y513249D02*
X814835Y513222D01*
G01X814763Y513265D02*
X814800Y513249D01*
G01X814725Y513270D02*
X814763Y513265D01*
G01X816883Y513069D02*
X816890Y512993D01*
G01X816864Y513132D02*
X816883Y513069D01*
G01X816836Y513183D02*
X816864Y513132D01*
G01X816804Y513222D02*
X816836Y513183D01*
G01X816768Y513249D02*
X816804Y513222D01*
G01X816732Y513265D02*
X816768Y513249D01*
G01X816693Y513270D02*
X816732Y513265D01*
G01X818851Y513069D02*
X818859Y512993D01*
G01X818832Y513132D02*
X818851Y513069D01*
G01X818805Y513183D02*
X818832Y513132D01*
G01X818772Y513222D02*
X818805Y513183D01*
G01X818737Y513249D02*
X818772Y513222D01*
G01X818700Y513265D02*
X818737Y513249D01*
G01X818662Y513270D02*
X818700Y513265D01*
G01X820820Y513069D02*
X820827Y512993D01*
G01X820801Y513132D02*
X820820Y513069D01*
G01X820773Y513183D02*
X820801Y513132D01*
G01X820741Y513222D02*
X820773Y513183D01*
G01X820705Y513249D02*
X820741Y513222D01*
G01X820669Y513265D02*
X820705Y513249D01*
G01X820630Y513270D02*
X820669Y513265D01*
G01X822788Y513069D02*
X822796Y512993D01*
G01X822769Y513132D02*
X822788Y513069D01*
G01X822742Y513183D02*
X822769Y513132D01*
G01X822709Y513222D02*
X822742Y513183D01*
G01X822674Y513249D02*
X822709Y513222D01*
G01X822637Y513265D02*
X822674Y513249D01*
G01X822599Y513270D02*
X822637Y513265D01*
G01X824757Y513069D02*
X824764Y512993D01*
G01X824738Y513132D02*
X824757Y513069D01*
G01X824710Y513183D02*
X824738Y513132D01*
G01X824678Y513222D02*
X824710Y513183D01*
G01X824643Y513249D02*
X824678Y513222D01*
G01X824606Y513265D02*
X824643Y513249D01*
G01X824567Y513270D02*
X824606Y513265D01*
G01X834599Y513069D02*
X834607Y512993D01*
G01X834580Y513132D02*
X834599Y513069D01*
G01X834553Y513183D02*
X834580Y513132D01*
G01X834520Y513222D02*
X834553Y513183D01*
G01X834485Y513249D02*
X834520Y513222D01*
G01X834448Y513265D02*
X834485Y513249D01*
G01X834410Y513270D02*
X834448Y513265D01*
G01X836568Y513069D02*
X836575Y512993D01*
G01X836549Y513132D02*
X836568Y513069D01*
G01X836521Y513183D02*
X836549Y513132D01*
G01X836489Y513222D02*
X836521Y513183D01*
G01X836454Y513249D02*
X836489Y513222D01*
G01X836417Y513265D02*
X836454Y513249D01*
G01X836378Y513270D02*
X836417Y513265D01*
G01X838536Y513069D02*
X838544Y512993D01*
G01X838517Y513132D02*
X838536Y513069D01*
G01X838490Y513183D02*
X838517Y513132D01*
G01X838457Y513222D02*
X838490Y513183D01*
G01X838422Y513249D02*
X838457Y513222D01*
G01X838385Y513265D02*
X838422Y513249D01*
G01X838347Y513270D02*
X838385Y513265D01*
G01X840505Y513069D02*
X840512Y512993D01*
G01X840486Y513132D02*
X840505Y513069D01*
G01X840458Y513183D02*
X840486Y513132D01*
G01X840426Y513222D02*
X840458Y513183D01*
G01X840391Y513249D02*
X840426Y513222D01*
G01X840354Y513265D02*
X840391Y513249D01*
G01X840315Y513270D02*
X840354Y513265D01*
G01X786812D02*
X786851Y513270D01*
G01X786776Y513249D02*
X786812Y513265D01*
G01X786740Y513222D02*
X786776Y513249D01*
G01X786654Y512993D02*
X786661Y513069D01*
G01X788781Y513265D02*
X788819Y513270D01*
G01X788744Y513249D02*
X788781Y513265D01*
G01X788709Y513222D02*
X788744Y513249D01*
G01X788676Y513183D02*
X788709Y513222D01*
G01X788649Y513132D02*
X788676Y513183D01*
G01X788630Y513069D02*
X788649Y513132D01*
G01X788622Y512993D02*
X788630Y513069D01*
G01X790749Y513265D02*
X790788Y513270D01*
G01X790713Y513249D02*
X790749Y513265D01*
G01X790677Y513222D02*
X790713Y513249D01*
G01X790645Y513183D02*
X790677Y513222D01*
G01X790617Y513132D02*
X790645Y513183D01*
G01X790598Y513069D02*
X790617Y513132D01*
G01X790591Y512993D02*
X790598Y513069D01*
G01X792718Y513265D02*
X792756Y513270D01*
G01X792681Y513249D02*
X792718Y513265D01*
G01X792646Y513222D02*
X792681Y513249D01*
G01X792613Y513183D02*
X792646Y513222D01*
G01X792586Y513132D02*
X792613Y513183D01*
G01X792567Y513069D02*
X792586Y513132D01*
G01X792559Y512993D02*
X792567Y513069D01*
G01X794686Y513265D02*
X794725Y513270D01*
G01X794650Y513249D02*
X794686Y513265D01*
G01X794614Y513222D02*
X794650Y513249D01*
G01X794582Y513183D02*
X794614Y513222D01*
G01X794554Y513132D02*
X794582Y513183D01*
G01X794535Y513069D02*
X794554Y513132D01*
G01X794528Y512993D02*
X794535Y513069D01*
G01X796655Y513265D02*
X796693Y513270D01*
G01X796618Y513249D02*
X796655Y513265D01*
G01X796583Y513222D02*
X796618Y513249D01*
G01X796550Y513183D02*
X796583Y513222D01*
G01X796523Y513132D02*
X796550Y513183D01*
G01X796504Y513069D02*
X796523Y513132D01*
G01X796496Y512993D02*
X796504Y513069D01*
G01X798623Y513265D02*
X798662Y513270D01*
G01X798587Y513249D02*
X798623Y513265D01*
G01X798551Y513222D02*
X798587Y513249D01*
G01X798519Y513183D02*
X798551Y513222D01*
G01X798491Y513132D02*
X798519Y513183D01*
G01X798472Y513069D02*
X798491Y513132D01*
G01X798465Y512993D02*
X798472Y513069D01*
G01X800592Y513265D02*
X800630Y513270D01*
G01X800555Y513249D02*
X800592Y513265D01*
G01X800520Y513222D02*
X800555Y513249D01*
G01X800487Y513183D02*
X800520Y513222D01*
G01X800460Y513132D02*
X800487Y513183D01*
G01X800441Y513069D02*
X800460Y513132D01*
G01X800433Y512993D02*
X800441Y513069D01*
G01X802560Y513265D02*
X802599Y513270D01*
G01X802524Y513249D02*
X802560Y513265D01*
G01X802488Y513222D02*
X802524Y513249D01*
G01X802456Y513183D02*
X802488Y513222D01*
G01X802428Y513132D02*
X802456Y513183D01*
G01X802409Y513069D02*
X802428Y513132D01*
G01X802402Y512993D02*
X802409Y513069D01*
G01X786812Y513412D02*
X786851Y513414D01*
G01X786775Y513404D02*
X786812Y513412D01*
G01X786741Y513391D02*
X786775Y513404D01*
G01X786712Y513373D02*
X786741Y513391D01*
G01X786654Y513274D02*
X786658Y513302D01*
G01X788780Y513412D02*
X788819Y513414D01*
G01X788744Y513404D02*
X788780Y513412D01*
G01X788710Y513391D02*
X788744Y513404D01*
G01X788680Y513373D02*
X788710Y513391D01*
G01X788655Y513352D02*
X788680Y513373D01*
G01X788637Y513328D02*
X788655Y513352D01*
G01X788626Y513302D02*
X788637Y513328D01*
G01X788622Y513274D02*
X788626Y513302D01*
G01X790749Y513412D02*
X790788Y513414D01*
G01X790712Y513404D02*
X790749Y513412D01*
G01X790678Y513391D02*
X790712Y513404D01*
G01X790649Y513373D02*
X790678Y513391D01*
G01X790624Y513352D02*
X790649Y513373D01*
G01X790606Y513328D02*
X790624Y513352D01*
G01X790595Y513302D02*
X790606Y513328D01*
G01X790591Y513274D02*
X790595Y513302D01*
G01X792717Y513412D02*
X792756Y513414D01*
G01X792681Y513404D02*
X792717Y513412D01*
G01X792647Y513391D02*
X792681Y513404D01*
G01X792617Y513373D02*
X792647Y513391D01*
G01X792592Y513352D02*
X792617Y513373D01*
G01X792574Y513328D02*
X792592Y513352D01*
G01X792563Y513302D02*
X792574Y513328D01*
G01X792559Y513274D02*
X792563Y513302D01*
G01X794686Y513412D02*
X794725Y513414D01*
G01X794649Y513404D02*
X794686Y513412D01*
G01X794615Y513391D02*
X794649Y513404D01*
G01X794586Y513373D02*
X794615Y513391D01*
G01X794561Y513352D02*
X794586Y513373D01*
G01X794543Y513328D02*
X794561Y513352D01*
G01X794532Y513302D02*
X794543Y513328D01*
G01X794528Y513274D02*
X794532Y513302D01*
G01X796654Y513412D02*
X796693Y513414D01*
G01X796618Y513404D02*
X796654Y513412D01*
G01X796584Y513391D02*
X796618Y513404D01*
G01X796554Y513373D02*
X796584Y513391D01*
G01X796529Y513352D02*
X796554Y513373D01*
G01X796511Y513328D02*
X796529Y513352D01*
G01X796500Y513302D02*
X796511Y513328D01*
G01X796496Y513274D02*
X796500Y513302D01*
G01X798623Y513412D02*
X798662Y513414D01*
G01X798586Y513404D02*
X798623Y513412D01*
G01X798552Y513391D02*
X798586Y513404D01*
G01X798523Y513373D02*
X798552Y513391D01*
G01X798498Y513352D02*
X798523Y513373D01*
G01X798480Y513328D02*
X798498Y513352D01*
G01X798469Y513302D02*
X798480Y513328D01*
G01X798465Y513274D02*
X798469Y513302D01*
G01X800591Y513412D02*
X800630Y513414D01*
G01X800555Y513404D02*
X800591Y513412D01*
G01X800521Y513391D02*
X800555Y513404D01*
G01X800491Y513373D02*
X800521Y513391D01*
G01X800466Y513352D02*
X800491Y513373D01*
G01X800448Y513328D02*
X800466Y513352D01*
G01X800437Y513302D02*
X800448Y513328D01*
G01X800433Y513274D02*
X800437Y513302D01*
G01X802560Y513412D02*
X802599Y513414D01*
G01X802523Y513404D02*
X802560Y513412D01*
G01X802489Y513391D02*
X802523Y513404D01*
G01X802460Y513373D02*
X802489Y513391D01*
G01X802435Y513352D02*
X802460Y513373D01*
G01X802417Y513328D02*
X802435Y513352D01*
G01X802406Y513302D02*
X802417Y513328D01*
G01X802402Y513274D02*
X802406Y513302D01*
G01X804528Y513412D02*
X804567Y513414D01*
G01X804492Y513404D02*
X804528Y513412D01*
G01X804458Y513391D02*
X804492Y513404D01*
G01X804428Y513373D02*
X804458Y513391D01*
G01X804403Y513352D02*
X804428Y513373D01*
G01X804385Y513328D02*
X804403Y513352D01*
G01X804374Y513302D02*
X804385Y513328D01*
G01X804370Y513274D02*
X804374Y513302D01*
G01X806497Y513412D02*
X806536Y513414D01*
G01X806460Y513404D02*
X806497Y513412D01*
G01X806426Y513391D02*
X806460Y513404D01*
G01X806397Y513373D02*
X806426Y513391D01*
G01X806372Y513352D02*
X806397Y513373D01*
G01X806354Y513328D02*
X806372Y513352D01*
G01X806343Y513302D02*
X806354Y513328D01*
G01X806339Y513274D02*
X806343Y513302D01*
G01X808465Y513412D02*
X808504Y513414D01*
G01X808429Y513404D02*
X808465Y513412D01*
G01X808395Y513391D02*
X808429Y513404D01*
G01X808365Y513373D02*
X808395Y513391D01*
G01X808340Y513352D02*
X808365Y513373D01*
G01X808322Y513328D02*
X808340Y513352D01*
G01X808311Y513302D02*
X808322Y513328D01*
G01X808307Y513274D02*
X808311Y513302D01*
G01X810434Y513412D02*
X810473Y513414D01*
G01X810397Y513404D02*
X810434Y513412D01*
G01X810363Y513391D02*
X810397Y513404D01*
G01X810334Y513373D02*
X810363Y513391D01*
G01X810309Y513352D02*
X810334Y513373D01*
G01X810291Y513328D02*
X810309Y513352D01*
G01X810280Y513302D02*
X810291Y513328D01*
G01X810276Y513274D02*
X810280Y513302D01*
G01X804529Y513265D02*
X804567Y513270D01*
G01X804492Y513249D02*
X804529Y513265D01*
G01X804457Y513222D02*
X804492Y513249D01*
G01X804424Y513183D02*
X804457Y513222D01*
G01X804397Y513132D02*
X804424Y513183D01*
G01X804378Y513069D02*
X804397Y513132D01*
G01X804370Y512993D02*
X804378Y513069D01*
G01X806497Y513265D02*
X806536Y513270D01*
G01X806461Y513249D02*
X806497Y513265D01*
G01X806425Y513222D02*
X806461Y513249D01*
G01X806393Y513183D02*
X806425Y513222D01*
G01X806365Y513132D02*
X806393Y513183D01*
G01X806346Y513069D02*
X806365Y513132D01*
G01X806339Y512993D02*
X806346Y513069D01*
G01X808466Y513265D02*
X808504Y513270D01*
G01X808429Y513249D02*
X808466Y513265D01*
G01X808394Y513222D02*
X808429Y513249D01*
G01X808361Y513183D02*
X808394Y513222D01*
G01X808334Y513132D02*
X808361Y513183D01*
G01X808315Y513069D02*
X808334Y513132D01*
G01X808307Y512993D02*
X808315Y513069D01*
G01X810434Y513265D02*
X810473Y513270D01*
G01X810398Y513249D02*
X810434Y513265D01*
G01X810362Y513222D02*
X810398Y513249D01*
G01X810330Y513183D02*
X810362Y513222D01*
G01X810302Y513132D02*
X810330Y513183D01*
G01X810283Y513069D02*
X810302Y513132D01*
G01X810276Y512993D02*
X810283Y513069D01*
G01X812403Y513265D02*
X812441Y513270D01*
G01X812366Y513249D02*
X812403Y513265D01*
G01X812331Y513222D02*
X812366Y513249D01*
G01X812298Y513183D02*
X812331Y513222D01*
G01X812271Y513132D02*
X812298Y513183D01*
G01X812252Y513069D02*
X812271Y513132D01*
G01X812244Y512993D02*
X812252Y513069D01*
G01X814371Y513265D02*
X814410Y513270D01*
G01X814335Y513249D02*
X814371Y513265D01*
G01X814299Y513222D02*
X814335Y513249D01*
G01X814267Y513183D02*
X814299Y513222D01*
G01X814239Y513132D02*
X814267Y513183D01*
G01X814220Y513069D02*
X814239Y513132D01*
G01X814213Y512993D02*
X814220Y513069D01*
G01X816340Y513265D02*
X816378Y513270D01*
G01X816303Y513249D02*
X816340Y513265D01*
G01X816268Y513222D02*
X816303Y513249D01*
G01X816235Y513183D02*
X816268Y513222D01*
G01X816208Y513132D02*
X816235Y513183D01*
G01X816189Y513069D02*
X816208Y513132D01*
G01X816181Y512993D02*
X816189Y513069D01*
G01X818308Y513265D02*
X818347Y513270D01*
G01X818272Y513249D02*
X818308Y513265D01*
G01X818236Y513222D02*
X818272Y513249D01*
G01X818204Y513183D02*
X818236Y513222D01*
G01X818176Y513132D02*
X818204Y513183D01*
G01X818157Y513069D02*
X818176Y513132D01*
G01X818150Y512993D02*
X818157Y513069D01*
G01X820277Y513265D02*
X820315Y513270D01*
G01X820240Y513249D02*
X820277Y513265D01*
G01X820205Y513222D02*
X820240Y513249D01*
G01X820172Y513183D02*
X820205Y513222D01*
G01X820145Y513132D02*
X820172Y513183D01*
G01X820126Y513069D02*
X820145Y513132D01*
G01X820118Y512993D02*
X820126Y513069D01*
G01X822245Y513265D02*
X822284Y513270D01*
G01X822209Y513249D02*
X822245Y513265D01*
G01X822173Y513222D02*
X822209Y513249D01*
G01X822141Y513183D02*
X822173Y513222D01*
G01X822113Y513132D02*
X822141Y513183D01*
G01X822094Y513069D02*
X822113Y513132D01*
G01X822087Y512993D02*
X822094Y513069D01*
G01X824214Y513265D02*
X824252Y513270D01*
G01X824177Y513249D02*
X824214Y513265D01*
G01X824142Y513222D02*
X824177Y513249D01*
G01X824109Y513183D02*
X824142Y513222D01*
G01X824082Y513132D02*
X824109Y513183D01*
G01X824063Y513069D02*
X824082Y513132D01*
G01X824055Y512993D02*
X824063Y513069D01*
G01X834056Y513265D02*
X834095Y513270D01*
G01X834020Y513249D02*
X834056Y513265D01*
G01X833984Y513222D02*
X834020Y513249D01*
G01X833952Y513183D02*
X833984Y513222D01*
G01X833924Y513132D02*
X833952Y513183D01*
G01X833905Y513069D02*
X833924Y513132D01*
G01X833898Y512993D02*
X833905Y513069D01*
G01X836025Y513265D02*
X836063Y513270D01*
G01X835988Y513249D02*
X836025Y513265D01*
G01X835953Y513222D02*
X835988Y513249D01*
G01X835920Y513183D02*
X835953Y513222D01*
G01X835893Y513132D02*
X835920Y513183D01*
G01X835874Y513069D02*
X835893Y513132D01*
G01X835867Y512993D02*
X835874Y513069D01*
G01X837993Y513265D02*
X838032Y513270D01*
G01X837957Y513249D02*
X837993Y513265D01*
G01X837921Y513222D02*
X837957Y513249D01*
G01X837889Y513183D02*
X837921Y513222D01*
G01X837862Y513132D02*
X837889Y513183D01*
G01X837842Y513069D02*
X837862Y513132D01*
G01X837835Y512993D02*
X837842Y513069D01*
G01X839962Y513265D02*
X840000Y513270D01*
G01X839925Y513249D02*
X839962Y513265D01*
G01X839890Y513222D02*
X839925Y513249D01*
G01X839857Y513183D02*
X839890Y513222D01*
G01X839830Y513132D02*
X839857Y513183D01*
G01X839811Y513069D02*
X839830Y513132D01*
G01X839804Y512993D02*
X839811Y513069D01*
G01X812402Y513412D02*
X812441Y513414D01*
G01X812366Y513404D02*
X812402Y513412D01*
G01X812332Y513391D02*
X812366Y513404D01*
G01X812302Y513373D02*
X812332Y513391D01*
G01X812277Y513352D02*
X812302Y513373D01*
G01X812259Y513328D02*
X812277Y513352D01*
G01X812248Y513302D02*
X812259Y513328D01*
G01X812244Y513274D02*
X812248Y513302D01*
G01X814371Y513412D02*
X814410Y513414D01*
G01X814334Y513404D02*
X814371Y513412D01*
G01X814300Y513391D02*
X814334Y513404D01*
G01X814271Y513373D02*
X814300Y513391D01*
G01X814246Y513352D02*
X814271Y513373D01*
G01X814228Y513328D02*
X814246Y513352D01*
G01X814217Y513302D02*
X814228Y513328D01*
G01X814213Y513274D02*
X814217Y513302D01*
G01X816339Y513412D02*
X816378Y513414D01*
G01X816303Y513404D02*
X816339Y513412D01*
G01X816269Y513391D02*
X816303Y513404D01*
G01X816239Y513373D02*
X816269Y513391D01*
G01X816214Y513352D02*
X816239Y513373D01*
G01X816196Y513328D02*
X816214Y513352D01*
G01X816185Y513302D02*
X816196Y513328D01*
G01X816181Y513274D02*
X816185Y513302D01*
G01X818308Y513412D02*
X818347Y513414D01*
G01X818271Y513404D02*
X818308Y513412D01*
G01X818237Y513391D02*
X818271Y513404D01*
G01X818208Y513373D02*
X818237Y513391D01*
G01X818183Y513352D02*
X818208Y513373D01*
G01X818165Y513328D02*
X818183Y513352D01*
G01X818154Y513302D02*
X818165Y513328D01*
G01X818150Y513274D02*
X818154Y513302D01*
G01X820276Y513412D02*
X820315Y513414D01*
G01X820240Y513404D02*
X820276Y513412D01*
G01X820206Y513391D02*
X820240Y513404D01*
G01X820176Y513373D02*
X820206Y513391D01*
G01X820151Y513352D02*
X820176Y513373D01*
G01X820133Y513328D02*
X820151Y513352D01*
G01X820122Y513302D02*
X820133Y513328D01*
G01X820118Y513274D02*
X820122Y513302D01*
G01X822245Y513412D02*
X822284Y513414D01*
G01X822208Y513404D02*
X822245Y513412D01*
G01X822174Y513391D02*
X822208Y513404D01*
G01X822145Y513373D02*
X822174Y513391D01*
G01X822120Y513352D02*
X822145Y513373D01*
G01X822102Y513328D02*
X822120Y513352D01*
G01X822091Y513302D02*
X822102Y513328D01*
G01X822087Y513274D02*
X822091Y513302D01*
G01X824213Y513412D02*
X824252Y513414D01*
G01X824177Y513404D02*
X824213Y513412D01*
G01X824143Y513391D02*
X824177Y513404D01*
G01X824113Y513373D02*
X824143Y513391D01*
G01X824088Y513352D02*
X824113Y513373D01*
G01X824070Y513328D02*
X824088Y513352D01*
G01X824059Y513302D02*
X824070Y513328D01*
G01X824055Y513274D02*
X824059Y513302D01*
G01X834056Y513412D02*
X834095Y513414D01*
G01X834019Y513404D02*
X834056Y513412D01*
G01X833985Y513391D02*
X834019Y513404D01*
G01X833956Y513373D02*
X833985Y513391D01*
G01X833931Y513352D02*
X833956Y513373D01*
G01X833913Y513328D02*
X833931Y513352D01*
G01X833902Y513302D02*
X833913Y513328D01*
G01X833898Y513274D02*
X833902Y513302D01*
G01X836024Y513412D02*
X836063Y513414D01*
G01X835988Y513404D02*
X836024Y513412D01*
G01X835954Y513391D02*
X835988Y513404D01*
G01X835924Y513373D02*
X835954Y513391D01*
G01X835899Y513352D02*
X835924Y513373D01*
G01X835881Y513328D02*
X835899Y513352D01*
G01X835870Y513302D02*
X835881Y513328D01*
G01X835867Y513274D02*
X835870Y513302D01*
G01X837993Y513412D02*
X838032Y513414D01*
G01X837956Y513404D02*
X837993Y513412D01*
G01X837922Y513391D02*
X837956Y513404D01*
G01X837893Y513373D02*
X837922Y513391D01*
G01X837868Y513352D02*
X837893Y513373D01*
G01X837850Y513328D02*
X837868Y513352D01*
G01X837839Y513302D02*
X837850Y513328D01*
G01X837835Y513274D02*
X837839Y513302D01*
G01X839961Y513412D02*
X840000Y513414D01*
G01X839925Y513404D02*
X839961Y513412D01*
G01X839891Y513391D02*
X839925Y513404D01*
G01X839861Y513373D02*
X839891Y513391D01*
G01X839836Y513352D02*
X839861Y513373D01*
G01X839818Y513328D02*
X839836Y513352D01*
G01X839807Y513302D02*
X839818Y513328D01*
G01X839804Y513274D02*
X839807Y513302D01*
G01X844685Y525197D02*
G03X845473I394J0D01*
G01Y530709D02*
G03X844685I-394J0D01*
G01X848032Y531890D02*
G03X847244Y532678I-788J0D01*
G01X846654Y531890D02*
G03X845867Y532678I-788J0D01*
G01Y523229D02*
G03X846654Y524016I0J787D01*
G01X844390Y507284D02*
G03X845571Y506103I1181J0D01*
G01X846063Y510237D02*
G03I-1968J0D01*
G01X846851D02*
G03I-2756J0D01*
G01X847244Y500591D02*
G03X848032Y501378I0J788D01*
G01X840945Y531183D02*
G03X840748Y530986I0J-197D01*
G01X841536D02*
G03X841339Y531183I-197J0D01*
G01X838977D02*
G03X838780Y530986I0J-197D01*
G01X839567D02*
G03X839370Y531183I-197J0D01*
G01X837008D02*
G03X836811Y530986I0J-197D01*
G01X837599D02*
G03X837402Y531183I-197J0D01*
G01X835040D02*
G03X834843Y530986I0J-197D01*
G01X835630D02*
G03X835433Y531183I-197J0D01*
G01X833071D02*
G03X832874Y530986I0J-197D01*
G01X833662D02*
G03X833465Y531183I-197J0D01*
G01X826674Y508268D02*
G03X831004I2165J0D01*
G01X823229Y531183D02*
G03X823032Y530986I0J-197D01*
G01X823819D02*
G03X823622Y531183I-197J0D01*
G01X821260D02*
G03X821063Y530986I0J-197D01*
G01X821851D02*
G03X821654Y531183I-197J0D01*
G01X819292D02*
G03X819095Y530986I0J-197D01*
G01X819882D02*
G03X819685Y531183I-197J0D01*
G01X817323D02*
G03X817126Y530986I0J-197D01*
G01X817914D02*
G03X817717Y531183I-197J0D01*
G01X815355D02*
G03X815158Y530986I0J-197D01*
G01X815945D02*
G03X815748Y531183I-197J0D01*
G01X813386D02*
G03X813189Y530986I0J-197D01*
G01X813977D02*
G03X813780Y531183I-197J0D01*
G01X811418D02*
G03X811221Y530986I0J-197D01*
G01X812008D02*
G03X811811Y531183I-197J0D01*
G01X840355Y499213D02*
G03X840552Y499410I0J197D01*
G01X839764D02*
G03X839961Y499213I197J0D01*
G01X838386D02*
G03X838583Y499410I0J197D01*
G01X837796D02*
G03X837992Y499213I197J0D01*
G01X836418D02*
G03X836615Y499410I0J197D01*
G01X835827D02*
G03X836024Y499213I197J0D01*
G01X834449D02*
G03X834646Y499410I0J197D01*
G01X833859D02*
G03X834055Y499213I197J0D01*
G01X824607D02*
G03X824804Y499410I0J197D01*
G01X824016D02*
G03X824213Y499213I197J0D01*
G01X822638D02*
G03X822835Y499410I0J197D01*
G01X822048D02*
G03X822244Y499213I197J0D01*
G01X820670D02*
G03X820867Y499410I0J197D01*
G01X820079D02*
G03X820276Y499213I197J0D01*
G01X818701D02*
G03X818898Y499410I0J197D01*
G01X818111D02*
G03X818307Y499213I197J0D01*
G01X816733D02*
G03X816929Y499410I0J196D01*
G01X816142D02*
G03X816339Y499213I197J0D01*
G01X814764D02*
G03X814961Y499410I0J197D01*
G01X814174D02*
G03X814370Y499213I197J0D01*
G01X812796D02*
G03X812992Y499410I0J196D01*
G01X812205D02*
G03X812402Y499213I197J0D01*
G01X809449Y531183D02*
G03X809252Y530986I0J-197D01*
G01X810040D02*
G03X809843Y531183I-197J0D01*
G01X807481D02*
G03X807284Y530986I0J-197D01*
G01X808071D02*
G03X807874Y531183I-197J0D01*
G01X805512D02*
G03X805315Y530986I0J-197D01*
G01X806103D02*
G03X805906Y531183I-197J0D01*
G01X803544D02*
G03X803347Y530986I0J-197D01*
G01X804134D02*
G03X803937Y531183I-197J0D01*
G01X801575D02*
G03X801378Y530986I0J-197D01*
G01X802166D02*
G03X801969Y531183I-197J0D01*
G01X799607D02*
G03X799410Y530986I0J-197D01*
G01X800197D02*
G03X800000Y531183I-197J0D01*
G01X797638D02*
G03X797441Y530986I0J-197D01*
G01X798229D02*
G03X798032Y531183I-197J0D01*
G01X795670D02*
G03X795473Y530986I0J-197D01*
G01X796260D02*
G03X796063Y531183I-197J0D01*
G01X793701D02*
G03X793504Y530986I0J-197D01*
G01X794292D02*
G03X794095Y531183I-197J0D01*
G01X791733D02*
G03X791536Y530986I0J-197D01*
G01X792323D02*
G03X792126Y531183I-197J0D01*
G01X789764D02*
G03X789567Y530986I0J-197D01*
G01X790355D02*
G03X790158Y531183I-197J0D01*
G01X787796D02*
G03X787599Y530986I0J-197D01*
G01X788386D02*
G03X788189Y531183I-197J0D01*
G01X810827Y499213D02*
G03X811024Y499410I0J197D01*
G01X810237D02*
G03X810433Y499213I197J0D01*
G01X808859D02*
G03X809055Y499410I0J196D01*
G01X808268D02*
G03X808465Y499213I197J0D01*
G01X806890D02*
G03X807087Y499410I0J197D01*
G01X806300D02*
G03X806496Y499213I197J0D01*
G01X804922D02*
G03X805118Y499410I0J196D01*
G01X804331D02*
G03X804528Y499213I197J0D01*
G01X802953D02*
G03X803150Y499410I0J197D01*
G01X802363D02*
G03X802559Y499213I197J0D01*
G01X800985D02*
G03X801181Y499410I0J196D01*
G01X800394D02*
G03X800591Y499213I197J0D01*
G01X799016D02*
G03X799213Y499410I0J197D01*
G01X798426D02*
G03X798622Y499213I197J0D01*
G01X797048D02*
G03X797244Y499410I0J196D01*
G01X796457D02*
G03X796654Y499213I197J0D01*
G01X795079D02*
G03X795276Y499410I0J197D01*
G01X794489D02*
G03X794685Y499213I197J0D01*
G01X793111D02*
G03X793307Y499410I0J196D01*
G01X792520D02*
G03X792717Y499213I197J0D01*
G01X791142D02*
G03X791339Y499410I0J197D01*
G01X790552D02*
G03X790748Y499213I197J0D01*
G01X789174D02*
G03X789370Y499410I0J196D01*
G01X788583D02*
G03X788780Y499213I197J0D01*
G01X787205D02*
G03X787402Y499410I0J197D01*
G01X786615D02*
G03X786811Y499213I197J0D01*
G01X841443Y510554D02*
X841536Y512214D01*
G01X841528Y512398D02*
X841483Y511604D01*
G01X839474Y510554D02*
X839567Y512214D01*
G01X839559Y512398D02*
X839515Y511604D01*
G01X837505Y510554D02*
X837599Y512214D01*
G01X837591Y512398D02*
X837546Y511604D01*
G01X841528Y512398D02*
X841536Y512555D01*
G01X839559Y512398D02*
X839567Y512555D01*
G01X837591Y512398D02*
X837599Y512555D01*
G01X841443Y510554D02*
X841483Y511604D01*
G01X839474Y510554D02*
X839515Y511604D01*
G01X837505Y510554D02*
X837546Y511604D01*
G01X835537Y510554D02*
X835578Y511604D01*
G01X848032Y531890D02*
Y500591D01*
G01X847048Y526575D02*
Y532678D01*
G01X846654Y531890D02*
Y524016D01*
G01X845571Y510040D02*
Y506103D01*
G01X845473Y530709D02*
Y525197D01*
G01X844882Y526575D02*
Y532678D01*
G01X844685Y525197D02*
Y530709D01*
G01X844390Y517126D02*
Y507284D01*
G01X844292Y523229D02*
Y532678D01*
G01X843989Y529725D02*
Y523229D01*
G01X843701Y532678D02*
Y529725D01*
G01X843307Y507596D02*
Y500591D01*
G01X843269Y532678D02*
Y529725D01*
G01X841536Y514571D02*
Y512214D01*
G01Y530986D02*
Y528665D01*
G01X840748Y512214D02*
Y514571D01*
G01Y530986D02*
Y528665D01*
G01X840552Y501731D02*
Y499410D01*
G01X840512Y513274D02*
Y509095D01*
G01X840315Y513414D02*
Y513270D01*
G01X840158Y526575D02*
Y522638D01*
G01X840000Y513270D02*
Y513414D01*
G01X839804Y513274D02*
Y509095D01*
G01X839764Y499410D02*
Y501731D01*
G01X839567Y514571D02*
Y512214D01*
G01Y530986D02*
Y528665D01*
G01X838780Y512214D02*
Y514571D01*
G01Y530986D02*
Y528665D01*
G01X838583Y501731D02*
Y499410D01*
G01X838544Y513274D02*
Y509095D01*
G01X838347Y513414D02*
Y513270D01*
G01X838189Y526575D02*
Y522638D01*
G01X838032Y513270D02*
Y513414D01*
G01X837835Y513274D02*
Y509095D01*
G01X837796Y499410D02*
Y501731D01*
G01X837599Y514571D02*
Y512214D01*
G01Y530986D02*
Y528665D01*
G01X836811Y512214D02*
Y514571D01*
G01Y530986D02*
Y528665D01*
G01X836615Y501731D02*
Y499410D01*
G01X836575Y513274D02*
Y509095D01*
G01X836378Y513414D02*
Y513270D01*
G01X836063D02*
Y513414D01*
G01X835867Y513274D02*
Y509095D01*
G01X835827Y499410D02*
Y501731D01*
G01X835630Y514571D02*
Y512214D01*
G01Y530986D02*
Y528665D01*
G01X834843Y512214D02*
Y514571D01*
G01Y530986D02*
Y528665D01*
G01X834646Y501731D02*
Y499410D01*
G01X834607Y513274D02*
Y509095D01*
G01X834410Y513414D02*
Y513270D01*
G01X834095D02*
Y513414D01*
G01X833898Y513274D02*
Y509095D01*
G01X833859Y499410D02*
Y501731D01*
G01X833662Y514571D02*
Y512214D01*
G01Y530986D02*
Y528665D01*
G01X832874Y512214D02*
Y514571D01*
G01Y530986D02*
Y528665D01*
G01X831004Y508268D02*
Y517126D01*
G01X840842Y510554D02*
X840801Y511604D01*
G01X838873Y510554D02*
X838833Y511604D01*
G01X836905Y510554D02*
X836864Y511604D01*
G01X834936Y510554D02*
X834896Y511604D01*
G01X832968Y510554D02*
X832927Y511604D01*
G01X840748Y512555D02*
X840756Y512398D01*
G01X838780Y512555D02*
X838788Y512398D01*
G01X836811Y512555D02*
X836819Y512398D01*
G01X834843Y512555D02*
X834851Y512398D01*
G01X832874Y512555D02*
X832882Y512398D01*
G01X823032Y512555D02*
X823040Y512398D01*
G01X840842Y510554D02*
X840748Y512214D01*
G01X838873Y510554D02*
X838780Y512214D01*
G01X836905Y510554D02*
X836811Y512214D01*
G01X834936Y510554D02*
X834843Y512214D01*
G01X832968Y510554D02*
X832874Y512214D01*
G01X823125Y510554D02*
X823032Y512214D01*
G01X840801Y511604D02*
X840756Y512398D01*
G01X838833Y511604D02*
X838788Y512398D01*
G01X836864Y511604D02*
X836819Y512398D01*
G01X834896Y511604D02*
X834851Y512398D01*
G01X832927Y511604D02*
X832882Y512398D01*
G01X823085Y511604D02*
X823040Y512398D01*
G01X835537Y510554D02*
X835630Y512214D01*
G01X835622Y512398D02*
X835578Y511604D01*
G01X833568Y510554D02*
X833662Y512214D01*
G01X833654Y512398D02*
X833609Y511604D01*
G01X823726Y510554D02*
X823819Y512214D01*
G01X823811Y512398D02*
X823766Y511604D01*
G01X821757Y510554D02*
X821851Y512214D01*
G01X821843Y512398D02*
X821798Y511604D01*
G01X819789Y510554D02*
X819882Y512214D01*
G01X819874Y512398D02*
X819829Y511604D01*
G01X817820Y510554D02*
X817914Y512214D01*
G01X817906Y512398D02*
X817861Y511604D01*
G01X815852Y510554D02*
X815945Y512214D01*
G01X815937Y512398D02*
X815892Y511604D01*
G01X813883Y510554D02*
X813977Y512214D01*
G01X813969Y512398D02*
X813924Y511604D01*
G01X811915Y510554D02*
X812008Y512214D01*
G01X812000Y512398D02*
X811955Y511604D01*
G01X809946Y510554D02*
X810040Y512214D01*
G01X810032Y512398D02*
X809987Y511604D01*
G01X807978Y510554D02*
X808071Y512214D01*
G01X808063Y512398D02*
X808018Y511604D01*
G01X806009Y510554D02*
X806103Y512214D01*
G01X806095Y512398D02*
X806050Y511604D01*
G01X804041Y510554D02*
X804134Y512214D01*
G01X804126Y512398D02*
X804081Y511604D01*
G01X802072Y510554D02*
X802166Y512214D01*
G01X802158Y512398D02*
X802113Y511604D01*
G01X800104Y510554D02*
X800197Y512214D01*
G01X800189Y512398D02*
X800144Y511604D01*
G01X798135Y510554D02*
X798229Y512214D01*
G01X798221Y512398D02*
X798176Y511604D01*
G01X835622Y512398D02*
X835630Y512555D01*
G01X833654Y512398D02*
X833662Y512555D01*
G01X823811Y512398D02*
X823819Y512555D01*
G01X821843Y512398D02*
X821851Y512555D01*
G01X819874Y512398D02*
X819882Y512555D01*
G01X817906Y512398D02*
X817914Y512555D01*
G01X815937Y512398D02*
X815945Y512555D01*
G01X813969Y512398D02*
X813977Y512555D01*
G01X812000Y512398D02*
X812008Y512555D01*
G01X810032Y512398D02*
X810040Y512555D01*
G01X808063Y512398D02*
X808071Y512555D01*
G01X806095Y512398D02*
X806103Y512555D01*
G01X804126Y512398D02*
X804134Y512555D01*
G01X802158Y512398D02*
X802166Y512555D01*
G01X800189Y512398D02*
X800197Y512555D01*
G01X798221Y512398D02*
X798229Y512555D01*
G01X796252Y512398D02*
X796260Y512555D01*
G01X833568Y510554D02*
X833609Y511604D01*
G01X823726Y510554D02*
X823766Y511604D01*
G01X821757Y510554D02*
X821798Y511604D01*
G01X819789Y510554D02*
X819829Y511604D01*
G01X817820Y510554D02*
X817861Y511604D01*
G01X815852Y510554D02*
X815892Y511604D01*
G01X813883Y510554D02*
X813924Y511604D01*
G01X811915Y510554D02*
X811955Y511604D01*
G01X809946Y510554D02*
X809987Y511604D01*
G01X807978Y510554D02*
X808018Y511604D01*
G01X806009Y510554D02*
X806050Y511604D01*
G01X804041Y510554D02*
X804081Y511604D01*
G01X802072Y510554D02*
X802113Y511604D01*
G01X800104Y510554D02*
X800144Y511604D01*
G01X798135Y510554D02*
X798176Y511604D01*
G01X796167Y510554D02*
X796207Y511604D01*
G01X826674Y517126D02*
Y508268D01*
G01X824804Y501731D02*
Y499410D01*
G01X824764Y513274D02*
Y509095D01*
G01X824567Y513414D02*
Y513270D01*
G01X824252D02*
Y513414D01*
G01X824055Y513274D02*
Y509095D01*
G01X824016Y499410D02*
Y501731D01*
G01X823819Y514571D02*
Y512214D01*
G01Y530986D02*
Y528665D01*
G01X823032Y512214D02*
Y514571D01*
G01Y530986D02*
Y528665D01*
G01X822835Y501731D02*
Y499410D01*
G01X822796Y513274D02*
Y509095D01*
G01X822599Y513414D02*
Y513270D01*
G01X822284D02*
Y513414D01*
G01X822087Y513274D02*
Y509095D01*
G01X822048Y499410D02*
Y501731D01*
G01X821851Y514571D02*
Y512214D01*
G01Y530986D02*
Y528665D01*
G01X821063Y512214D02*
Y514571D01*
G01Y530986D02*
Y528665D01*
G01X820867Y501731D02*
Y499410D01*
G01X820827Y513274D02*
Y509095D01*
G01X820630Y513414D02*
Y513270D01*
G01X820315D02*
Y513414D01*
G01X820118Y513274D02*
Y509095D01*
G01X820079Y499410D02*
Y501731D01*
G01X819882Y514571D02*
Y512214D01*
G01Y530986D02*
Y528665D01*
G01X819095Y512214D02*
Y514571D01*
G01Y530986D02*
Y528665D01*
G01X818898Y501731D02*
Y499410D01*
G01X818859Y513274D02*
Y509095D01*
G01X818662Y513414D02*
Y513270D01*
G01X818347D02*
Y513414D01*
G01X818150Y513274D02*
Y509095D01*
G01X818111Y499410D02*
Y501731D01*
G01X817914Y514571D02*
Y512214D01*
G01Y530986D02*
Y528665D01*
G01X817126Y512214D02*
Y514571D01*
G01Y530986D02*
Y528665D01*
G01X816929Y501731D02*
Y499410D01*
G01X816890Y513274D02*
Y509095D01*
G01X816693Y513414D02*
Y513270D01*
G01X816378D02*
Y513414D01*
G01X816181Y513274D02*
Y509095D01*
G01X816142Y499410D02*
Y501731D01*
G01X815945Y514571D02*
Y512214D01*
G01Y530986D02*
Y528665D01*
G01X815158Y512214D02*
Y514571D01*
G01Y530986D02*
Y528665D01*
G01X814961Y501731D02*
Y499410D01*
G01X814922Y513274D02*
Y509095D01*
G01X814725Y513414D02*
Y513270D01*
G01X814410D02*
Y513414D01*
G01X814213Y513274D02*
Y509095D01*
G01X814174Y499410D02*
Y501731D01*
G01X813977Y514571D02*
Y512214D01*
G01Y530986D02*
Y528665D01*
G01X813189Y512214D02*
Y514571D01*
G01Y530986D02*
Y528665D01*
G01X812992Y501731D02*
Y499410D01*
G01X812953Y513274D02*
Y509095D01*
G01X812756Y513414D02*
Y513270D01*
G01X812441D02*
Y513414D01*
G01X812244Y513274D02*
Y509095D01*
G01X812205Y499410D02*
Y501731D01*
G01X812008Y514571D02*
Y512214D01*
G01Y530986D02*
Y528665D01*
G01X811221Y512214D02*
Y514571D01*
G01Y530986D02*
Y528665D01*
G01X811024Y501731D02*
Y499410D01*
G01X810985Y513274D02*
Y509095D01*
G01X810788Y513414D02*
Y513270D01*
G01X810473D02*
Y513414D01*
G01X810276Y513274D02*
Y509095D01*
G01X810237Y499410D02*
Y501731D01*
G01X810040Y514571D02*
Y512214D01*
G01Y530986D02*
Y528665D01*
G01X809252Y512214D02*
Y514571D01*
G01Y530986D02*
Y528665D01*
G01X809055Y501731D02*
Y499410D01*
G01X809016Y513274D02*
Y509095D01*
G01X808819Y513414D02*
Y513270D01*
G01X808504D02*
Y513414D01*
G01X808307Y513274D02*
Y509095D01*
G01X808268Y499410D02*
Y501731D01*
G01X808071Y514571D02*
Y512214D01*
G01Y530986D02*
Y528665D01*
G01X807284Y512214D02*
Y514571D01*
G01Y530986D02*
Y528665D01*
G01X807087Y501731D02*
Y499410D01*
G01X807048Y513274D02*
Y509095D01*
G01X806851Y513414D02*
Y513270D01*
G01X806536D02*
Y513414D01*
G01X806339Y513274D02*
Y509095D01*
G01X806300Y499410D02*
Y501731D01*
G01X806103Y514571D02*
Y512214D01*
G01Y530986D02*
Y528665D01*
G01X805315Y512214D02*
Y514571D01*
G01Y530986D02*
Y528665D01*
G01X805118Y501731D02*
Y499410D01*
G01X805079Y513274D02*
Y509095D01*
G01X804882Y513414D02*
Y513270D01*
G01X804567D02*
Y513414D01*
G01X804370Y513274D02*
Y509095D01*
G01X804331Y499410D02*
Y501731D01*
G01X804134Y514571D02*
Y512214D01*
G01Y530986D02*
Y528665D01*
G01X803347Y512214D02*
Y514571D01*
G01Y530986D02*
Y528665D01*
G01X803150Y501731D02*
Y499410D01*
G01X803111Y513274D02*
Y509095D01*
G01X802914Y513414D02*
Y513270D01*
G01X802599D02*
Y513414D01*
G01X802402Y513274D02*
Y509095D01*
G01X802363Y499410D02*
Y501731D01*
G01X802166Y514571D02*
Y512214D01*
G01Y530986D02*
Y528665D01*
G01X801378Y512214D02*
Y514571D01*
G01Y530986D02*
Y528665D01*
G01X801181Y501731D02*
Y499410D01*
G01X801142Y513274D02*
Y509095D01*
G01X800945Y513414D02*
Y513270D01*
G01X800630D02*
Y513414D01*
G01X800433Y513274D02*
Y509095D01*
G01X800394Y499410D02*
Y501731D01*
G01X800197Y514571D02*
Y512214D01*
G01Y530986D02*
Y528665D01*
G01X799410Y512214D02*
Y514571D01*
G01Y530986D02*
Y528665D01*
G01X799213Y501731D02*
Y499410D01*
G01X799174Y513274D02*
Y509095D01*
G01X798977Y513414D02*
Y513270D01*
G01X798662D02*
Y513414D01*
G01X798465Y513274D02*
Y509095D01*
G01X798426Y499410D02*
Y501731D01*
G01X798229Y514571D02*
Y512214D01*
G01Y530986D02*
Y528665D01*
G01X797441Y512214D02*
Y514571D01*
G01Y530986D02*
Y528665D01*
G01X797244Y501731D02*
Y499410D01*
G01X797205Y513274D02*
Y509095D01*
G01X797008Y513414D02*
Y513270D01*
G01X796693D02*
Y513414D01*
G01X796496Y513274D02*
Y509095D01*
G01X796457Y499410D02*
Y501731D01*
G01X796260Y514571D02*
Y512214D01*
G01Y530986D02*
Y528665D01*
G01X795473Y512214D02*
Y514571D01*
G01Y530986D02*
Y528665D01*
G01X795276Y501731D02*
Y499410D01*
G01X795237Y513274D02*
Y509095D01*
G01X795040Y513414D02*
Y513270D01*
G01X794725D02*
Y513414D01*
G01X794528Y513274D02*
Y509095D01*
G01X794489Y499410D02*
Y501731D01*
G01X794292Y514571D02*
Y512214D01*
G01Y530986D02*
Y528665D01*
G01X793504Y512214D02*
Y514571D01*
G01Y530986D02*
Y528665D01*
G01X793307Y501731D02*
Y499410D01*
G01X793268Y513274D02*
Y509095D01*
G01X793071Y513414D02*
Y513270D01*
G01X792756D02*
Y513414D01*
G01X792559Y513274D02*
Y509095D01*
G01X792520Y499410D02*
Y501731D01*
G01X792323Y514571D02*
Y512214D01*
G01Y530986D02*
Y528665D01*
G01X791536Y512214D02*
Y514571D01*
G01Y530986D02*
Y528665D01*
G01X791339Y501731D02*
Y499410D01*
G01X791300Y513274D02*
Y509095D01*
G01X791103Y513414D02*
Y513270D01*
G01X790788D02*
Y513414D01*
G01X790591Y513274D02*
Y509095D01*
G01X790552Y499410D02*
Y501731D01*
G01X790355Y514571D02*
Y512214D01*
G01Y530986D02*
Y528665D01*
G01X789567Y512214D02*
Y514571D01*
G01Y530986D02*
Y528665D01*
G01X789370Y501731D02*
Y499410D01*
G01X789331Y513274D02*
Y509095D01*
G01X789134Y513414D02*
Y513270D01*
G01X823125Y510554D02*
X823085Y511604D01*
G01X821157Y510554D02*
X821116Y511604D01*
G01X819188Y510554D02*
X819148Y511604D01*
G01X817220Y510554D02*
X817179Y511604D01*
G01X815251Y510554D02*
X815211Y511604D01*
G01X813283Y510554D02*
X813242Y511604D01*
G01X811314Y510554D02*
X811274Y511604D01*
G01X809346Y510554D02*
X809305Y511604D01*
G01X807377Y510554D02*
X807337Y511604D01*
G01X805409Y510554D02*
X805368Y511604D01*
G01X803440Y510554D02*
X803400Y511604D01*
G01X801472Y510554D02*
X801431Y511604D01*
G01X799503Y510554D02*
X799463Y511604D01*
G01X797535Y510554D02*
X797494Y511604D01*
G01X795566Y510554D02*
X795526Y511604D01*
G01X793598Y510554D02*
X793557Y511604D01*
G01X791629Y510554D02*
X791589Y511604D01*
G01X789661Y510554D02*
X789620Y511604D01*
G01X787692Y510554D02*
X787652Y511604D01*
G01X821063Y512555D02*
X821071Y512398D01*
G01X819095Y512555D02*
X819103Y512398D01*
G01X817126Y512555D02*
X817134Y512398D01*
G01X815158Y512555D02*
X815166Y512398D01*
G01X813189Y512555D02*
X813197Y512398D01*
G01X811221Y512555D02*
X811229Y512398D01*
G01X809252Y512555D02*
X809260Y512398D01*
G01X807284Y512555D02*
X807292Y512398D01*
G01X805315Y512555D02*
X805323Y512398D01*
G01X803347Y512555D02*
X803355Y512398D01*
G01X801378Y512555D02*
X801386Y512398D01*
G01X799410Y512555D02*
X799418Y512398D01*
G01X797441Y512555D02*
X797449Y512398D01*
G01X795473Y512555D02*
X795481Y512398D01*
G01X793504Y512555D02*
X793512Y512398D01*
G01X791536Y512555D02*
X791544Y512398D01*
G01X789567Y512555D02*
X789575Y512398D01*
G01X787599Y512555D02*
X787607Y512398D01*
G01X821157Y510554D02*
X821063Y512214D01*
G01X819188Y510554D02*
X819095Y512214D01*
G01X817220Y510554D02*
X817126Y512214D01*
G01X815251Y510554D02*
X815158Y512214D01*
G01X813283Y510554D02*
X813189Y512214D01*
G01X811314Y510554D02*
X811221Y512214D01*
G01X809346Y510554D02*
X809252Y512214D01*
G01X807377Y510554D02*
X807284Y512214D01*
G01X805409Y510554D02*
X805315Y512214D01*
G01X803440Y510554D02*
X803347Y512214D01*
G01X801472Y510554D02*
X801378Y512214D01*
G01X799503Y510554D02*
X799410Y512214D01*
G01X797535Y510554D02*
X797441Y512214D01*
G01X795566Y510554D02*
X795473Y512214D01*
G01X793598Y510554D02*
X793504Y512214D01*
G01X791629Y510554D02*
X791536Y512214D01*
G01X789661Y510554D02*
X789567Y512214D01*
G01X787692Y510554D02*
X787599Y512214D01*
G01X821116Y511604D02*
X821071Y512398D01*
G01X819148Y511604D02*
X819103Y512398D01*
G01X817179Y511604D02*
X817134Y512398D01*
G01X815211Y511604D02*
X815166Y512398D01*
G01X813242Y511604D02*
X813197Y512398D01*
G01X811274Y511604D02*
X811229Y512398D01*
G01X809305Y511604D02*
X809260Y512398D01*
G01X807337Y511604D02*
X807292Y512398D01*
G01X805368Y511604D02*
X805323Y512398D01*
G01X803400Y511604D02*
X803355Y512398D01*
G01X801431Y511604D02*
X801386Y512398D01*
G01X799463Y511604D02*
X799418Y512398D01*
G01X797494Y511604D02*
X797449Y512398D01*
G01X795526Y511604D02*
X795481Y512398D01*
G01X793557Y511604D02*
X793512Y512398D01*
G01X791589Y511604D02*
X791544Y512398D01*
G01X789620Y511604D02*
X789575Y512398D01*
G01X787652Y511604D02*
X787607Y512398D01*
G01X796167Y510554D02*
X796260Y512214D01*
G01X796252Y512398D02*
X796207Y511604D01*
G01X794198Y510554D02*
X794292Y512214D01*
G01X794284Y512398D02*
X794239Y511604D01*
G01X792230Y510554D02*
X792323Y512214D01*
G01X792315Y512398D02*
X792270Y511604D01*
G01X790261Y510554D02*
X790355Y512214D01*
G01X790347Y512398D02*
X790302Y511604D01*
G01X788293Y510554D02*
X788386Y512214D01*
G01X788378Y512398D02*
X788333Y511604D01*
G01X794284Y512398D02*
X794292Y512555D01*
G01X792315Y512398D02*
X792323Y512555D01*
G01X790347Y512398D02*
X790355Y512555D01*
G01X788378Y512398D02*
X788386Y512555D01*
G01X794198Y510554D02*
X794239Y511604D01*
G01X792230Y510554D02*
X792270Y511604D01*
G01X790261Y510554D02*
X790302Y511604D01*
G01X788293Y510554D02*
X788333Y511604D01*
G01X788819Y513270D02*
Y513414D01*
G01X788622Y513274D02*
Y509095D01*
G01X788583Y499410D02*
Y501731D01*
G01X788386Y514571D02*
Y512214D01*
G01Y530986D02*
Y528665D01*
G01X787599Y512214D02*
Y514571D01*
G01Y530986D02*
Y528665D01*
G01X787402Y501731D02*
Y499410D01*
G01X787363Y513274D02*
Y509095D01*
G01X787166Y513414D02*
Y513270D01*
G01X787087Y523898D02*
Y515040D01*
G01X786851Y513270D02*
Y513414D01*
G01X786654Y513274D02*
Y509095D01*
G01X786615Y499410D02*
Y501731D01*
G01X843111Y532678D02*
X847244D01*
G01X790158Y531183D02*
X789764D01*
G01X788189D02*
X787796D01*
G01X794095D02*
X793701D01*
G01X792126D02*
X791733D01*
G01X796063D02*
X795670D01*
G01X800000D02*
X799607D01*
G01X798032D02*
X797638D01*
G01X803937D02*
X803544D01*
G01X801969D02*
X801575D01*
G01X805906D02*
X805512D01*
G01X809843D02*
X809449D01*
G01X807874D02*
X807481D01*
G01X813780D02*
X813386D01*
G01X811811D02*
X811418D01*
G01X815748D02*
X815355D01*
G01X819685D02*
X819292D01*
G01X817717D02*
X817323D01*
G01X823622D02*
X823229D01*
G01X821654D02*
X821260D01*
G01X833465D02*
X833071D01*
G01X835433D02*
X835040D01*
G01X839370D02*
X838977D01*
G01X837402D02*
X837008D01*
G01X841339D02*
X840945D01*
G01X790355Y529214D02*
X789567D01*
G01X788386D02*
X787599D01*
G01X794292D02*
X793504D01*
G01X792323D02*
X791536D01*
G01X796260D02*
X795473D01*
G01X800197D02*
X799410D01*
G01X798229D02*
X797441D01*
G01X804134D02*
X803347D01*
G01X802166D02*
X801378D01*
G01X806103D02*
X805315D01*
G01X810040D02*
X809252D01*
G01X808071D02*
X807284D01*
G01X813977D02*
X813189D01*
G01X812008D02*
X811221D01*
G01X815945D02*
X815158D01*
G01X819882D02*
X819095D01*
G01X817914D02*
X817126D01*
G01X823819D02*
X823032D01*
G01X821851D02*
X821063D01*
G01X833662D02*
X832874D01*
G01X837599D02*
X836811D01*
G01X835630D02*
X834843D01*
G01X839567D02*
X838780D01*
G01X841536D02*
X840748D01*
G01Y528665D02*
X841536D01*
G01X838780D02*
X839567D01*
G01X836811D02*
X837599D01*
G01X834843D02*
X835630D01*
G01X832874D02*
X833662D01*
G01X823032D02*
X823819D01*
G01X821063D02*
X821851D01*
G01X819095D02*
X819882D01*
G01X817126D02*
X817914D01*
G01X815158D02*
X815945D01*
G01X813189D02*
X813977D01*
G01X811221D02*
X812008D01*
G01X809252D02*
X810040D01*
G01X807284D02*
X808071D01*
G01X805315D02*
X806103D01*
G01X803347D02*
X804134D01*
G01X801378D02*
X802166D01*
G01X799410D02*
X800197D01*
G01X797441D02*
X798229D01*
G01X795473D02*
X796260D01*
G01X793504D02*
X794292D01*
G01X791536D02*
X792323D01*
G01X789567D02*
X790355D01*
G01X787599D02*
X788386D01*
G01X840158Y526575D02*
X838189D01*
G01X845473D02*
X844882D01*
G01X848032D02*
X846654D01*
G01X845867Y523229D02*
X843989D01*
G01X838189Y522638D02*
X840158D01*
G01X844390Y517126D02*
X831004D01*
G01X788386Y514571D02*
X787599D01*
G01X790355D02*
X789567D01*
G01X792323D02*
X791536D01*
G01X794292D02*
X793504D01*
G01X796260D02*
X795473D01*
G01X798229D02*
X797441D01*
G01X800197D02*
X799410D01*
G01X802166D02*
X801378D01*
G01X804134D02*
X803347D01*
G01X806103D02*
X805315D01*
G01X808071D02*
X807284D01*
G01X810040D02*
X809252D01*
G01X812008D02*
X811221D01*
G01X813977D02*
X813189D01*
G01X815945D02*
X815158D01*
G01X817914D02*
X817126D01*
G01X819882D02*
X819095D01*
G01X823819D02*
X823032D01*
G01X821851D02*
X821063D01*
G01X833662D02*
X832874D01*
G01X835630D02*
X834843D01*
G01X837599D02*
X836811D01*
G01X839567D02*
X838780D01*
G01X841536D02*
X840748D01*
G01X788386Y513888D02*
X787599D01*
G01X790355D02*
X789567D01*
G01X792323D02*
X791536D01*
G01X794292D02*
X793504D01*
G01X796260D02*
X795473D01*
G01X798229D02*
X797441D01*
G01X800197D02*
X799410D01*
G01X802166D02*
X801378D01*
G01X804134D02*
X803347D01*
G01X806103D02*
X805315D01*
G01X808071D02*
X807284D01*
G01X810040D02*
X809252D01*
G01X812008D02*
X811221D01*
G01X813977D02*
X813189D01*
G01X815945D02*
X815158D01*
G01X817914D02*
X817126D01*
G01X819882D02*
X819095D01*
G01X823819D02*
X823032D01*
G01X821851D02*
X821063D01*
G01X833662D02*
X832874D01*
G01X835630D02*
X834843D01*
G01X837599D02*
X836811D01*
G01X839567D02*
X838780D01*
G01X841536D02*
X840748D01*
G01X788386Y513826D02*
X787599D01*
G01X790355D02*
X789567D01*
G01X792323D02*
X791536D01*
G01X794292D02*
X793504D01*
G01X796260D02*
X795473D01*
G01X798229D02*
X797441D01*
G01X800197D02*
X799410D01*
G01X802166D02*
X801378D01*
G01X804134D02*
X803347D01*
G01X806103D02*
X805315D01*
G01X808071D02*
X807284D01*
G01X810040D02*
X809252D01*
G01X812008D02*
X811221D01*
G01X813977D02*
X813189D01*
G01X815945D02*
X815158D01*
G01X817914D02*
X817126D01*
G01X819882D02*
X819095D01*
G01X823819D02*
X823032D01*
G01X821851D02*
X821063D01*
G01X833662D02*
X832874D01*
G01X835630D02*
X834843D01*
G01X837599D02*
X836811D01*
G01X839567D02*
X838780D01*
G01X841536D02*
X840748D01*
G01Y513499D02*
X841536D01*
G01X838780D02*
X839567D01*
G01X834843D02*
X835630D01*
G01X836811D02*
X837599D01*
G01X832874D02*
X833662D01*
G01X823032D02*
X823819D01*
G01X821063D02*
X821851D01*
G01X817126D02*
X817914D01*
G01X819095D02*
X819882D01*
G01X815158D02*
X815945D01*
G01X811221D02*
X812008D01*
G01X813189D02*
X813977D01*
G01X807284D02*
X808071D01*
G01X809252D02*
X810040D01*
G01X805315D02*
X806103D01*
G01X801378D02*
X802166D01*
G01X803347D02*
X804134D01*
G01X797441D02*
X798229D01*
G01X799410D02*
X800197D01*
G01X795473D02*
X796260D01*
G01X791536D02*
X792323D01*
G01X793504D02*
X794292D01*
G01X787599D02*
X788386D01*
G01X789567D02*
X790355D01*
G01X838032Y513414D02*
X838347D01*
G01X840000D02*
X840315D01*
G01X834095D02*
X834410D01*
G01X836063D02*
X836378D01*
G01X824252D02*
X824567D01*
G01X820315D02*
X820630D01*
G01X822284D02*
X822599D01*
G01X818347D02*
X818662D01*
G01X814410D02*
X814725D01*
G01X816378D02*
X816693D01*
G01X810473D02*
X810788D01*
G01X812441D02*
X812756D01*
G01X808504D02*
X808819D01*
G01X804567D02*
X804882D01*
G01X806536D02*
X806851D01*
G01X800630D02*
X800945D01*
G01X802599D02*
X802914D01*
G01X798662D02*
X798977D01*
G01X794725D02*
X795040D01*
G01X796693D02*
X797008D01*
G01X790788D02*
X791103D01*
G01X792756D02*
X793071D01*
G01X788819D02*
X789134D01*
G01X786851D02*
X787166D01*
G01X838032Y513270D02*
X838347D01*
G01X840000D02*
X840315D01*
G01X834095D02*
X834410D01*
G01X836063D02*
X836378D01*
G01X824252D02*
X824567D01*
G01X820315D02*
X820630D01*
G01X822284D02*
X822599D01*
G01X818347D02*
X818662D01*
G01X814410D02*
X814725D01*
G01X816378D02*
X816693D01*
G01X810473D02*
X810788D01*
G01X812441D02*
X812756D01*
G01X808504D02*
X808819D01*
G01X804567D02*
X804882D01*
G01X806536D02*
X806851D01*
G01X800630D02*
X800945D01*
G01X802599D02*
X802914D01*
G01X798662D02*
X798977D01*
G01X794725D02*
X795040D01*
G01X796693D02*
X797008D01*
G01X790788D02*
X791103D01*
G01X792756D02*
X793071D01*
G01X788819D02*
X789134D01*
G01X786851D02*
X787166D01*
G01X787363Y512890D02*
X786654D01*
G01X789331D02*
X788622D01*
G01X791300D02*
X790591D01*
G01X793268D02*
X792559D01*
G01X795237D02*
X794528D01*
G01X797205D02*
X796496D01*
G01X799174D02*
X798465D01*
G01X801142D02*
X800433D01*
G01X803111D02*
X802402D01*
G01X805079D02*
X804370D01*
G01X807048D02*
X806339D01*
G01X809016D02*
X808307D01*
G01X810985D02*
X810276D01*
G01X812953D02*
X812244D01*
G01X814922D02*
X814213D01*
G01X816890D02*
X816181D01*
G01X818859D02*
X818150D01*
G01X820827D02*
X820118D01*
G01X822796D02*
X822087D01*
G01X824764D02*
X824055D01*
G01X834607D02*
X833898D01*
G01X836575D02*
X835867D01*
G01X838544D02*
X837835D01*
G01X840512D02*
X839804D01*
G01X837835Y512854D02*
X838544D01*
G01X839804D02*
X840512D01*
G01X833898D02*
X834607D01*
G01X835867D02*
X836575D01*
G01X824055D02*
X824764D01*
G01X822087D02*
X822796D01*
G01X818150D02*
X818859D01*
G01X820118D02*
X820827D01*
G01X814213D02*
X814922D01*
G01X816181D02*
X816890D01*
G01X812244D02*
X812953D01*
G01X808307D02*
X809016D01*
G01X810276D02*
X810985D01*
G01X804370D02*
X805079D01*
G01X806339D02*
X807048D01*
G01X800433D02*
X801142D01*
G01X802402D02*
X803111D01*
G01X798465D02*
X799174D01*
G01X794528D02*
X795237D01*
G01X796496D02*
X797205D01*
G01X790591D02*
X791300D01*
G01X792559D02*
X793268D01*
G01X788622D02*
X789331D01*
G01X786654D02*
X787363D01*
G01X831004Y512796D02*
X844390D01*
G01X787363Y512522D02*
X786654D01*
G01X789331D02*
X788622D01*
G01X791300D02*
X790591D01*
G01X793268D02*
X792559D01*
G01X795237D02*
X794528D01*
G01X797205D02*
X796496D01*
G01X799174D02*
X798465D01*
G01X801142D02*
X800433D01*
G01X803111D02*
X802402D01*
G01X805079D02*
X804370D01*
G01X807048D02*
X806339D01*
G01X809016D02*
X808307D01*
G01X810985D02*
X810276D01*
G01X812953D02*
X812244D01*
G01X814922D02*
X814213D01*
G01X816890D02*
X816181D01*
G01X818859D02*
X818150D01*
G01X820827D02*
X820118D01*
G01X822796D02*
X822087D01*
G01X824764D02*
X824055D01*
G01X834607D02*
X833898D01*
G01X836575D02*
X835867D01*
G01X838544D02*
X837835D01*
G01X840512D02*
X839804D01*
G01X788378Y512398D02*
X787607D01*
G01X790347D02*
X789575D01*
G01X792315D02*
X791544D01*
G01X794284D02*
X793512D01*
G01X796252D02*
X795481D01*
G01X798221D02*
X797449D01*
G01X800189D02*
X799418D01*
G01X802158D02*
X801386D01*
G01X804126D02*
X803355D01*
G01X806095D02*
X805323D01*
G01X808063D02*
X807292D01*
G01X810032D02*
X809260D01*
G01X812000D02*
X811229D01*
G01X813969D02*
X813197D01*
G01X815937D02*
X815166D01*
G01X817906D02*
X817134D01*
G01X819874D02*
X819103D01*
G01X823811D02*
X823040D01*
G01X821843D02*
X821071D01*
G01X833654D02*
X832882D01*
G01X835622D02*
X834851D01*
G01X837591D02*
X836819D01*
G01X839559D02*
X838788D01*
G01X841528D02*
X840756D01*
G01Y512064D02*
X841528D01*
G01X838788D02*
X839559D01*
G01X834851D02*
X835622D01*
G01X836819D02*
X837591D01*
G01X832882D02*
X833654D01*
G01X823040D02*
X823811D01*
G01X821071D02*
X821843D01*
G01X817134D02*
X817906D01*
G01X819103D02*
X819874D01*
G01X815166D02*
X815937D01*
G01X811229D02*
X812000D01*
G01X813197D02*
X813969D01*
G01X807292D02*
X808063D01*
G01X809260D02*
X810032D01*
G01X805323D02*
X806095D01*
G01X801386D02*
X802158D01*
G01X803355D02*
X804126D01*
G01X797449D02*
X798221D01*
G01X799418D02*
X800189D01*
G01X795481D02*
X796252D01*
G01X791544D02*
X792315D01*
G01X793512D02*
X794284D01*
G01X787607D02*
X788378D01*
G01X789575D02*
X790347D01*
G01X837835Y511674D02*
X838544D01*
G01X839804D02*
X840512D01*
G01X833898D02*
X834607D01*
G01X835867D02*
X836575D01*
G01X824055D02*
X824764D01*
G01X822087D02*
X822796D01*
G01X818150D02*
X818859D01*
G01X820118D02*
X820827D01*
G01X814213D02*
X814922D01*
G01X816181D02*
X816890D01*
G01X812244D02*
X812953D01*
G01X808307D02*
X809016D01*
G01X810276D02*
X810985D01*
G01X804370D02*
X805079D01*
G01X806339D02*
X807048D01*
G01X800433D02*
X801142D01*
G01X802402D02*
X803111D01*
G01X798465D02*
X799174D01*
G01X794528D02*
X795237D01*
G01X796496D02*
X797205D01*
G01X790591D02*
X791300D01*
G01X792559D02*
X793268D01*
G01X788622D02*
X789331D01*
G01X786654D02*
X787363D01*
G01X788333Y511604D02*
X787652D01*
G01X790302D02*
X789620D01*
G01X792270D02*
X791589D01*
G01X794239D02*
X793557D01*
G01X796207D02*
X795526D01*
G01X798176D02*
X797494D01*
G01X800144D02*
X799463D01*
G01X802113D02*
X801431D01*
G01X804081D02*
X803400D01*
G01X806050D02*
X805368D01*
G01X808018D02*
X807337D01*
G01X809987D02*
X809305D01*
G01X811955D02*
X811274D01*
G01X813924D02*
X813242D01*
G01X815892D02*
X815211D01*
G01X817861D02*
X817179D01*
G01X819829D02*
X819148D01*
G01X823766D02*
X823085D01*
G01X821798D02*
X821116D01*
G01X833609D02*
X832927D01*
G01X835578D02*
X834896D01*
G01X837546D02*
X836864D01*
G01X839515D02*
X838833D01*
G01X841483D02*
X840801D01*
G01X787363Y511497D02*
X786654D01*
G01X789331D02*
X788622D01*
G01X791300D02*
X790591D01*
G01X793268D02*
X792559D01*
G01X795237D02*
X794528D01*
G01X797205D02*
X796496D01*
G01X799174D02*
X798465D01*
G01X801142D02*
X800433D01*
G01X803111D02*
X802402D01*
G01X805079D02*
X804370D01*
G01X807048D02*
X806339D01*
G01X809016D02*
X808307D01*
G01X810985D02*
X810276D01*
G01X812953D02*
X812244D01*
G01X814922D02*
X814213D01*
G01X816890D02*
X816181D01*
G01X818859D02*
X818150D01*
G01X820827D02*
X820118D01*
G01X822796D02*
X822087D01*
G01X824764D02*
X824055D01*
G01X834607D02*
X833898D01*
G01X836575D02*
X835867D01*
G01X838544D02*
X837835D01*
G01X840512D02*
X839804D01*
G01X788293Y510554D02*
X787692D01*
G01X790261D02*
X789661D01*
G01X792230D02*
X791629D01*
G01X794198D02*
X793598D01*
G01X796167D02*
X795566D01*
G01X798135D02*
X797535D01*
G01X800104D02*
X799503D01*
G01X802072D02*
X801472D01*
G01X804041D02*
X803440D01*
G01X806009D02*
X805409D01*
G01X807978D02*
X807377D01*
G01X809946D02*
X809346D01*
G01X811915D02*
X811314D01*
G01X813883D02*
X813283D01*
G01X815852D02*
X815251D01*
G01X817820D02*
X817220D01*
G01X819789D02*
X819188D01*
G01X823726D02*
X823125D01*
G01X821757D02*
X821157D01*
G01X833568D02*
X832968D01*
G01X835537D02*
X834936D01*
G01X837505D02*
X836905D01*
G01X839474D02*
X838873D01*
G01X841443D02*
X840842D01*
G01X787363Y510355D02*
X786654D01*
G01X789331D02*
X788622D01*
G01X791300D02*
X790591D01*
G01X793268D02*
X792559D01*
G01X795237D02*
X794528D01*
G01X797205D02*
X796496D01*
G01X799174D02*
X798465D01*
G01X801142D02*
X800433D01*
G01X803111D02*
X802402D01*
G01X805079D02*
X804370D01*
G01X807048D02*
X806339D01*
G01X809016D02*
X808307D01*
G01X810985D02*
X810276D01*
G01X812953D02*
X812244D01*
G01X814922D02*
X814213D01*
G01X816890D02*
X816181D01*
G01X818859D02*
X818150D01*
G01X820827D02*
X820118D01*
G01X822796D02*
X822087D01*
G01X824764D02*
X824055D01*
G01X834607D02*
X833898D01*
G01X836575D02*
X835867D01*
G01X838544D02*
X837835D01*
G01X840512D02*
X839804D01*
G01X848032Y510237D02*
X846851D01*
G01X787363Y509095D02*
X786654D01*
G01X789331D02*
X788622D01*
G01X791300D02*
X790591D01*
G01X793268D02*
X792559D01*
G01X795237D02*
X794528D01*
G01X797205D02*
X796496D01*
G01X799174D02*
X798465D01*
G01X801142D02*
X800433D01*
G01X803111D02*
X802402D01*
G01X805079D02*
X804370D01*
G01X807048D02*
X806339D01*
G01X809016D02*
X808307D01*
G01X810985D02*
X810276D01*
G01X812953D02*
X812244D01*
G01X814922D02*
X814213D01*
G01X816890D02*
X816181D01*
G01X818859D02*
X818150D01*
G01X820827D02*
X820118D01*
G01X822796D02*
X822087D01*
G01X824764D02*
X824055D01*
G01X834607D02*
X833898D01*
G01X836575D02*
X835867D01*
G01X838544D02*
X837835D01*
G01X840512D02*
X839804D01*
G01X848032Y506103D02*
X845571D01*
G01X787402Y501731D02*
X786615D01*
G01X789370D02*
X788583D01*
G01X793307D02*
X792520D01*
G01X791339D02*
X790552D01*
G01X797244D02*
X796457D01*
G01X795276D02*
X794489D01*
G01X801181D02*
X800394D01*
G01X799213D02*
X798426D01*
G01X803150D02*
X802363D01*
G01X807087D02*
X806300D01*
G01X805118D02*
X804331D01*
G01X811024D02*
X810237D01*
G01X809055D02*
X808268D01*
G01X812992D02*
X812205D01*
G01X816929D02*
X816142D01*
G01X814961D02*
X814174D01*
G01X820867D02*
X820079D01*
G01X818898D02*
X818111D01*
G01X822835D02*
X822048D01*
G01X824804D02*
X824016D01*
G01X836615D02*
X835827D01*
G01X834646D02*
X833859D01*
G01X840552D02*
X839764D01*
G01X838583D02*
X837796D01*
G01X839764Y501182D02*
X840552D01*
G01X837796D02*
X838583D01*
G01X835827D02*
X836615D01*
G01X833859D02*
X834646D01*
G01X824016D02*
X824804D01*
G01X822048D02*
X822835D01*
G01X820079D02*
X820867D01*
G01X818111D02*
X818898D01*
G01X816142D02*
X816929D01*
G01X814174D02*
X814961D01*
G01X812205D02*
X812992D01*
G01X810237D02*
X811024D01*
G01X808268D02*
X809055D01*
G01X806300D02*
X807087D01*
G01X804331D02*
X805118D01*
G01X802363D02*
X803150D01*
G01X800394D02*
X801181D01*
G01X798426D02*
X799213D01*
G01X796457D02*
X797244D01*
G01X794489D02*
X795276D01*
G01X792520D02*
X793307D01*
G01X790552D02*
X791339D01*
G01X788583D02*
X789370D01*
G01X786615D02*
X787402D01*
G01X787205Y499213D02*
X786811D01*
G01X789174D02*
X788780D01*
G01X793111D02*
X792717D01*
G01X791142D02*
X790748D01*
G01X797048D02*
X796654D01*
G01X795079D02*
X794685D01*
G01X799016D02*
X798622D01*
G01X802953D02*
X802559D01*
G01X800985D02*
X800591D01*
G01X806890D02*
X806496D01*
G01X804922D02*
X804528D01*
G01X808859D02*
X808465D01*
G01X812796D02*
X812402D01*
G01X810827D02*
X810433D01*
G01X816733D02*
X816339D01*
G01X814764D02*
X814370D01*
G01X820670D02*
X820276D01*
G01X818701D02*
X818307D01*
G01X822638D02*
X822244D01*
G01X824607D02*
X824213D01*
G01X836418D02*
X836024D01*
G01X834449D02*
X834055D01*
G01X840355D02*
X839961D01*
G01X838386D02*
X837992D01*
G01X842520Y629922D02*
G03X846457Y633859I0J3937D01*
G01D02*
Y759843D01*
G01X838583Y637796D02*
Y709449D01*
G01X812123Y734367D02*
G03I-4292J0D01*
G01X838583Y759843D02*
G03X834646Y763780I-3937J0D01*
G01X838583Y740158D02*
Y759843D01*
G01Y740158D02*
G03X846457I3937J0D01*
G01Y709449D02*
G03X838583I-3937J0D01*
G01X850394Y763780D02*
G03X846457Y759843I0J-3937D01*
G01X903079Y763780D02*
X850394D01*
G01X853013Y1444354D02*
X1183721D01*
G01X916004Y-524387D02*
Y-614517D01*
G01X921260Y0D02*
G03X925197Y3937I0J3937D01*
G01X883859Y31496D02*
G03I-7874J0D01*
G01X925197Y3937D02*
Y723480D01*
G01X882874Y472441D02*
G03I-6889J0D01*
G01Y606300D02*
G03I-6889J0D01*
G01X925197Y723727D02*
Y807769D01*
G01X906600Y761604D02*
G03X903079Y763780I-3521J-1761D01*
G01X925197Y723480D02*
G03X924781Y725241I-3937J0D01*
G01X882874Y740158D02*
G03I-6889J0D01*
G01X906600Y761604D02*
X924782Y725241D01*
G01X958371Y-714465D02*
Y-733402D01*
G01Y1463291D02*
Y1444354D01*
G01X1144351Y-675095D02*
Y-419310D01*
G01X1202658Y1463291D02*
Y-733402D01*
G01X1183721Y1444354D02*
Y-714465D01*
G01X1183722Y-569780D02*
Y-714465D01*
G01X1183721Y-498583D02*
X1202658D01*
G01X1183721Y-282701D02*
X1202658D01*
G01X1183721Y-66819D02*
X1202658D01*
G01X1183721Y149063D02*
X1202658D01*
G01X1183721Y364945D02*
X1202658D01*
G01X1183721Y580826D02*
X1202658D01*
G01X1183721Y796708D02*
X1202658D01*
G01X1183721Y1012590D02*
X1202658D01*
G01X1183532Y1228472D02*
X1202469D01*
G01X1183721Y1444354D02*
Y1349866D01*
M02*
